(lib_symbols
	(symbol "CSD86330Q3D_1"
			(pin_names
				(hide yes)
			)
			(exclude_from_sim no)
			(in_bom yes)
			(on_board yes)
			(property "Reference" "U"
				(at 30.48 -5.08 0)
				(effects
					(font
						(size 1.27 1.27)
						(thickness 0.15)
					)
					(justify left bottom)
				)
			)
			(property "Value" "CSD86330Q3D_1"
				(at 30.48 -10.16 0)
				(effects
					(font
						(size 1.27 1.27)
						(thickness 0.15)
					)
					(justify left bottom)
					(hide yes)
				)
			)
			(property "Footprint" "antmicro-footprints:CSD86330Q3D"
				(at 30.48 -12.7 0)
				(effects
					(font
						(size 1.27 1.27)
						(thickness 0.15)
					)
					(justify left bottom)
					(hide yes)
				)
			)
			(property "Datasheet" "https://www.ti.com/lit/ds/symlink/csd86330q3d.pdf?ts=1619602857581&ref_url=https%253A%252F%252Fwww.ti.com%252Fproduct%252FCSD86330Q3D"
				(at 30.48 -15.24 0)
				(effects
					(font
						(size 1.27 1.27)
						(thickness 0.15)
					)
					(justify left bottom)
					(hide yes)
				)
			)
			(property "Description" "Dual MOSFET, N Channel, 25 V, 25 V, 20 A, 20 A, 4.6 ohm"
				(at 0 0 0)
				(effects
					(font
						(size 1.27 1.27)
					)
					(hide yes)
				)
			)
			(property "Manufacturer" "Texas Instruments"
				(at 30.48 -17.78 0)
				(effects
					(font
						(size 1.27 1.27)
						(thickness 0.15)
					)
					(justify left bottom)
					(hide yes)
				)
			)
			(property "MPN" "CSD86330Q3D"
				(at 30.48 -7.62 0)
				(effects
					(font
						(size 1.27 1.27)
						(thickness 0.15)
					)
					(justify left bottom)
				)
			)
			(property "Author" "Antmicro"
				(at 30.48 -20.32 0)
				(effects
					(font
						(size 1.27 1.27)
						(thickness 0.15)
					)
					(justify left bottom)
					(hide yes)
				)
			)
			(property "License" "Apache-2.0"
				(at 30.48 -22.86 0)
				(effects
					(font
						(size 1.27 1.27)
						(thickness 0.15)
					)
					(justify left bottom)
					(hide yes)
				)
			)
			(property "ki_keywords" "SMT, TRANSISTOR, IC, MOSFET, ARRAY"
				(at 0 0 0)
				(effects
					(font
						(size 1.27 1.27)
					)
					(hide yes)
				)
			)
			(property "ki_fp_filters" "DQZ8_1P8X2P7"
				(at 0 0 0)
				(effects
					(font
						(size 1.27 1.27)
					)
					(hide yes)
				)
			)
			(symbol "CSD86330Q3D_1_1_1"
				(rectangle
					(start 2.54 5.08)
					(end 12.7 -15.24)
					(stroke
						(width 0.254)
						(type default)
					)
					(fill
						(type background)
					)
				)
				(polyline
					(pts
						(xy 2.54 0) (xy 4.572 0)
					)
					(stroke
						(width 0.254)
						(type default)
					)
					(fill
						(type background)
					)
				)
				(polyline
					(pts
						(xy 2.54 -5.08) (xy 7.62 -5.08)
					)
					(stroke
						(width 0.254)
						(type default)
					)
					(fill
						(type background)
					)
				)
				(polyline
					(pts
						(xy 2.54 -10.16) (xy 4.572 -10.16)
					)
					(stroke
						(width 0.254)
						(type default)
					)
					(fill
						(type background)
					)
				)
				(polyline
					(pts
						(xy 4.572 2.286) (xy 4.572 -2.286)
					)
					(stroke
						(width 0.254)
						(type default)
					)
					(fill
						(type background)
					)
				)
				(polyline
					(pts
						(xy 4.572 -7.874) (xy 4.572 -12.446)
					)
					(stroke
						(width 0.254)
						(type default)
					)
					(fill
						(type background)
					)
				)
				(polyline
					(pts
						(xy 5.08 2.286) (xy 5.08 1.27)
					)
					(stroke
						(width 0.254)
						(type default)
					)
					(fill
						(type background)
					)
				)
				(polyline
					(pts
						(xy 5.08 0) (xy 6.604 -0.508)
					)
					(stroke
						(width 0.254)
						(type default)
					)
					(fill
						(type background)
					)
				)
				(polyline
					(pts
						(xy 5.08 -0.508) (xy 5.08 0.508)
					)
					(stroke
						(width 0.254)
						(type default)
					)
					(fill
						(type background)
					)
				)
				(polyline
					(pts
						(xy 5.08 -2.286) (xy 5.08 -1.27)
					)
					(stroke
						(width 0.254)
						(type default)
					)
					(fill
						(type background)
					)
				)
				(polyline
					(pts
						(xy 5.08 -7.874) (xy 5.08 -8.89)
					)
					(stroke
						(width 0.254)
						(type default)
					)
					(fill
						(type background)
					)
				)
				(polyline
					(pts
						(xy 5.08 -10.16) (xy 6.604 -10.668)
					)
					(stroke
						(width 0.254)
						(type default)
					)
					(fill
						(type background)
					)
				)
				(polyline
					(pts
						(xy 5.08 -10.668) (xy 5.08 -9.652)
					)
					(stroke
						(width 0.254)
						(type default)
					)
					(fill
						(type background)
					)
				)
				(polyline
					(pts
						(xy 5.08 -12.446) (xy 5.08 -11.43)
					)
					(stroke
						(width 0.254)
						(type default)
					)
					(fill
						(type background)
					)
				)
				(polyline
					(pts
						(xy 6.604 0.508) (xy 5.08 0)
					)
					(stroke
						(width 0.254)
						(type default)
					)
					(fill
						(type background)
					)
				)
				(polyline
					(pts
						(xy 6.604 -0.508) (xy 6.604 0.508)
					)
					(stroke
						(width 0.254)
						(type default)
					)
					(fill
						(type background)
					)
				)
				(polyline
					(pts
						(xy 6.604 -9.652) (xy 5.08 -10.16)
					)
					(stroke
						(width 0.254)
						(type default)
					)
					(fill
						(type background)
					)
				)
				(polyline
					(pts
						(xy 6.604 -10.668) (xy 6.604 -9.652)
					)
					(stroke
						(width 0.254)
						(type default)
					)
					(fill
						(type background)
					)
				)
				(polyline
					(pts
						(xy 7.62 5.08) (xy 7.62 2.54)
					)
					(stroke
						(width 0.254)
						(type default)
					)
					(fill
						(type background)
					)
				)
				(polyline
					(pts
						(xy 7.62 2.54) (xy 10.16 2.54)
					)
					(stroke
						(width 0.254)
						(type default)
					)
					(fill
						(type background)
					)
				)
				(polyline
					(pts
						(xy 7.62 1.778) (xy 5.08 1.778)
					)
					(stroke
						(width 0.254)
						(type default)
					)
					(fill
						(type background)
					)
				)
				(polyline
					(pts
						(xy 7.62 1.778) (xy 7.62 2.54)
					)
					(stroke
						(width 0.254)
						(type default)
					)
					(fill
						(type background)
					)
				)
				(polyline
					(pts
						(xy 7.62 0) (xy 5.08 0)
					)
					(stroke
						(width 0.254)
						(type default)
					)
					(fill
						(type background)
					)
				)
				(polyline
					(pts
						(xy 7.62 0) (xy 7.62 -2.54)
					)
					(stroke
						(width 0.254)
						(type default)
					)
					(fill
						(type background)
					)
				)
				(polyline
					(pts
						(xy 7.62 -1.778) (xy 5.08 -1.778)
					)
					(stroke
						(width 0.254)
						(type default)
					)
					(fill
						(type background)
					)
				)
				(polyline
					(pts
						(xy 7.62 -2.54) (xy 10.16 -2.54)
					)
					(stroke
						(width 0.254)
						(type default)
					)
					(fill
						(type background)
					)
				)
				(polyline
					(pts
						(xy 7.62 -5.08) (xy 7.62 -5.08)
					)
					(stroke
						(width 0.254)
						(type default)
					)
					(fill
						(type background)
					)
				)
				(circle
					(center 7.62 -5.08)
					(radius 0.254)
					(stroke
						(width 0.254)
						(type default)
					)
					(fill
						(type background)
					)
				)
				(polyline
					(pts
						(xy 7.62 -7.62) (xy 7.62 -2.54)
					)
					(stroke
						(width 0.254)
						(type default)
					)
					(fill
						(type background)
					)
				)
				(polyline
					(pts
						(xy 7.62 -7.62) (xy 10.16 -7.62)
					)
					(stroke
						(width 0.254)
						(type default)
					)
					(fill
						(type background)
					)
				)
				(polyline
					(pts
						(xy 7.62 -8.382) (xy 5.08 -8.382)
					)
					(stroke
						(width 0.254)
						(type default)
					)
					(fill
						(type background)
					)
				)
				(polyline
					(pts
						(xy 7.62 -8.382) (xy 7.62 -7.62)
					)
					(stroke
						(width 0.254)
						(type default)
					)
					(fill
						(type background)
					)
				)
				(polyline
					(pts
						(xy 7.62 -10.16) (xy 5.08 -10.16)
					)
					(stroke
						(width 0.254)
						(type default)
					)
					(fill
						(type background)
					)
				)
				(polyline
					(pts
						(xy 7.62 -10.16) (xy 7.62 -12.7)
					)
					(stroke
						(width 0.254)
						(type default)
					)
					(fill
						(type background)
					)
				)
				(polyline
					(pts
						(xy 7.62 -11.938) (xy 5.08 -11.938)
					)
					(stroke
						(width 0.254)
						(type default)
					)
					(fill
						(type background)
					)
				)
				(polyline
					(pts
						(xy 7.62 -12.7) (xy 7.62 -15.24)
					)
					(stroke
						(width 0.254)
						(type default)
					)
					(fill
						(type background)
					)
				)
				(polyline
					(pts
						(xy 7.62 -12.7) (xy 10.16 -12.7)
					)
					(stroke
						(width 0.254)
						(type default)
					)
					(fill
						(type background)
					)
				)
				(polyline
					(pts
						(xy 9.398 0.508) (xy 10.922 0.508)
					)
					(stroke
						(width 0.254)
						(type default)
					)
					(fill
						(type background)
					)
				)
				(polyline
					(pts
						(xy 9.398 -0.762) (xy 10.922 -0.762)
					)
					(stroke
						(width 0.254)
						(type default)
					)
					(fill
						(type background)
					)
				)
				(polyline
					(pts
						(xy 9.398 -9.652) (xy 10.922 -9.652)
					)
					(stroke
						(width 0.254)
						(type default)
					)
					(fill
						(type background)
					)
				)
				(polyline
					(pts
						(xy 9.398 -10.922) (xy 10.922 -10.922)
					)
					(stroke
						(width 0.254)
						(type default)
					)
					(fill
						(type background)
					)
				)
				(polyline
					(pts
						(xy 10.16 2.54) (xy 10.16 0.508)
					)
					(stroke
						(width 0.254)
						(type default)
					)
					(fill
						(type background)
					)
				)
				(polyline
					(pts
						(xy 10.16 0.508) (xy 9.398 -0.762)
					)
					(stroke
						(width 0.254)
						(type default)
					)
					(fill
						(type background)
					)
				)
				(polyline
					(pts
						(xy 10.16 -2.54) (xy 10.16 -0.762)
					)
					(stroke
						(width 0.254)
						(type default)
					)
					(fill
						(type background)
					)
				)
				(polyline
					(pts
						(xy 10.16 -7.62) (xy 10.16 -9.652)
					)
					(stroke
						(width 0.254)
						(type default)
					)
					(fill
						(type background)
					)
				)
				(polyline
					(pts
						(xy 10.16 -9.652) (xy 9.398 -10.922)
					)
					(stroke
						(width 0.254)
						(type default)
					)
					(fill
						(type background)
					)
				)
				(polyline
					(pts
						(xy 10.16 -12.7) (xy 10.16 -10.922)
					)
					(stroke
						(width 0.254)
						(type default)
					)
					(fill
						(type background)
					)
				)
				(polyline
					(pts
						(xy 10.922 -0.762) (xy 10.16 0.508)
					)
					(stroke
						(width 0.254)
						(type default)
					)
					(fill
						(type background)
					)
				)
				(polyline
					(pts
						(xy 10.922 -10.922) (xy 10.16 -9.652)
					)
					(stroke
						(width 0.254)
						(type default)
					)
					(fill
						(type background)
					)
				)
				(polyline
					(pts
						(xy 12.7 -5.08) (xy 7.62 -5.08)
					)
					(stroke
						(width 0.254)
						(type default)
					)
					(fill
						(type background)
					)
				)
				(pin unspecified line
					(at 0 0 0)
					(length 2.54)
					(name "TG"
						(effects
							(font
								(size 1.27 1.27)
							)
						)
					)
					(number "3"
						(effects
							(font
								(size 1.27 1.27)
							)
						)
					)
				)
				(pin unspecified line
					(at 0 -5.08 0)
					(length 2.54)
					(name "TGR"
						(effects
							(font
								(size 1.27 1.27)
							)
						)
					)
					(number "4"
						(effects
							(font
								(size 1.27 1.27)
							)
						)
					)
				)
				(pin unspecified line
					(at 0 -10.16 0)
					(length 2.54)
					(name "BG"
						(effects
							(font
								(size 1.27 1.27)
							)
						)
					)
					(number "5"
						(effects
							(font
								(size 1.27 1.27)
							)
						)
					)
				)
				(pin unspecified line
					(at 7.62 7.62 270)
					(length 2.54)
					(name "VIN"
						(effects
							(font
								(size 1.27 1.27)
							)
						)
					)
					(number "1"
						(effects
							(font
								(size 1.27 1.27)
							)
						)
					)
				)
				(pin passive line
					(at 7.62 7.62 270)
					(length 2.54)
					(hide yes)
					(name "VIN"
						(effects
							(font
								(size 1.27 1.27)
							)
						)
					)
					(number "2"
						(effects
							(font
								(size 1.27 1.27)
							)
						)
					)
				)
				(pin unspecified line
					(at 7.62 -17.78 90)
					(length 2.54)
					(name "PGND"
						(effects
							(font
								(size 1.27 1.27)
							)
						)
					)
					(number "9"
						(effects
							(font
								(size 1.27 1.27)
							)
						)
					)
				)
				(pin unspecified line
					(at 15.24 -5.08 180)
					(length 2.54)
					(name "VSW"
						(effects
							(font
								(size 1.27 1.27)
							)
						)
					)
					(number "6"
						(effects
							(font
								(size 1.27 1.27)
							)
						)
					)
				)
				(pin passive line
					(at 15.24 -5.08 180)
					(length 2.54)
					(hide yes)
					(name "VSW"
						(effects
							(font
								(size 1.27 1.27)
							)
						)
					)
					(number "7"
						(effects
							(font
								(size 1.27 1.27)
							)
						)
					)
				)
				(pin passive line
					(at 15.24 -5.08 180)
					(length 2.54)
					(hide yes)
					(name "VSW"
						(effects
							(font
								(size 1.27 1.27)
							)
						)
					)
					(number "8"
						(effects
							(font
								(size 1.27 1.27)
							)
						)
					)
				)
			)
		)
	(symbol "antmicroB2BConnectors:Plug_Hirose_DF40_2x50_DF40C-100DP-0.4V"
			(pin_names
				(hide yes)
			)
			(exclude_from_sim no)
			(in_bom yes)
			(on_board yes)
			(property "Reference" "J"
				(at 36.83 0 0)
				(effects
					(font
						(size 1.27 1.27)
						(thickness 0.15)
					)
					(justify left bottom)
				)
			)
			(property "Value" "Plug_Hirose_DF40_2x50_DF40C-100DP-0.4V"
				(at 36.83 -5.08 0)
				(effects
					(font
						(size 1.27 1.27)
						(thickness 0.15)
					)
					(justify left bottom)
					(hide yes)
				)
			)
			(property "Footprint" "antmicro-footprints:Conn_Plug_Hirose_DF40_2x50_DF40C-100DP-0.4V"
				(at 36.83 -7.62 0)
				(effects
					(font
						(size 1.27 1.27)
						(thickness 0.15)
					)
					(justify left bottom)
					(hide yes)
				)
			)
			(property "Datasheet" "https://www.hirose.com/en/product/document?clcode=CL0684-4032-1-51&productname=DF40C-100DP-0.4V(51)&series=DF40&documenttype=2DDrawing&lang=en&documentid=0001001212"
				(at 36.83 -10.16 0)
				(effects
					(font
						(size 1.27 1.27)
						(thickness 0.15)
					)
					(justify left bottom)
					(hide yes)
				)
			)
			(property "Description" "Mezzanine Connector, Header, 0.4 mm, 2 Rows, 100 Contacts, Surface Mount, Phosphor Bronze"
				(at 0 0 0)
				(effects
					(font
						(size 1.27 1.27)
					)
					(hide yes)
				)
			)
			(property "MPN" "DF40C-100DP-0.4V(51)"
				(at 36.83 -2.54 0)
				(effects
					(font
						(size 1.27 1.27)
						(thickness 0.15)
					)
					(justify left bottom)
				)
			)
			(property "Manufacturer" "Hirose Electric"
				(at 36.83 -12.7 0)
				(effects
					(font
						(size 1.27 1.27)
						(thickness 0.15)
					)
					(justify left bottom)
					(hide yes)
				)
			)
			(property "Pitch" "0.4 mm"
				(at 36.83 -15.24 0)
				(effects
					(font
						(size 1.27 1.27)
					)
					(justify left bottom)
					(hide yes)
				)
			)
			(property "Author" "Antmicro"
				(at 36.83 -17.78 0)
				(effects
					(font
						(size 1.27 1.27)
						(thickness 0.15)
					)
					(justify left bottom)
					(hide yes)
				)
			)
			(property "License" "Apache-2.0"
				(at 36.83 -20.32 0)
				(effects
					(font
						(size 1.27 1.27)
						(thickness 0.15)
					)
					(justify left bottom)
					(hide yes)
				)
			)
			(property "ki_keywords" "CONNECTOR, B2B, PLUG"
				(at 0 0 0)
				(effects
					(font
						(size 1.27 1.27)
					)
					(hide yes)
				)
			)
			(symbol "Plug_Hirose_DF40_2x50_DF40C-100DP-0.4V_1_1"
				(rectangle
					(start 3.81 2.54)
					(end 10.16 -129.54)
					(stroke
						(width 0.254)
						(type default)
					)
					(fill
						(type background)
					)
				)
				(rectangle
					(start 5.08 1.27)
					(end 8.89 -128.27)
					(stroke
						(width 0.254)
						(type default)
					)
					(fill
						(type background)
					)
				)
				(pin passive line
					(at 0 0 0)
					(length 3.81)
					(name "~"
						(effects
							(font
								(size 1.27 1.27)
							)
						)
					)
					(number "1"
						(effects
							(font
								(size 1.27 1.27)
							)
						)
					)
				)
				(pin passive line
					(at 0 -2.54 0)
					(length 3.81)
					(name "~"
						(effects
							(font
								(size 1.27 1.27)
							)
						)
					)
					(number "3"
						(effects
							(font
								(size 1.27 1.27)
							)
						)
					)
				)
				(pin passive line
					(at 0 -5.08 0)
					(length 3.81)
					(name "~"
						(effects
							(font
								(size 1.27 1.27)
							)
						)
					)
					(number "5"
						(effects
							(font
								(size 1.27 1.27)
							)
						)
					)
				)
				(pin passive line
					(at 0 -7.62 0)
					(length 3.81)
					(name "~"
						(effects
							(font
								(size 1.27 1.27)
							)
						)
					)
					(number "7"
						(effects
							(font
								(size 1.27 1.27)
							)
						)
					)
				)
				(pin passive line
					(at 0 -10.16 0)
					(length 3.81)
					(name "~"
						(effects
							(font
								(size 1.27 1.27)
							)
						)
					)
					(number "9"
						(effects
							(font
								(size 1.27 1.27)
							)
						)
					)
				)
				(pin passive line
					(at 0 -12.7 0)
					(length 3.81)
					(name "~"
						(effects
							(font
								(size 1.27 1.27)
							)
						)
					)
					(number "11"
						(effects
							(font
								(size 1.27 1.27)
							)
						)
					)
				)
				(pin passive line
					(at 0 -15.24 0)
					(length 3.81)
					(name "~"
						(effects
							(font
								(size 1.27 1.27)
							)
						)
					)
					(number "13"
						(effects
							(font
								(size 1.27 1.27)
							)
						)
					)
				)
				(pin passive line
					(at 0 -17.78 0)
					(length 3.81)
					(name "~"
						(effects
							(font
								(size 1.27 1.27)
							)
						)
					)
					(number "15"
						(effects
							(font
								(size 1.27 1.27)
							)
						)
					)
				)
				(pin passive line
					(at 0 -20.32 0)
					(length 3.81)
					(name "~"
						(effects
							(font
								(size 1.27 1.27)
							)
						)
					)
					(number "17"
						(effects
							(font
								(size 1.27 1.27)
							)
						)
					)
				)
				(pin passive line
					(at 0 -22.86 0)
					(length 3.81)
					(name "~"
						(effects
							(font
								(size 1.27 1.27)
							)
						)
					)
					(number "19"
						(effects
							(font
								(size 1.27 1.27)
							)
						)
					)
				)
				(pin passive line
					(at 0 -25.4 0)
					(length 3.81)
					(name "~"
						(effects
							(font
								(size 1.27 1.27)
							)
						)
					)
					(number "21"
						(effects
							(font
								(size 1.27 1.27)
							)
						)
					)
				)
				(pin passive line
					(at 0 -27.94 0)
					(length 3.81)
					(name "~"
						(effects
							(font
								(size 1.27 1.27)
							)
						)
					)
					(number "23"
						(effects
							(font
								(size 1.27 1.27)
							)
						)
					)
				)
				(pin passive line
					(at 0 -30.48 0)
					(length 3.81)
					(name "~"
						(effects
							(font
								(size 1.27 1.27)
							)
						)
					)
					(number "25"
						(effects
							(font
								(size 1.27 1.27)
							)
						)
					)
				)
				(pin passive line
					(at 0 -33.02 0)
					(length 3.81)
					(name "~"
						(effects
							(font
								(size 1.27 1.27)
							)
						)
					)
					(number "27"
						(effects
							(font
								(size 1.27 1.27)
							)
						)
					)
				)
				(pin passive line
					(at 0 -35.56 0)
					(length 3.81)
					(name "~"
						(effects
							(font
								(size 1.27 1.27)
							)
						)
					)
					(number "29"
						(effects
							(font
								(size 1.27 1.27)
							)
						)
					)
				)
				(pin passive line
					(at 0 -38.1 0)
					(length 3.81)
					(name "~"
						(effects
							(font
								(size 1.27 1.27)
							)
						)
					)
					(number "31"
						(effects
							(font
								(size 1.27 1.27)
							)
						)
					)
				)
				(pin passive line
					(at 0 -40.64 0)
					(length 3.81)
					(name "~"
						(effects
							(font
								(size 1.27 1.27)
							)
						)
					)
					(number "33"
						(effects
							(font
								(size 1.27 1.27)
							)
						)
					)
				)
				(pin passive line
					(at 0 -43.18 0)
					(length 3.81)
					(name "~"
						(effects
							(font
								(size 1.27 1.27)
							)
						)
					)
					(number "35"
						(effects
							(font
								(size 1.27 1.27)
							)
						)
					)
				)
				(pin passive line
					(at 0 -45.72 0)
					(length 3.81)
					(name "~"
						(effects
							(font
								(size 1.27 1.27)
							)
						)
					)
					(number "37"
						(effects
							(font
								(size 1.27 1.27)
							)
						)
					)
				)
				(pin passive line
					(at 0 -48.26 0)
					(length 3.81)
					(name "~"
						(effects
							(font
								(size 1.27 1.27)
							)
						)
					)
					(number "39"
						(effects
							(font
								(size 1.27 1.27)
							)
						)
					)
				)
				(pin passive line
					(at 0 -50.8 0)
					(length 3.81)
					(name "~"
						(effects
							(font
								(size 1.27 1.27)
							)
						)
					)
					(number "41"
						(effects
							(font
								(size 1.27 1.27)
							)
						)
					)
				)
				(pin passive line
					(at 0 -53.34 0)
					(length 3.81)
					(name "~"
						(effects
							(font
								(size 1.27 1.27)
							)
						)
					)
					(number "43"
						(effects
							(font
								(size 1.27 1.27)
							)
						)
					)
				)
				(pin passive line
					(at 0 -55.88 0)
					(length 3.81)
					(name "~"
						(effects
							(font
								(size 1.27 1.27)
							)
						)
					)
					(number "45"
						(effects
							(font
								(size 1.27 1.27)
							)
						)
					)
				)
				(pin passive line
					(at 0 -58.42 0)
					(length 3.81)
					(name "~"
						(effects
							(font
								(size 1.27 1.27)
							)
						)
					)
					(number "47"
						(effects
							(font
								(size 1.27 1.27)
							)
						)
					)
				)
				(pin passive line
					(at 0 -60.96 0)
					(length 3.81)
					(name "~"
						(effects
							(font
								(size 1.27 1.27)
							)
						)
					)
					(number "49"
						(effects
							(font
								(size 1.27 1.27)
							)
						)
					)
				)
				(pin passive line
					(at 0 -63.5 0)
					(length 3.81)
					(name "~"
						(effects
							(font
								(size 1.27 1.27)
							)
						)
					)
					(number "51"
						(effects
							(font
								(size 1.27 1.27)
							)
						)
					)
				)
				(pin passive line
					(at 0 -66.04 0)
					(length 3.81)
					(name "~"
						(effects
							(font
								(size 1.27 1.27)
							)
						)
					)
					(number "53"
						(effects
							(font
								(size 1.27 1.27)
							)
						)
					)
				)
				(pin passive line
					(at 0 -68.58 0)
					(length 3.81)
					(name "~"
						(effects
							(font
								(size 1.27 1.27)
							)
						)
					)
					(number "55"
						(effects
							(font
								(size 1.27 1.27)
							)
						)
					)
				)
				(pin passive line
					(at 0 -71.12 0)
					(length 3.81)
					(name "~"
						(effects
							(font
								(size 1.27 1.27)
							)
						)
					)
					(number "57"
						(effects
							(font
								(size 1.27 1.27)
							)
						)
					)
				)
				(pin passive line
					(at 0 -73.66 0)
					(length 3.81)
					(name "~"
						(effects
							(font
								(size 1.27 1.27)
							)
						)
					)
					(number "59"
						(effects
							(font
								(size 1.27 1.27)
							)
						)
					)
				)
				(pin passive line
					(at 0 -76.2 0)
					(length 3.81)
					(name "~"
						(effects
							(font
								(size 1.27 1.27)
							)
						)
					)
					(number "61"
						(effects
							(font
								(size 1.27 1.27)
							)
						)
					)
				)
				(pin passive line
					(at 0 -78.74 0)
					(length 3.81)
					(name "~"
						(effects
							(font
								(size 1.27 1.27)
							)
						)
					)
					(number "63"
						(effects
							(font
								(size 1.27 1.27)
							)
						)
					)
				)
				(pin passive line
					(at 0 -81.28 0)
					(length 3.81)
					(name "~"
						(effects
							(font
								(size 1.27 1.27)
							)
						)
					)
					(number "65"
						(effects
							(font
								(size 1.27 1.27)
							)
						)
					)
				)
				(pin passive line
					(at 0 -83.82 0)
					(length 3.81)
					(name "~"
						(effects
							(font
								(size 1.27 1.27)
							)
						)
					)
					(number "67"
						(effects
							(font
								(size 1.27 1.27)
							)
						)
					)
				)
				(pin passive line
					(at 0 -86.36 0)
					(length 3.81)
					(name "~"
						(effects
							(font
								(size 1.27 1.27)
							)
						)
					)
					(number "69"
						(effects
							(font
								(size 1.27 1.27)
							)
						)
					)
				)
				(pin passive line
					(at 0 -88.9 0)
					(length 3.81)
					(name "~"
						(effects
							(font
								(size 1.27 1.27)
							)
						)
					)
					(number "71"
						(effects
							(font
								(size 1.27 1.27)
							)
						)
					)
				)
				(pin passive line
					(at 0 -91.44 0)
					(length 3.81)
					(name "~"
						(effects
							(font
								(size 1.27 1.27)
							)
						)
					)
					(number "73"
						(effects
							(font
								(size 1.27 1.27)
							)
						)
					)
				)
				(pin passive line
					(at 0 -93.98 0)
					(length 3.81)
					(name "~"
						(effects
							(font
								(size 1.27 1.27)
							)
						)
					)
					(number "75"
						(effects
							(font
								(size 1.27 1.27)
							)
						)
					)
				)
				(pin passive line
					(at 0 -96.52 0)
					(length 3.81)
					(name "~"
						(effects
							(font
								(size 1.27 1.27)
							)
						)
					)
					(number "77"
						(effects
							(font
								(size 1.27 1.27)
							)
						)
					)
				)
				(pin passive line
					(at 0 -99.06 0)
					(length 3.81)
					(name "~"
						(effects
							(font
								(size 1.27 1.27)
							)
						)
					)
					(number "79"
						(effects
							(font
								(size 1.27 1.27)
							)
						)
					)
				)
				(pin passive line
					(at 0 -101.6 0)
					(length 3.81)
					(name "~"
						(effects
							(font
								(size 1.27 1.27)
							)
						)
					)
					(number "81"
						(effects
							(font
								(size 1.27 1.27)
							)
						)
					)
				)
				(pin passive line
					(at 0 -104.14 0)
					(length 3.81)
					(name "~"
						(effects
							(font
								(size 1.27 1.27)
							)
						)
					)
					(number "83"
						(effects
							(font
								(size 1.27 1.27)
							)
						)
					)
				)
				(pin passive line
					(at 0 -106.68 0)
					(length 3.81)
					(name "~"
						(effects
							(font
								(size 1.27 1.27)
							)
						)
					)
					(number "85"
						(effects
							(font
								(size 1.27 1.27)
							)
						)
					)
				)
				(pin passive line
					(at 0 -109.22 0)
					(length 3.81)
					(name "~"
						(effects
							(font
								(size 1.27 1.27)
							)
						)
					)
					(number "87"
						(effects
							(font
								(size 1.27 1.27)
							)
						)
					)
				)
				(pin passive line
					(at 0 -111.76 0)
					(length 3.81)
					(name "~"
						(effects
							(font
								(size 1.27 1.27)
							)
						)
					)
					(number "89"
						(effects
							(font
								(size 1.27 1.27)
							)
						)
					)
				)
				(pin passive line
					(at 0 -114.3 0)
					(length 3.81)
					(name "~"
						(effects
							(font
								(size 1.27 1.27)
							)
						)
					)
					(number "91"
						(effects
							(font
								(size 1.27 1.27)
							)
						)
					)
				)
				(pin passive line
					(at 0 -116.84 0)
					(length 3.81)
					(name "~"
						(effects
							(font
								(size 1.27 1.27)
							)
						)
					)
					(number "93"
						(effects
							(font
								(size 1.27 1.27)
							)
						)
					)
				)
				(pin passive line
					(at 0 -119.38 0)
					(length 3.81)
					(name "~"
						(effects
							(font
								(size 1.27 1.27)
							)
						)
					)
					(number "95"
						(effects
							(font
								(size 1.27 1.27)
							)
						)
					)
				)
				(pin passive line
					(at 0 -121.92 0)
					(length 3.81)
					(name "~"
						(effects
							(font
								(size 1.27 1.27)
							)
						)
					)
					(number "97"
						(effects
							(font
								(size 1.27 1.27)
							)
						)
					)
				)
				(pin passive line
					(at 0 -124.46 0)
					(length 3.81)
					(name "~"
						(effects
							(font
								(size 1.27 1.27)
							)
						)
					)
					(number "99"
						(effects
							(font
								(size 1.27 1.27)
							)
						)
					)
				)
				(pin passive line
					(at 13.97 0 180)
					(length 3.81)
					(name "~"
						(effects
							(font
								(size 1.27 1.27)
							)
						)
					)
					(number "2"
						(effects
							(font
								(size 1.27 1.27)
							)
						)
					)
				)
				(pin passive line
					(at 13.97 -2.54 180)
					(length 3.81)
					(name "~"
						(effects
							(font
								(size 1.27 1.27)
							)
						)
					)
					(number "4"
						(effects
							(font
								(size 1.27 1.27)
							)
						)
					)
				)
				(pin passive line
					(at 13.97 -5.08 180)
					(length 3.81)
					(name "~"
						(effects
							(font
								(size 1.27 1.27)
							)
						)
					)
					(number "6"
						(effects
							(font
								(size 1.27 1.27)
							)
						)
					)
				)
				(pin passive line
					(at 13.97 -7.62 180)
					(length 3.81)
					(name "~"
						(effects
							(font
								(size 1.27 1.27)
							)
						)
					)
					(number "8"
						(effects
							(font
								(size 1.27 1.27)
							)
						)
					)
				)
				(pin passive line
					(at 13.97 -10.16 180)
					(length 3.81)
					(name "~"
						(effects
							(font
								(size 1.27 1.27)
							)
						)
					)
					(number "10"
						(effects
							(font
								(size 1.27 1.27)
							)
						)
					)
				)
				(pin passive line
					(at 13.97 -12.7 180)
					(length 3.81)
					(name "~"
						(effects
							(font
								(size 1.27 1.27)
							)
						)
					)
					(number "12"
						(effects
							(font
								(size 1.27 1.27)
							)
						)
					)
				)
				(pin passive line
					(at 13.97 -15.24 180)
					(length 3.81)
					(name "~"
						(effects
							(font
								(size 1.27 1.27)
							)
						)
					)
					(number "14"
						(effects
							(font
								(size 1.27 1.27)
							)
						)
					)
				)
				(pin passive line
					(at 13.97 -17.78 180)
					(length 3.81)
					(name "~"
						(effects
							(font
								(size 1.27 1.27)
							)
						)
					)
					(number "16"
						(effects
							(font
								(size 1.27 1.27)
							)
						)
					)
				)
				(pin passive line
					(at 13.97 -20.32 180)
					(length 3.81)
					(name "~"
						(effects
							(font
								(size 1.27 1.27)
							)
						)
					)
					(number "18"
						(effects
							(font
								(size 1.27 1.27)
							)
						)
					)
				)
				(pin passive line
					(at 13.97 -22.86 180)
					(length 3.81)
					(name "~"
						(effects
							(font
								(size 1.27 1.27)
							)
						)
					)
					(number "20"
						(effects
							(font
								(size 1.27 1.27)
							)
						)
					)
				)
				(pin passive line
					(at 13.97 -25.4 180)
					(length 3.81)
					(name "~"
						(effects
							(font
								(size 1.27 1.27)
							)
						)
					)
					(number "22"
						(effects
							(font
								(size 1.27 1.27)
							)
						)
					)
				)
				(pin passive line
					(at 13.97 -27.94 180)
					(length 3.81)
					(name "~"
						(effects
							(font
								(size 1.27 1.27)
							)
						)
					)
					(number "24"
						(effects
							(font
								(size 1.27 1.27)
							)
						)
					)
				)
				(pin passive line
					(at 13.97 -30.48 180)
					(length 3.81)
					(name "~"
						(effects
							(font
								(size 1.27 1.27)
							)
						)
					)
					(number "26"
						(effects
							(font
								(size 1.27 1.27)
							)
						)
					)
				)
				(pin passive line
					(at 13.97 -33.02 180)
					(length 3.81)
					(name "~"
						(effects
							(font
								(size 1.27 1.27)
							)
						)
					)
					(number "28"
						(effects
							(font
								(size 1.27 1.27)
							)
						)
					)
				)
				(pin passive line
					(at 13.97 -35.56 180)
					(length 3.81)
					(name "~"
						(effects
							(font
								(size 1.27 1.27)
							)
						)
					)
					(number "30"
						(effects
							(font
								(size 1.27 1.27)
							)
						)
					)
				)
				(pin passive line
					(at 13.97 -38.1 180)
					(length 3.81)
					(name "~"
						(effects
							(font
								(size 1.27 1.27)
							)
						)
					)
					(number "32"
						(effects
							(font
								(size 1.27 1.27)
							)
						)
					)
				)
				(pin passive line
					(at 13.97 -40.64 180)
					(length 3.81)
					(name "~"
						(effects
							(font
								(size 1.27 1.27)
							)
						)
					)
					(number "34"
						(effects
							(font
								(size 1.27 1.27)
							)
						)
					)
				)
				(pin passive line
					(at 13.97 -43.18 180)
					(length 3.81)
					(name "~"
						(effects
							(font
								(size 1.27 1.27)
							)
						)
					)
					(number "36"
						(effects
							(font
								(size 1.27 1.27)
							)
						)
					)
				)
				(pin passive line
					(at 13.97 -45.72 180)
					(length 3.81)
					(name "~"
						(effects
							(font
								(size 1.27 1.27)
							)
						)
					)
					(number "38"
						(effects
							(font
								(size 1.27 1.27)
							)
						)
					)
				)
				(pin passive line
					(at 13.97 -48.26 180)
					(length 3.81)
					(name "~"
						(effects
							(font
								(size 1.27 1.27)
							)
						)
					)
					(number "40"
						(effects
							(font
								(size 1.27 1.27)
							)
						)
					)
				)
				(pin passive line
					(at 13.97 -50.8 180)
					(length 3.81)
					(name "~"
						(effects
							(font
								(size 1.27 1.27)
							)
						)
					)
					(number "42"
						(effects
							(font
								(size 1.27 1.27)
							)
						)
					)
				)
				(pin passive line
					(at 13.97 -53.34 180)
					(length 3.81)
					(name "~"
						(effects
							(font
								(size 1.27 1.27)
							)
						)
					)
					(number "44"
						(effects
							(font
								(size 1.27 1.27)
							)
						)
					)
				)
				(pin passive line
					(at 13.97 -55.88 180)
					(length 3.81)
					(name "~"
						(effects
							(font
								(size 1.27 1.27)
							)
						)
					)
					(number "46"
						(effects
							(font
								(size 1.27 1.27)
							)
						)
					)
				)
				(pin passive line
					(at 13.97 -58.42 180)
					(length 3.81)
					(name "~"
						(effects
							(font
								(size 1.27 1.27)
							)
						)
					)
					(number "48"
						(effects
							(font
								(size 1.27 1.27)
							)
						)
					)
				)
				(pin passive line
					(at 13.97 -60.96 180)
					(length 3.81)
					(name "~"
						(effects
							(font
								(size 1.27 1.27)
							)
						)
					)
					(number "50"
						(effects
							(font
								(size 1.27 1.27)
							)
						)
					)
				)
				(pin passive line
					(at 13.97 -63.5 180)
					(length 3.81)
					(name "~"
						(effects
							(font
								(size 1.27 1.27)
							)
						)
					)
					(number "52"
						(effects
							(font
								(size 1.27 1.27)
							)
						)
					)
				)
				(pin passive line
					(at 13.97 -66.04 180)
					(length 3.81)
					(name "~"
						(effects
							(font
								(size 1.27 1.27)
							)
						)
					)
					(number "54"
						(effects
							(font
								(size 1.27 1.27)
							)
						)
					)
				)
				(pin passive line
					(at 13.97 -68.58 180)
					(length 3.81)
					(name "~"
						(effects
							(font
								(size 1.27 1.27)
							)
						)
					)
					(number "56"
						(effects
							(font
								(size 1.27 1.27)
							)
						)
					)
				)
				(pin passive line
					(at 13.97 -71.12 180)
					(length 3.81)
					(name "~"
						(effects
							(font
								(size 1.27 1.27)
							)
						)
					)
					(number "58"
						(effects
							(font
								(size 1.27 1.27)
							)
						)
					)
				)
				(pin passive line
					(at 13.97 -73.66 180)
					(length 3.81)
					(name "~"
						(effects
							(font
								(size 1.27 1.27)
							)
						)
					)
					(number "60"
						(effects
							(font
								(size 1.27 1.27)
							)
						)
					)
				)
				(pin passive line
					(at 13.97 -76.2 180)
					(length 3.81)
					(name "~"
						(effects
							(font
								(size 1.27 1.27)
							)
						)
					)
					(number "62"
						(effects
							(font
								(size 1.27 1.27)
							)
						)
					)
				)
				(pin passive line
					(at 13.97 -78.74 180)
					(length 3.81)
					(name "~"
						(effects
							(font
								(size 1.27 1.27)
							)
						)
					)
					(number "64"
						(effects
							(font
								(size 1.27 1.27)
							)
						)
					)
				)
				(pin passive line
					(at 13.97 -81.28 180)
					(length 3.81)
					(name "~"
						(effects
							(font
								(size 1.27 1.27)
							)
						)
					)
					(number "66"
						(effects
							(font
								(size 1.27 1.27)
							)
						)
					)
				)
				(pin passive line
					(at 13.97 -83.82 180)
					(length 3.81)
					(name "~"
						(effects
							(font
								(size 1.27 1.27)
							)
						)
					)
					(number "68"
						(effects
							(font
								(size 1.27 1.27)
							)
						)
					)
				)
				(pin passive line
					(at 13.97 -86.36 180)
					(length 3.81)
					(name "~"
						(effects
							(font
								(size 1.27 1.27)
							)
						)
					)
					(number "70"
						(effects
							(font
								(size 1.27 1.27)
							)
						)
					)
				)
				(pin passive line
					(at 13.97 -88.9 180)
					(length 3.81)
					(name "~"
						(effects
							(font
								(size 1.27 1.27)
							)
						)
					)
					(number "72"
						(effects
							(font
								(size 1.27 1.27)
							)
						)
					)
				)
				(pin passive line
					(at 13.97 -91.44 180)
					(length 3.81)
					(name "~"
						(effects
							(font
								(size 1.27 1.27)
							)
						)
					)
					(number "74"
						(effects
							(font
								(size 1.27 1.27)
							)
						)
					)
				)
				(pin passive line
					(at 13.97 -93.98 180)
					(length 3.81)
					(name "~"
						(effects
							(font
								(size 1.27 1.27)
							)
						)
					)
					(number "76"
						(effects
							(font
								(size 1.27 1.27)
							)
						)
					)
				)
				(pin passive line
					(at 13.97 -96.52 180)
					(length 3.81)
					(name "~"
						(effects
							(font
								(size 1.27 1.27)
							)
						)
					)
					(number "78"
						(effects
							(font
								(size 1.27 1.27)
							)
						)
					)
				)
				(pin passive line
					(at 13.97 -99.06 180)
					(length 3.81)
					(name "~"
						(effects
							(font
								(size 1.27 1.27)
							)
						)
					)
					(number "80"
						(effects
							(font
								(size 1.27 1.27)
							)
						)
					)
				)
				(pin passive line
					(at 13.97 -101.6 180)
					(length 3.81)
					(name "~"
						(effects
							(font
								(size 1.27 1.27)
							)
						)
					)
					(number "82"
						(effects
							(font
								(size 1.27 1.27)
							)
						)
					)
				)
				(pin passive line
					(at 13.97 -104.14 180)
					(length 3.81)
					(name "~"
						(effects
							(font
								(size 1.27 1.27)
							)
						)
					)
					(number "84"
						(effects
							(font
								(size 1.27 1.27)
							)
						)
					)
				)
				(pin passive line
					(at 13.97 -106.68 180)
					(length 3.81)
					(name "~"
						(effects
							(font
								(size 1.27 1.27)
							)
						)
					)
					(number "86"
						(effects
							(font
								(size 1.27 1.27)
							)
						)
					)
				)
				(pin passive line
					(at 13.97 -109.22 180)
					(length 3.81)
					(name "~"
						(effects
							(font
								(size 1.27 1.27)
							)
						)
					)
					(number "88"
						(effects
							(font
								(size 1.27 1.27)
							)
						)
					)
				)
				(pin passive line
					(at 13.97 -111.76 180)
					(length 3.81)
					(name "~"
						(effects
							(font
								(size 1.27 1.27)
							)
						)
					)
					(number "90"
						(effects
							(font
								(size 1.27 1.27)
							)
						)
					)
				)
				(pin passive line
					(at 13.97 -114.3 180)
					(length 3.81)
					(name "~"
						(effects
							(font
								(size 1.27 1.27)
							)
						)
					)
					(number "92"
						(effects
							(font
								(size 1.27 1.27)
							)
						)
					)
				)
				(pin passive line
					(at 13.97 -116.84 180)
					(length 3.81)
					(name "~"
						(effects
							(font
								(size 1.27 1.27)
							)
						)
					)
					(number "94"
						(effects
							(font
								(size 1.27 1.27)
							)
						)
					)
				)
				(pin passive line
					(at 13.97 -119.38 180)
					(length 3.81)
					(name "~"
						(effects
							(font
								(size 1.27 1.27)
							)
						)
					)
					(number "96"
						(effects
							(font
								(size 1.27 1.27)
							)
						)
					)
				)
				(pin passive line
					(at 13.97 -121.92 180)
					(length 3.81)
					(name "~"
						(effects
							(font
								(size 1.27 1.27)
							)
						)
					)
					(number "98"
						(effects
							(font
								(size 1.27 1.27)
							)
						)
					)
				)
				(pin passive line
					(at 13.97 -124.46 180)
					(length 3.81)
					(name "~"
						(effects
							(font
								(size 1.27 1.27)
							)
						)
					)
					(number "100"
						(effects
							(font
								(size 1.27 1.27)
							)
						)
					)
				)
				(pin passive line
					(at 13.97 -127 180)
					(length 3.81)
					(name "MP"
						(effects
							(font
								(size 1.27 1.27)
							)
						)
					)
					(number "MP"
						(effects
							(font
								(size 1.27 1.27)
							)
						)
					)
				)
			)
		)
	(symbol "antmicroCapacitors0402:C_100n_0402"
			(pin_numbers
				(hide yes)
			)
			(pin_names
				(hide yes)
			)
			(exclude_from_sim no)
			(in_bom yes)
			(on_board yes)
			(property "Reference" "C"
				(at 20.32 -5.08 0)
				(effects
					(font
						(size 1.27 1.27)
						(thickness 0.15)
					)
					(justify left bottom)
				)
			)
			(property "Value" "C_100n_0402"
				(at 20.32 -10.16 0)
				(effects
					(font
						(size 1.27 1.27)
						(thickness 0.15)
					)
					(justify left bottom)
					(hide yes)
				)
			)
			(property "Footprint" "antmicro-footprints:C_0402_1005Metric"
				(at 20.32 -12.7 0)
				(effects
					(font
						(size 1.27 1.27)
						(thickness 0.15)
					)
					(justify left bottom)
					(hide yes)
				)
			)
			(property "Datasheet" "https://www.murata.com/products/productdetail?partno=GRM155R61H104KE14%23"
				(at 20.32 -15.24 0)
				(effects
					(font
						(size 1.27 1.27)
						(thickness 0.15)
					)
					(justify left bottom)
					(hide yes)
				)
			)
			(property "Description" "SMD Multilayer Ceramic Capacitor, 0.1 µF, 50 V, 0402 [1005 Metric], ± 10%, X5R, GRM Series"
				(at 0 0 0)
				(effects
					(font
						(size 1.27 1.27)
					)
					(hide yes)
				)
			)
			(property "MPN" "GRM155R61H104KE14D"
				(at 20.32 -17.78 0)
				(effects
					(font
						(size 1.27 1.27)
						(thickness 0.15)
					)
					(justify left bottom)
					(hide yes)
				)
			)
			(property "Manufacturer" "Murata"
				(at 20.32 -20.32 0)
				(effects
					(font
						(size 1.27 1.27)
						(thickness 0.15)
					)
					(justify left bottom)
					(hide yes)
				)
			)
			(property "License" "Apache-2.0"
				(at 20.32 -22.86 0)
				(effects
					(font
						(size 1.27 1.27)
						(thickness 0.15)
					)
					(justify left bottom)
					(hide yes)
				)
			)
			(property "Author" "Antmicro"
				(at 20.32 -25.4 0)
				(effects
					(font
						(size 1.27 1.27)
						(thickness 0.15)
					)
					(justify left bottom)
					(hide yes)
				)
			)
			(property "Val" "100n"
				(at 20.32 -7.62 0)
				(effects
					(font
						(size 1.27 1.27)
						(thickness 0.15)
					)
					(justify left bottom)
				)
			)
			(property "Voltage" "50V"
				(at 20.32 -27.94 0)
				(effects
					(font
						(size 1.27 1.27)
					)
					(justify left bottom)
					(hide yes)
				)
			)
			(property "Dielectric" "X5R"
				(at 20.32 -30.48 0)
				(effects
					(font
						(size 1.27 1.27)
					)
					(justify left bottom)
					(hide yes)
				)
			)
			(property "ki_keywords" "0402, SMT, CAPACITOR, PASSIVE, CERAMIC, MLCC"
				(at 0 0 0)
				(effects
					(font
						(size 1.27 1.27)
					)
					(hide yes)
				)
			)
			(symbol "C_100n_0402_0_1"
				(polyline
					(pts
						(xy 2.032 -1.524) (xy 2.032 1.524)
					)
					(stroke
						(width 0.3048)
						(type default)
					)
					(fill
						(type none)
					)
				)
				(polyline
					(pts
						(xy 3.048 -1.524) (xy 3.048 1.524)
					)
					(stroke
						(width 0.3302)
						(type default)
					)
					(fill
						(type none)
					)
				)
			)
			(symbol "C_100n_0402_1_1"
				(pin passive line
					(at 0 0 0)
					(length 2.032)
					(name "~"
						(effects
							(font
								(size 1.27 1.27)
							)
						)
					)
					(number "1"
						(effects
							(font
								(size 1.27 1.27)
							)
						)
					)
				)
				(pin passive line
					(at 5.08 0 180)
					(length 2.032)
					(name "~"
						(effects
							(font
								(size 1.27 1.27)
							)
						)
					)
					(number "2"
						(effects
							(font
								(size 1.27 1.27)
							)
						)
					)
				)
			)
		)
	(symbol "antmicroCapacitors0402:C_10n_0402"
			(pin_numbers
				(hide yes)
			)
			(pin_names
				(hide yes)
			)
			(exclude_from_sim no)
			(in_bom yes)
			(on_board yes)
			(property "Reference" "C"
				(at 20.32 -5.08 0)
				(effects
					(font
						(size 1.27 1.27)
						(thickness 0.15)
					)
					(justify left bottom)
				)
			)
			(property "Value" "C_10n_0402"
				(at 20.32 -10.16 0)
				(effects
					(font
						(size 1.27 1.27)
						(thickness 0.15)
					)
					(justify left bottom)
					(hide yes)
				)
			)
			(property "Footprint" "antmicro-footprints:C_0402_1005Metric"
				(at 20.32 -12.7 0)
				(effects
					(font
						(size 1.27 1.27)
						(thickness 0.15)
					)
					(justify left bottom)
					(hide yes)
				)
			)
			(property "Datasheet" "https://www.murata.com/products/productdetail?partno=GRM155R71H103KA88%23"
				(at 20.32 -15.24 0)
				(effects
					(font
						(size 1.27 1.27)
						(thickness 0.15)
					)
					(justify left bottom)
					(hide yes)
				)
			)
			(property "Description" "SMD Multilayer Ceramic Capacitor, 10000 pF, 50 V, 0402 [1005 Metric], ± 10%, X7R, GRM Series"
				(at 0 0 0)
				(effects
					(font
						(size 1.27 1.27)
					)
					(hide yes)
				)
			)
			(property "MPN" "GRM155R71H103KA88D"
				(at 20.32 -17.78 0)
				(effects
					(font
						(size 1.27 1.27)
						(thickness 0.15)
					)
					(justify left bottom)
					(hide yes)
				)
			)
			(property "Manufacturer" "Murata"
				(at 20.32 -20.32 0)
				(effects
					(font
						(size 1.27 1.27)
						(thickness 0.15)
					)
					(justify left bottom)
					(hide yes)
				)
			)
			(property "License" "Apache-2.0"
				(at 20.32 -22.86 0)
				(effects
					(font
						(size 1.27 1.27)
						(thickness 0.15)
					)
					(justify left bottom)
					(hide yes)
				)
			)
			(property "Author" "Antmicro"
				(at 20.32 -25.4 0)
				(effects
					(font
						(size 1.27 1.27)
						(thickness 0.15)
					)
					(justify left bottom)
					(hide yes)
				)
			)
			(property "Val" "10n"
				(at 20.32 -7.62 0)
				(effects
					(font
						(size 1.27 1.27)
						(thickness 0.15)
					)
					(justify left bottom)
				)
			)
			(property "Voltage" "50V"
				(at 20.32 -27.94 0)
				(effects
					(font
						(size 1.27 1.27)
					)
					(justify left bottom)
					(hide yes)
				)
			)
			(property "Dielectric" "X7R"
				(at 20.32 -30.48 0)
				(effects
					(font
						(size 1.27 1.27)
					)
					(justify left bottom)
					(hide yes)
				)
			)
			(property "ki_keywords" "0402, SMT, CAPACITOR, PASSIVE"
				(at 0 0 0)
				(effects
					(font
						(size 1.27 1.27)
					)
					(hide yes)
				)
			)
			(symbol "C_10n_0402_0_1"
				(polyline
					(pts
						(xy 2.032 -1.524) (xy 2.032 1.524)
					)
					(stroke
						(width 0.3048)
						(type default)
					)
					(fill
						(type none)
					)
				)
				(polyline
					(pts
						(xy 3.048 -1.524) (xy 3.048 1.524)
					)
					(stroke
						(width 0.3302)
						(type default)
					)
					(fill
						(type none)
					)
				)
			)
			(symbol "C_10n_0402_1_1"
				(pin passive line
					(at 0 0 0)
					(length 2.032)
					(name "~"
						(effects
							(font
								(size 1.27 1.27)
							)
						)
					)
					(number "1"
						(effects
							(font
								(size 1.27 1.27)
							)
						)
					)
				)
				(pin passive line
					(at 5.08 0 180)
					(length 2.032)
					(name "~"
						(effects
							(font
								(size 1.27 1.27)
							)
						)
					)
					(number "2"
						(effects
							(font
								(size 1.27 1.27)
							)
						)
					)
				)
			)
		)
	(symbol "antmicroCapacitors0402:C_10u_0402"
			(pin_numbers
				(hide yes)
			)
			(pin_names
				(hide yes)
			)
			(exclude_from_sim no)
			(in_bom yes)
			(on_board yes)
			(property "Reference" "C"
				(at 20.32 -5.08 0)
				(effects
					(font
						(size 1.27 1.27)
						(thickness 0.15)
					)
					(justify left bottom)
				)
			)
			(property "Value" "C_10u_0402"
				(at 20.32 -10.16 0)
				(effects
					(font
						(size 1.27 1.27)
						(thickness 0.15)
					)
					(justify left bottom)
					(hide yes)
				)
			)
			(property "Footprint" "antmicro-footprints:C_0402_1005Metric"
				(at 20.32 -12.7 0)
				(effects
					(font
						(size 1.27 1.27)
						(thickness 0.15)
					)
					(justify left bottom)
					(hide yes)
				)
			)
			(property "Datasheet" "https://www.yageo.com/en/Chart/Download/pdf/CC0402MRX5R5BB106"
				(at 20.32 -15.24 0)
				(effects
					(font
						(size 1.27 1.27)
						(thickness 0.15)
					)
					(justify left bottom)
					(hide yes)
				)
			)
			(property "Description" "SMD Multilayer Ceramic Capacitor, 10 µF, 6.3 V, 0402 [1005 Metric], ± 20%, X5R, CC Series"
				(at 0 0 0)
				(effects
					(font
						(size 1.27 1.27)
					)
					(hide yes)
				)
			)
			(property "MPN" "CC0402MRX5R5BB106"
				(at 20.32 -17.78 0)
				(effects
					(font
						(size 1.27 1.27)
						(thickness 0.15)
					)
					(justify left bottom)
					(hide yes)
				)
			)
			(property "Manufacturer" "YAGEO"
				(at 20.32 -20.32 0)
				(effects
					(font
						(size 1.27 1.27)
						(thickness 0.15)
					)
					(justify left bottom)
					(hide yes)
				)
			)
			(property "License" "Apache-2.0"
				(at 20.32 -22.86 0)
				(effects
					(font
						(size 1.27 1.27)
						(thickness 0.15)
					)
					(justify left bottom)
					(hide yes)
				)
			)
			(property "Author" "Antmicro"
				(at 20.32 -25.4 0)
				(effects
					(font
						(size 1.27 1.27)
						(thickness 0.15)
					)
					(justify left bottom)
					(hide yes)
				)
			)
			(property "Val" "10u"
				(at 20.32 -7.62 0)
				(effects
					(font
						(size 1.27 1.27)
						(thickness 0.15)
					)
					(justify left bottom)
				)
			)
			(property "Voltage" ""
				(at 20.32 -27.94 0)
				(effects
					(font
						(size 1.27 1.27)
					)
					(justify left bottom)
					(hide yes)
				)
			)
			(property "Dielectric" ""
				(at 20.32 -30.48 0)
				(effects
					(font
						(size 1.27 1.27)
					)
					(justify left bottom)
					(hide yes)
				)
			)
			(property "ki_keywords" "0402, SMT, CAPACITOR, PASSIVE, MLCC, CERAMIC"
				(at 0 0 0)
				(effects
					(font
						(size 1.27 1.27)
					)
					(hide yes)
				)
			)
			(symbol "C_10u_0402_0_1"
				(polyline
					(pts
						(xy 2.032 -1.524) (xy 2.032 1.524)
					)
					(stroke
						(width 0.3048)
						(type default)
					)
					(fill
						(type none)
					)
				)
				(polyline
					(pts
						(xy 3.048 -1.524) (xy 3.048 1.524)
					)
					(stroke
						(width 0.3302)
						(type default)
					)
					(fill
						(type none)
					)
				)
			)
			(symbol "C_10u_0402_1_1"
				(pin passive line
					(at 0 0 0)
					(length 2.032)
					(name "~"
						(effects
							(font
								(size 1.27 1.27)
							)
						)
					)
					(number "1"
						(effects
							(font
								(size 1.27 1.27)
							)
						)
					)
				)
				(pin passive line
					(at 5.08 0 180)
					(length 2.032)
					(name "~"
						(effects
							(font
								(size 1.27 1.27)
							)
						)
					)
					(number "2"
						(effects
							(font
								(size 1.27 1.27)
							)
						)
					)
				)
			)
		)
	(symbol "antmicroCapacitors0402:C_10u_10V_0402"
			(pin_numbers
				(hide yes)
			)
			(pin_names
				(hide yes)
			)
			(exclude_from_sim no)
			(in_bom yes)
			(on_board yes)
			(property "Reference" "C"
				(at 20.32 -5.08 0)
				(effects
					(font
						(size 1.27 1.27)
						(thickness 0.15)
					)
					(justify left bottom)
				)
			)
			(property "Value" "C_10u_10V_0402"
				(at 20.32 -10.16 0)
				(effects
					(font
						(size 1.27 1.27)
						(thickness 0.15)
					)
					(justify left bottom)
					(hide yes)
				)
			)
			(property "Footprint" "antmicro-footprints:C_0402_1005Metric"
				(at 20.32 -12.7 0)
				(effects
					(font
						(size 1.27 1.27)
						(thickness 0.15)
					)
					(justify left bottom)
					(hide yes)
				)
			)
			(property "Datasheet" "https://www.murata.com/products/productdetail?partno=GRM155R61A106ME11%23"
				(at 20.32 -15.24 0)
				(effects
					(font
						(size 1.27 1.27)
						(thickness 0.15)
					)
					(justify left bottom)
					(hide yes)
				)
			)
			(property "Description" "Multilayer Ceramic Capacitors MLCC - SMD/SMT 10 uF 10 VDC 20% 0402 X5R"
				(at 0 0 0)
				(effects
					(font
						(size 1.27 1.27)
					)
					(hide yes)
				)
			)
			(property "MPN" "GRM155R61A106ME11D"
				(at 20.32 -17.78 0)
				(effects
					(font
						(size 1.27 1.27)
						(thickness 0.15)
					)
					(justify left bottom)
					(hide yes)
				)
			)
			(property "Manufacturer" "Murata"
				(at 20.32 -20.32 0)
				(effects
					(font
						(size 1.27 1.27)
						(thickness 0.15)
					)
					(justify left bottom)
					(hide yes)
				)
			)
			(property "License" "Apache-2.0"
				(at 20.32 -22.86 0)
				(effects
					(font
						(size 1.27 1.27)
						(thickness 0.15)
					)
					(justify left bottom)
					(hide yes)
				)
			)
			(property "Author" "Antmicro"
				(at 20.32 -25.4 0)
				(effects
					(font
						(size 1.27 1.27)
						(thickness 0.15)
					)
					(justify left bottom)
					(hide yes)
				)
			)
			(property "Val" "10u"
				(at 20.32 -7.62 0)
				(effects
					(font
						(size 1.27 1.27)
						(thickness 0.15)
					)
					(justify left bottom)
				)
			)
			(property "Voltage" "10V"
				(at 20.32 -27.94 0)
				(effects
					(font
						(size 1.27 1.27)
					)
					(justify left bottom)
					(hide yes)
				)
			)
			(property "Dielectric" "X5R"
				(at 20.32 -30.48 0)
				(effects
					(font
						(size 1.27 1.27)
					)
					(justify left bottom)
					(hide yes)
				)
			)
			(property "ki_keywords" "0402, SMT, CAPACITOR, PASSIVE, CERAMIC"
				(at 0 0 0)
				(effects
					(font
						(size 1.27 1.27)
					)
					(hide yes)
				)
			)
			(symbol "C_10u_10V_0402_0_1"
				(polyline
					(pts
						(xy 2.032 -1.524) (xy 2.032 1.524)
					)
					(stroke
						(width 0.3048)
						(type default)
					)
					(fill
						(type none)
					)
				)
				(polyline
					(pts
						(xy 3.048 -1.524) (xy 3.048 1.524)
					)
					(stroke
						(width 0.3302)
						(type default)
					)
					(fill
						(type none)
					)
				)
			)
			(symbol "C_10u_10V_0402_1_1"
				(pin passive line
					(at 0 0 0)
					(length 2.032)
					(name "~"
						(effects
							(font
								(size 1.27 1.27)
							)
						)
					)
					(number "1"
						(effects
							(font
								(size 1.27 1.27)
							)
						)
					)
				)
				(pin passive line
					(at 5.08 0 180)
					(length 2.032)
					(name "~"
						(effects
							(font
								(size 1.27 1.27)
							)
						)
					)
					(number "2"
						(effects
							(font
								(size 1.27 1.27)
							)
						)
					)
				)
			)
		)
	(symbol "antmicroCapacitors0402:C_1n_0402"
			(pin_numbers
				(hide yes)
			)
			(pin_names
				(hide yes)
			)
			(exclude_from_sim no)
			(in_bom yes)
			(on_board yes)
			(property "Reference" "C"
				(at 20.32 -5.08 0)
				(effects
					(font
						(size 1.27 1.27)
						(thickness 0.15)
					)
					(justify left bottom)
				)
			)
			(property "Value" "C_1n_0402"
				(at 20.32 -10.16 0)
				(effects
					(font
						(size 1.27 1.27)
						(thickness 0.15)
					)
					(justify left bottom)
					(hide yes)
				)
			)
			(property "Footprint" "antmicro-footprints:C_0402_1005Metric"
				(at 20.32 -12.7 0)
				(effects
					(font
						(size 1.27 1.27)
						(thickness 0.15)
					)
					(justify left bottom)
					(hide yes)
				)
			)
			(property "Datasheet" "https://www.murata.com/products/productdetail?partno=GRM1555C1H102JA01%23"
				(at 20.32 -15.24 0)
				(effects
					(font
						(size 1.27 1.27)
						(thickness 0.15)
					)
					(justify left bottom)
					(hide yes)
				)
			)
			(property "Description" "SMD Multilayer Ceramic Capacitor, 1000 pF, 50 V, 0402 [1005 Metric], ± 5%, C0G / NP0, GRM Series"
				(at 0 0 0)
				(effects
					(font
						(size 1.27 1.27)
					)
					(hide yes)
				)
			)
			(property "MPN" "GRM1555C1H102JA01D"
				(at 20.32 -17.78 0)
				(effects
					(font
						(size 1.27 1.27)
						(thickness 0.15)
					)
					(justify left bottom)
					(hide yes)
				)
			)
			(property "Manufacturer" "Murata"
				(at 20.32 -20.32 0)
				(effects
					(font
						(size 1.27 1.27)
						(thickness 0.15)
					)
					(justify left bottom)
					(hide yes)
				)
			)
			(property "License" "Apache-2.0"
				(at 20.32 -22.86 0)
				(effects
					(font
						(size 1.27 1.27)
						(thickness 0.15)
					)
					(justify left bottom)
					(hide yes)
				)
			)
			(property "Author" "Antmicro"
				(at 20.32 -25.4 0)
				(effects
					(font
						(size 1.27 1.27)
						(thickness 0.15)
					)
					(justify left bottom)
					(hide yes)
				)
			)
			(property "Val" "1n"
				(at 20.32 -7.62 0)
				(effects
					(font
						(size 1.27 1.27)
						(thickness 0.15)
					)
					(justify left bottom)
				)
			)
			(property "Voltage" "50V"
				(at 20.32 -27.94 0)
				(effects
					(font
						(size 1.27 1.27)
					)
					(justify left bottom)
					(hide yes)
				)
			)
			(property "Dielectric" "C0G"
				(at 20.32 -30.48 0)
				(effects
					(font
						(size 1.27 1.27)
					)
					(justify left bottom)
					(hide yes)
				)
			)
			(property "ki_keywords" "0402, SMT, CAPACITOR, PASSIVE, CERAMIC, MLCC"
				(at 0 0 0)
				(effects
					(font
						(size 1.27 1.27)
					)
					(hide yes)
				)
			)
			(symbol "C_1n_0402_0_1"
				(polyline
					(pts
						(xy 2.032 -1.524) (xy 2.032 1.524)
					)
					(stroke
						(width 0.3048)
						(type default)
					)
					(fill
						(type none)
					)
				)
				(polyline
					(pts
						(xy 3.048 -1.524) (xy 3.048 1.524)
					)
					(stroke
						(width 0.3302)
						(type default)
					)
					(fill
						(type none)
					)
				)
			)
			(symbol "C_1n_0402_1_1"
				(pin passive line
					(at 0 0 0)
					(length 2.032)
					(name "~"
						(effects
							(font
								(size 1.27 1.27)
							)
						)
					)
					(number "1"
						(effects
							(font
								(size 1.27 1.27)
							)
						)
					)
				)
				(pin passive line
					(at 5.08 0 180)
					(length 2.032)
					(name "~"
						(effects
							(font
								(size 1.27 1.27)
							)
						)
					)
					(number "2"
						(effects
							(font
								(size 1.27 1.27)
							)
						)
					)
				)
			)
		)
	(symbol "antmicroCapacitors0402:C_1u_0402"
			(pin_numbers
				(hide yes)
			)
			(pin_names
				(hide yes)
			)
			(exclude_from_sim no)
			(in_bom yes)
			(on_board yes)
			(property "Reference" "C"
				(at 20.32 -5.08 0)
				(effects
					(font
						(size 1.27 1.27)
						(thickness 0.15)
					)
					(justify left bottom)
				)
			)
			(property "Value" "C_1u_0402"
				(at 20.32 -10.16 0)
				(effects
					(font
						(size 1.27 1.27)
						(thickness 0.15)
					)
					(justify left bottom)
					(hide yes)
				)
			)
			(property "Footprint" "antmicro-footprints:C_0402_1005Metric"
				(at 20.32 -12.7 0)
				(effects
					(font
						(size 1.27 1.27)
						(thickness 0.15)
					)
					(justify left bottom)
					(hide yes)
				)
			)
			(property "Datasheet" "https://product.tdk.com/en/search/capacitor/ceramic/mlcc/info?part_no=C1005X6S1A105K050BC"
				(at 20.32 -15.24 0)
				(effects
					(font
						(size 1.27 1.27)
						(thickness 0.15)
					)
					(justify left bottom)
					(hide yes)
				)
			)
			(property "Description" "SMD Multilayer Ceramic Capacitor, 1 µF, 10 V, 0402 [1005 Metric], ± 10%, X6S, C"
				(at 0 0 0)
				(effects
					(font
						(size 1.27 1.27)
					)
					(hide yes)
				)
			)
			(property "MPN" "C1005X6S1A105K050BC"
				(at 20.32 -17.78 0)
				(effects
					(font
						(size 1.27 1.27)
						(thickness 0.15)
					)
					(justify left bottom)
					(hide yes)
				)
			)
			(property "Manufacturer" "TDK"
				(at 20.32 -20.32 0)
				(effects
					(font
						(size 1.27 1.27)
						(thickness 0.15)
					)
					(justify left bottom)
					(hide yes)
				)
			)
			(property "License" "Apache-2.0"
				(at 20.32 -22.86 0)
				(effects
					(font
						(size 1.27 1.27)
						(thickness 0.15)
					)
					(justify left bottom)
					(hide yes)
				)
			)
			(property "Author" "Antmicro"
				(at 20.32 -25.4 0)
				(effects
					(font
						(size 1.27 1.27)
						(thickness 0.15)
					)
					(justify left bottom)
					(hide yes)
				)
			)
			(property "Val" "1u"
				(at 20.32 -7.62 0)
				(effects
					(font
						(size 1.27 1.27)
						(thickness 0.15)
					)
					(justify left bottom)
				)
			)
			(property "Voltage" ""
				(at 20.32 -27.94 0)
				(effects
					(font
						(size 1.27 1.27)
					)
					(justify left bottom)
					(hide yes)
				)
			)
			(property "Dielectric" ""
				(at 20.32 -30.48 0)
				(effects
					(font
						(size 1.27 1.27)
					)
					(justify left bottom)
					(hide yes)
				)
			)
			(property "ki_keywords" "0402, SMT, CAPACITOR, PASSIVE, CERAMIC, MLCC"
				(at 0 0 0)
				(effects
					(font
						(size 1.27 1.27)
					)
					(hide yes)
				)
			)
			(symbol "C_1u_0402_0_1"
				(polyline
					(pts
						(xy 2.032 -1.524) (xy 2.032 1.524)
					)
					(stroke
						(width 0.3048)
						(type default)
					)
					(fill
						(type none)
					)
				)
				(polyline
					(pts
						(xy 3.048 -1.524) (xy 3.048 1.524)
					)
					(stroke
						(width 0.3302)
						(type default)
					)
					(fill
						(type none)
					)
				)
			)
			(symbol "C_1u_0402_1_1"
				(pin passive line
					(at 0 0 0)
					(length 2.032)
					(name "~"
						(effects
							(font
								(size 1.27 1.27)
							)
						)
					)
					(number "1"
						(effects
							(font
								(size 1.27 1.27)
							)
						)
					)
				)
				(pin passive line
					(at 5.08 0 180)
					(length 2.032)
					(name "~"
						(effects
							(font
								(size 1.27 1.27)
							)
						)
					)
					(number "2"
						(effects
							(font
								(size 1.27 1.27)
							)
						)
					)
				)
			)
		)
	(symbol "antmicroCapacitors0402:C_22n_0402"
			(pin_numbers
				(hide yes)
			)
			(pin_names
				(hide yes)
			)
			(exclude_from_sim no)
			(in_bom yes)
			(on_board yes)
			(property "Reference" "C"
				(at 20.32 -5.08 0)
				(effects
					(font
						(size 1.27 1.27)
						(thickness 0.15)
					)
					(justify left bottom)
				)
			)
			(property "Value" "C_22n_0402"
				(at 20.32 -10.16 0)
				(effects
					(font
						(size 1.27 1.27)
						(thickness 0.15)
					)
					(justify left bottom)
					(hide yes)
				)
			)
			(property "Footprint" "antmicro-footprints:C_0402_1005Metric"
				(at 20.32 -12.7 0)
				(effects
					(font
						(size 1.27 1.27)
						(thickness 0.15)
					)
					(justify left bottom)
					(hide yes)
				)
			)
			(property "Datasheet" "https://www.murata.com/products/productdetail?partno=GCM155R71H223MA55%23"
				(at 20.32 -15.24 0)
				(effects
					(font
						(size 1.27 1.27)
						(thickness 0.15)
					)
					(justify left bottom)
					(hide yes)
				)
			)
			(property "Description" "SMD Multilayer Ceramic Capacitors, 0.022 µF, 50 V, 20%, 0402 [1005 Metric], X7R"
				(at 0 0 0)
				(effects
					(font
						(size 1.27 1.27)
					)
					(hide yes)
				)
			)
			(property "MPN" "GCM155R71H223MA55D"
				(at 20.32 -17.78 0)
				(effects
					(font
						(size 1.27 1.27)
						(thickness 0.15)
					)
					(justify left bottom)
					(hide yes)
				)
			)
			(property "Manufacturer" "Murata"
				(at 20.32 -20.32 0)
				(effects
					(font
						(size 1.27 1.27)
						(thickness 0.15)
					)
					(justify left bottom)
					(hide yes)
				)
			)
			(property "License" "Apache-2.0"
				(at 20.32 -22.86 0)
				(effects
					(font
						(size 1.27 1.27)
						(thickness 0.15)
					)
					(justify left bottom)
					(hide yes)
				)
			)
			(property "Author" "Antmicro"
				(at 20.32 -25.4 0)
				(effects
					(font
						(size 1.27 1.27)
						(thickness 0.15)
					)
					(justify left bottom)
					(hide yes)
				)
			)
			(property "Val" "22n"
				(at 20.32 -7.62 0)
				(effects
					(font
						(size 1.27 1.27)
						(thickness 0.15)
					)
					(justify left bottom)
				)
			)
			(property "Voltage" ""
				(at 20.32 -27.94 0)
				(effects
					(font
						(size 1.27 1.27)
					)
					(justify left bottom)
					(hide yes)
				)
			)
			(property "Dielectric" ""
				(at 20.32 -30.48 0)
				(effects
					(font
						(size 1.27 1.27)
					)
					(justify left bottom)
					(hide yes)
				)
			)
			(property "ki_keywords" "0402, SMT, CAPACITOR, PASSIVE, CERAMIC, MLCC"
				(at 0 0 0)
				(effects
					(font
						(size 1.27 1.27)
					)
					(hide yes)
				)
			)
			(symbol "C_22n_0402_0_1"
				(polyline
					(pts
						(xy 2.032 -1.524) (xy 2.032 1.524)
					)
					(stroke
						(width 0.3048)
						(type default)
					)
					(fill
						(type none)
					)
				)
				(polyline
					(pts
						(xy 3.048 -1.524) (xy 3.048 1.524)
					)
					(stroke
						(width 0.3302)
						(type default)
					)
					(fill
						(type none)
					)
				)
			)
			(symbol "C_22n_0402_1_1"
				(pin passive line
					(at 0 0 0)
					(length 2.032)
					(name "~"
						(effects
							(font
								(size 1.27 1.27)
							)
						)
					)
					(number "1"
						(effects
							(font
								(size 1.27 1.27)
							)
						)
					)
				)
				(pin passive line
					(at 5.08 0 180)
					(length 2.032)
					(name "~"
						(effects
							(font
								(size 1.27 1.27)
							)
						)
					)
					(number "2"
						(effects
							(font
								(size 1.27 1.27)
							)
						)
					)
				)
			)
		)
	(symbol "antmicroCapacitors0402:C_22p_0402"
			(pin_numbers
				(hide yes)
			)
			(pin_names
				(hide yes)
			)
			(exclude_from_sim no)
			(in_bom yes)
			(on_board yes)
			(property "Reference" "C"
				(at 20.32 -5.08 0)
				(effects
					(font
						(size 1.27 1.27)
						(thickness 0.15)
					)
					(justify left bottom)
				)
			)
			(property "Value" "C_22p_0402"
				(at 20.32 -10.16 0)
				(effects
					(font
						(size 1.27 1.27)
						(thickness 0.15)
					)
					(justify left bottom)
					(hide yes)
				)
			)
			(property "Footprint" "antmicro-footprints:C_0402_1005Metric"
				(at 20.32 -12.7 0)
				(effects
					(font
						(size 1.27 1.27)
						(thickness 0.15)
					)
					(justify left bottom)
					(hide yes)
				)
			)
			(property "Datasheet" "https://www.yageo.com/en/Chart/Download/pdf/CC0402JRNPO9BN220"
				(at 20.32 -15.24 0)
				(effects
					(font
						(size 1.27 1.27)
						(thickness 0.15)
					)
					(justify left bottom)
					(hide yes)
				)
			)
			(property "Description" "SMD Multilayer Ceramic Capacitor, 22 pF, 50 V, 0402 [1005 Metric], ± 5%, C0G / NP0, CC Series"
				(at 0 0 0)
				(effects
					(font
						(size 1.27 1.27)
					)
					(hide yes)
				)
			)
			(property "MPN" "CC0402JRNPO9BN220"
				(at 20.32 -17.78 0)
				(effects
					(font
						(size 1.27 1.27)
						(thickness 0.15)
					)
					(justify left bottom)
					(hide yes)
				)
			)
			(property "Manufacturer" "YAGEO"
				(at 20.32 -20.32 0)
				(effects
					(font
						(size 1.27 1.27)
						(thickness 0.15)
					)
					(justify left bottom)
					(hide yes)
				)
			)
			(property "License" "Apache-2.0"
				(at 20.32 -22.86 0)
				(effects
					(font
						(size 1.27 1.27)
						(thickness 0.15)
					)
					(justify left bottom)
					(hide yes)
				)
			)
			(property "Author" "Antmicro"
				(at 20.32 -25.4 0)
				(effects
					(font
						(size 1.27 1.27)
						(thickness 0.15)
					)
					(justify left bottom)
					(hide yes)
				)
			)
			(property "Val" "22p"
				(at 20.32 -7.62 0)
				(effects
					(font
						(size 1.27 1.27)
						(thickness 0.15)
					)
					(justify left bottom)
				)
			)
			(property "Voltage" ""
				(at 20.32 -27.94 0)
				(effects
					(font
						(size 1.27 1.27)
					)
					(justify left bottom)
					(hide yes)
				)
			)
			(property "Dielectric" ""
				(at 20.32 -30.48 0)
				(effects
					(font
						(size 1.27 1.27)
					)
					(justify left bottom)
					(hide yes)
				)
			)
			(property "ki_keywords" "0402, SMT, CAPACITOR, PASSIVE, MLCC, CERAMIC"
				(at 0 0 0)
				(effects
					(font
						(size 1.27 1.27)
					)
					(hide yes)
				)
			)
			(symbol "C_22p_0402_0_1"
				(polyline
					(pts
						(xy 2.032 -1.524) (xy 2.032 1.524)
					)
					(stroke
						(width 0.3048)
						(type default)
					)
					(fill
						(type none)
					)
				)
				(polyline
					(pts
						(xy 3.048 -1.524) (xy 3.048 1.524)
					)
					(stroke
						(width 0.3302)
						(type default)
					)
					(fill
						(type none)
					)
				)
			)
			(symbol "C_22p_0402_1_1"
				(pin passive line
					(at 0 0 0)
					(length 2.032)
					(name "~"
						(effects
							(font
								(size 1.27 1.27)
							)
						)
					)
					(number "1"
						(effects
							(font
								(size 1.27 1.27)
							)
						)
					)
				)
				(pin passive line
					(at 5.08 0 180)
					(length 2.032)
					(name "~"
						(effects
							(font
								(size 1.27 1.27)
							)
						)
					)
					(number "2"
						(effects
							(font
								(size 1.27 1.27)
							)
						)
					)
				)
			)
		)
	(symbol "antmicroCapacitors0402:C_22u_0402"
			(pin_numbers
				(hide yes)
			)
			(pin_names
				(hide yes)
			)
			(exclude_from_sim no)
			(in_bom yes)
			(on_board yes)
			(property "Reference" "C"
				(at 20.32 -5.08 0)
				(effects
					(font
						(size 1.27 1.27)
						(thickness 0.15)
					)
					(justify left bottom)
				)
			)
			(property "Value" "C_22u_0402"
				(at 20.32 -10.16 0)
				(effects
					(font
						(size 1.27 1.27)
						(thickness 0.15)
					)
					(justify left bottom)
					(hide yes)
				)
			)
			(property "Footprint" "antmicro-footprints:C_0402_1005Metric"
				(at 20.32 -12.7 0)
				(effects
					(font
						(size 1.27 1.27)
						(thickness 0.15)
					)
					(justify left bottom)
					(hide yes)
				)
			)
			(property "Datasheet" "https://www.murata.com/products/productdetail?partno=GRM158R60J226ME01%23"
				(at 20.32 -15.24 0)
				(effects
					(font
						(size 1.27 1.27)
						(thickness 0.15)
					)
					(justify left bottom)
					(hide yes)
				)
			)
			(property "Description" "SMD Multilayer Ceramic Capacitor, 22 uF, 4 V, 0402 [1005 Metric], X6S"
				(at 0 0 0)
				(effects
					(font
						(size 1.27 1.27)
					)
					(hide yes)
				)
			)
			(property "MPN" "GRM158R60J226ME01D"
				(at 20.32 -17.78 0)
				(effects
					(font
						(size 1.27 1.27)
						(thickness 0.15)
					)
					(justify left bottom)
					(hide yes)
				)
			)
			(property "Manufacturer" "Murata"
				(at 20.32 -20.32 0)
				(effects
					(font
						(size 1.27 1.27)
						(thickness 0.15)
					)
					(justify left bottom)
					(hide yes)
				)
			)
			(property "License" "Apache-2.0"
				(at 20.32 -22.86 0)
				(effects
					(font
						(size 1.27 1.27)
						(thickness 0.15)
					)
					(justify left bottom)
					(hide yes)
				)
			)
			(property "Author" "Antmicro"
				(at 20.32 -25.4 0)
				(effects
					(font
						(size 1.27 1.27)
						(thickness 0.15)
					)
					(justify left bottom)
					(hide yes)
				)
			)
			(property "Val" "22u"
				(at 20.32 -7.62 0)
				(effects
					(font
						(size 1.27 1.27)
						(thickness 0.15)
					)
					(justify left bottom)
				)
			)
			(property "Voltage" ""
				(at 20.32 -27.94 0)
				(effects
					(font
						(size 1.27 1.27)
					)
					(justify left bottom)
					(hide yes)
				)
			)
			(property "Dielectric" ""
				(at 20.32 -30.48 0)
				(effects
					(font
						(size 1.27 1.27)
					)
					(justify left bottom)
					(hide yes)
				)
			)
			(property "ki_keywords" "1210, SMT, CAPACITOR, PASSIVE, CERAMIC, MLCC"
				(at 0 0 0)
				(effects
					(font
						(size 1.27 1.27)
					)
					(hide yes)
				)
			)
			(symbol "C_22u_0402_0_1"
				(polyline
					(pts
						(xy 2.032 -1.524) (xy 2.032 1.524)
					)
					(stroke
						(width 0.3048)
						(type default)
					)
					(fill
						(type none)
					)
				)
				(polyline
					(pts
						(xy 3.048 -1.524) (xy 3.048 1.524)
					)
					(stroke
						(width 0.3302)
						(type default)
					)
					(fill
						(type none)
					)
				)
			)
			(symbol "C_22u_0402_1_1"
				(pin passive line
					(at 0 0 0)
					(length 2.032)
					(name "~"
						(effects
							(font
								(size 1.27 1.27)
							)
						)
					)
					(number "1"
						(effects
							(font
								(size 1.27 1.27)
							)
						)
					)
				)
				(pin passive line
					(at 5.08 0 180)
					(length 2.032)
					(name "~"
						(effects
							(font
								(size 1.27 1.27)
							)
						)
					)
					(number "2"
						(effects
							(font
								(size 1.27 1.27)
							)
						)
					)
				)
			)
		)
	(symbol "antmicroCapacitors0402:C_3n3_0402"
			(pin_numbers
				(hide yes)
			)
			(pin_names
				(hide yes)
			)
			(exclude_from_sim no)
			(in_bom yes)
			(on_board yes)
			(property "Reference" "C"
				(at 20.32 -5.08 0)
				(effects
					(font
						(size 1.27 1.27)
						(thickness 0.15)
					)
					(justify left bottom)
				)
			)
			(property "Value" "C_3n3_0402"
				(at 20.32 -10.16 0)
				(effects
					(font
						(size 1.27 1.27)
						(thickness 0.15)
					)
					(justify left bottom)
					(hide yes)
				)
			)
			(property "Footprint" "antmicro-footprints:C_0402_1005Metric"
				(at 20.32 -12.7 0)
				(effects
					(font
						(size 1.27 1.27)
						(thickness 0.15)
					)
					(justify left bottom)
					(hide yes)
				)
			)
			(property "Datasheet" "https://www.kemet.com/en/us/capacitors/product/C0402C332K5RAC.html"
				(at 20.32 -15.24 0)
				(effects
					(font
						(size 1.27 1.27)
						(thickness 0.15)
					)
					(justify left bottom)
					(hide yes)
				)
			)
			(property "Description" "SMD Multilayer Ceramic Capacitor, 3300 pF, 50 V, 0402 [1005 Metric], ± 10%, X7R, MC"
				(at 0 0 0)
				(effects
					(font
						(size 1.27 1.27)
					)
					(hide yes)
				)
			)
			(property "MPN" "C0402C332K5RAC"
				(at 20.32 -17.78 0)
				(effects
					(font
						(size 1.27 1.27)
						(thickness 0.15)
					)
					(justify left bottom)
					(hide yes)
				)
			)
			(property "Manufacturer" "KEMET"
				(at 20.32 -20.32 0)
				(effects
					(font
						(size 1.27 1.27)
						(thickness 0.15)
					)
					(justify left bottom)
					(hide yes)
				)
			)
			(property "License" "Apache-2.0"
				(at 20.32 -22.86 0)
				(effects
					(font
						(size 1.27 1.27)
						(thickness 0.15)
					)
					(justify left bottom)
					(hide yes)
				)
			)
			(property "Author" "Antmicro"
				(at 20.32 -25.4 0)
				(effects
					(font
						(size 1.27 1.27)
						(thickness 0.15)
					)
					(justify left bottom)
					(hide yes)
				)
			)
			(property "Val" "3n3"
				(at 20.32 -7.62 0)
				(effects
					(font
						(size 1.27 1.27)
						(thickness 0.15)
					)
					(justify left bottom)
				)
			)
			(property "Voltage" "50V"
				(at 20.32 -27.94 0)
				(effects
					(font
						(size 1.27 1.27)
					)
					(justify left bottom)
					(hide yes)
				)
			)
			(property "Dielectric" "X7R"
				(at 20.32 -30.48 0)
				(effects
					(font
						(size 1.27 1.27)
					)
					(justify left bottom)
					(hide yes)
				)
			)
			(property "ki_keywords" "0402, SMT, CAPACITOR, PASSIVE"
				(at 0 0 0)
				(effects
					(font
						(size 1.27 1.27)
					)
					(hide yes)
				)
			)
			(symbol "C_3n3_0402_0_1"
				(polyline
					(pts
						(xy 2.032 -1.524) (xy 2.032 1.524)
					)
					(stroke
						(width 0.3048)
						(type default)
					)
					(fill
						(type none)
					)
				)
				(polyline
					(pts
						(xy 3.048 -1.524) (xy 3.048 1.524)
					)
					(stroke
						(width 0.3302)
						(type default)
					)
					(fill
						(type none)
					)
				)
			)
			(symbol "C_3n3_0402_1_1"
				(pin passive line
					(at 0 0 0)
					(length 2.032)
					(name "~"
						(effects
							(font
								(size 1.27 1.27)
							)
						)
					)
					(number "1"
						(effects
							(font
								(size 1.27 1.27)
							)
						)
					)
				)
				(pin passive line
					(at 5.08 0 180)
					(length 2.032)
					(name "~"
						(effects
							(font
								(size 1.27 1.27)
							)
						)
					)
					(number "2"
						(effects
							(font
								(size 1.27 1.27)
							)
						)
					)
				)
			)
		)
	(symbol "antmicroCapacitors0402:C_470n_0402"
			(pin_numbers
				(hide yes)
			)
			(pin_names
				(hide yes)
			)
			(exclude_from_sim no)
			(in_bom yes)
			(on_board yes)
			(property "Reference" "C"
				(at 20.32 -5.08 0)
				(effects
					(font
						(size 1.27 1.27)
						(thickness 0.15)
					)
					(justify left bottom)
				)
			)
			(property "Value" "C_470n_0402"
				(at 20.32 -10.16 0)
				(effects
					(font
						(size 1.27 1.27)
						(thickness 0.15)
					)
					(justify left bottom)
					(hide yes)
				)
			)
			(property "Footprint" "antmicro-footprints:C_0402_1005Metric"
				(at 20.32 -12.7 0)
				(effects
					(font
						(size 1.27 1.27)
						(thickness 0.15)
					)
					(justify left bottom)
					(hide yes)
				)
			)
			(property "Datasheet" "https://product.tdk.com/en/search/capacitor/ceramic/mlcc/info?part_no=C1005X5R1E474M050BB"
				(at 20.32 -15.24 0)
				(effects
					(font
						(size 1.27 1.27)
						(thickness 0.15)
					)
					(justify left bottom)
					(hide yes)
				)
			)
			(property "Description" "SMD Multilayer Ceramic Capacitor, 0.47 µF, 25 V, 0402 [1005 Metric], ± 20%, X5R, C"
				(at 0 0 0)
				(effects
					(font
						(size 1.27 1.27)
					)
					(hide yes)
				)
			)
			(property "MPN" "C1005X5R1E474M050BB"
				(at 20.32 -17.78 0)
				(effects
					(font
						(size 1.27 1.27)
						(thickness 0.15)
					)
					(justify left bottom)
					(hide yes)
				)
			)
			(property "Manufacturer" "TDK"
				(at 20.32 -20.32 0)
				(effects
					(font
						(size 1.27 1.27)
						(thickness 0.15)
					)
					(justify left bottom)
					(hide yes)
				)
			)
			(property "License" "Apache-2.0"
				(at 20.32 -22.86 0)
				(effects
					(font
						(size 1.27 1.27)
						(thickness 0.15)
					)
					(justify left bottom)
					(hide yes)
				)
			)
			(property "Author" "Antmicro"
				(at 20.32 -25.4 0)
				(effects
					(font
						(size 1.27 1.27)
						(thickness 0.15)
					)
					(justify left bottom)
					(hide yes)
				)
			)
			(property "Val" "470n"
				(at 20.32 -7.62 0)
				(effects
					(font
						(size 1.27 1.27)
						(thickness 0.15)
					)
					(justify left bottom)
				)
			)
			(property "Voltage" ""
				(at 20.32 -27.94 0)
				(effects
					(font
						(size 1.27 1.27)
					)
					(justify left bottom)
					(hide yes)
				)
			)
			(property "Dielectric" ""
				(at 20.32 -30.48 0)
				(effects
					(font
						(size 1.27 1.27)
					)
					(justify left bottom)
					(hide yes)
				)
			)
			(property "ki_keywords" "0402, SMT, CAPACITOR, PASSIVE, CERAMIC, MLCC"
				(at 0 0 0)
				(effects
					(font
						(size 1.27 1.27)
					)
					(hide yes)
				)
			)
			(symbol "C_470n_0402_0_1"
				(polyline
					(pts
						(xy 2.032 -1.524) (xy 2.032 1.524)
					)
					(stroke
						(width 0.3048)
						(type default)
					)
					(fill
						(type none)
					)
				)
				(polyline
					(pts
						(xy 3.048 -1.524) (xy 3.048 1.524)
					)
					(stroke
						(width 0.3302)
						(type default)
					)
					(fill
						(type none)
					)
				)
			)
			(symbol "C_470n_0402_1_1"
				(pin passive line
					(at 0 0 0)
					(length 2.032)
					(name "~"
						(effects
							(font
								(size 1.27 1.27)
							)
						)
					)
					(number "1"
						(effects
							(font
								(size 1.27 1.27)
							)
						)
					)
				)
				(pin passive line
					(at 5.08 0 180)
					(length 2.032)
					(name "~"
						(effects
							(font
								(size 1.27 1.27)
							)
						)
					)
					(number "2"
						(effects
							(font
								(size 1.27 1.27)
							)
						)
					)
				)
			)
		)
	(symbol "antmicroCapacitors0402:C_47n_0402"
			(pin_numbers
				(hide yes)
			)
			(pin_names
				(hide yes)
			)
			(exclude_from_sim no)
			(in_bom yes)
			(on_board yes)
			(property "Reference" "C"
				(at 20.32 -5.08 0)
				(effects
					(font
						(size 1.27 1.27)
						(thickness 0.15)
					)
					(justify left bottom)
				)
			)
			(property "Value" "C_47n_0402"
				(at 20.32 -10.16 0)
				(effects
					(font
						(size 1.27 1.27)
						(thickness 0.15)
					)
					(justify left bottom)
					(hide yes)
				)
			)
			(property "Footprint" "antmicro-footprints:C_0402_1005Metric"
				(at 20.32 -12.7 0)
				(effects
					(font
						(size 1.27 1.27)
						(thickness 0.15)
					)
					(justify left bottom)
					(hide yes)
				)
			)
			(property "Datasheet" "https://www.murata.com/en-us/products/productdetail?partno=GRM155R61C473KA01%23"
				(at 20.32 -15.24 0)
				(effects
					(font
						(size 1.27 1.27)
						(thickness 0.15)
					)
					(justify left bottom)
					(hide yes)
				)
			)
			(property "Description" "SMD Multilayer Ceramic Capacitor, 47000 pF, 16 V, 0402 [1005 Metric], ± 10%, X5R, MC"
				(at 0 0 0)
				(effects
					(font
						(size 1.27 1.27)
					)
					(hide yes)
				)
			)
			(property "MPN" "GRM155R61C473KA01D"
				(at 20.32 -17.78 0)
				(effects
					(font
						(size 1.27 1.27)
						(thickness 0.15)
					)
					(justify left bottom)
					(hide yes)
				)
			)
			(property "Manufacturer" "Murata"
				(at 20.32 -20.32 0)
				(effects
					(font
						(size 1.27 1.27)
						(thickness 0.15)
					)
					(justify left bottom)
					(hide yes)
				)
			)
			(property "License" "Apache-2.0"
				(at 20.32 -22.86 0)
				(effects
					(font
						(size 1.27 1.27)
						(thickness 0.15)
					)
					(justify left bottom)
					(hide yes)
				)
			)
			(property "Author" "Antmicro"
				(at 20.32 -25.4 0)
				(effects
					(font
						(size 1.27 1.27)
						(thickness 0.15)
					)
					(justify left bottom)
					(hide yes)
				)
			)
			(property "Val" "47n"
				(at 20.32 -7.62 0)
				(effects
					(font
						(size 1.27 1.27)
						(thickness 0.15)
					)
					(justify left bottom)
				)
			)
			(property "Voltage" ""
				(at 20.32 -27.94 0)
				(effects
					(font
						(size 1.27 1.27)
					)
					(justify left bottom)
					(hide yes)
				)
			)
			(property "Dielectric" ""
				(at 20.32 -30.48 0)
				(effects
					(font
						(size 1.27 1.27)
					)
					(justify left bottom)
					(hide yes)
				)
			)
			(property "ki_keywords" "0402, SMT, CAPACITOR, PASSIVE"
				(at 0 0 0)
				(effects
					(font
						(size 1.27 1.27)
					)
					(hide yes)
				)
			)
			(symbol "C_47n_0402_0_1"
				(polyline
					(pts
						(xy 2.032 -1.524) (xy 2.032 1.524)
					)
					(stroke
						(width 0.3048)
						(type default)
					)
					(fill
						(type none)
					)
				)
				(polyline
					(pts
						(xy 3.048 -1.524) (xy 3.048 1.524)
					)
					(stroke
						(width 0.3302)
						(type default)
					)
					(fill
						(type none)
					)
				)
			)
			(symbol "C_47n_0402_1_1"
				(pin passive line
					(at 0 0 0)
					(length 2.032)
					(name "~"
						(effects
							(font
								(size 1.27 1.27)
							)
						)
					)
					(number "1"
						(effects
							(font
								(size 1.27 1.27)
							)
						)
					)
				)
				(pin passive line
					(at 5.08 0 180)
					(length 2.032)
					(name "~"
						(effects
							(font
								(size 1.27 1.27)
							)
						)
					)
					(number "2"
						(effects
							(font
								(size 1.27 1.27)
							)
						)
					)
				)
			)
		)
	(symbol "antmicroCapacitors0402:C_4n7_0402"
			(pin_numbers
				(hide yes)
			)
			(pin_names
				(hide yes)
			)
			(exclude_from_sim no)
			(in_bom yes)
			(on_board yes)
			(property "Reference" "C"
				(at 20.32 -5.08 0)
				(effects
					(font
						(size 1.27 1.27)
						(thickness 0.15)
					)
					(justify left bottom)
				)
			)
			(property "Value" "C_4n7_0402"
				(at 20.32 -10.16 0)
				(effects
					(font
						(size 1.27 1.27)
						(thickness 0.15)
					)
					(justify left bottom)
					(hide yes)
				)
			)
			(property "Footprint" "antmicro-footprints:C_0402_1005Metric"
				(at 20.32 -12.7 0)
				(effects
					(font
						(size 1.27 1.27)
						(thickness 0.15)
					)
					(justify left bottom)
					(hide yes)
				)
			)
			(property "Datasheet" "https://product.tdk.com/en/search/capacitor/ceramic/mlcc/info?part_no=CGA2B3X7S2A472K050BB"
				(at 20.32 -15.24 0)
				(effects
					(font
						(size 1.27 1.27)
						(thickness 0.15)
					)
					(justify left bottom)
					(hide yes)
				)
			)
			(property "Description" "SMD Multilayer Ceramic Capacitor, 4700 pF, 100 V, 0402 [1005 Metric], ± 10%, X7S, CGA"
				(at 0 0 0)
				(effects
					(font
						(size 1.27 1.27)
					)
					(hide yes)
				)
			)
			(property "MPN" "CGA2B3X7S2A472K050BB"
				(at 20.32 -17.78 0)
				(effects
					(font
						(size 1.27 1.27)
						(thickness 0.15)
					)
					(justify left bottom)
					(hide yes)
				)
			)
			(property "Manufacturer" "TDK"
				(at 20.32 -20.32 0)
				(effects
					(font
						(size 1.27 1.27)
						(thickness 0.15)
					)
					(justify left bottom)
					(hide yes)
				)
			)
			(property "License" "Apache-2.0"
				(at 20.32 -22.86 0)
				(effects
					(font
						(size 1.27 1.27)
						(thickness 0.15)
					)
					(justify left bottom)
					(hide yes)
				)
			)
			(property "Author" "Antmicro"
				(at 20.32 -25.4 0)
				(effects
					(font
						(size 1.27 1.27)
						(thickness 0.15)
					)
					(justify left bottom)
					(hide yes)
				)
			)
			(property "Val" "4n7"
				(at 20.32 -7.62 0)
				(effects
					(font
						(size 1.27 1.27)
						(thickness 0.15)
					)
					(justify left bottom)
				)
			)
			(property "Voltage" ""
				(at 20.32 -27.94 0)
				(effects
					(font
						(size 1.27 1.27)
					)
					(justify left bottom)
					(hide yes)
				)
			)
			(property "Dielectric" ""
				(at 20.32 -30.48 0)
				(effects
					(font
						(size 1.27 1.27)
					)
					(justify left bottom)
					(hide yes)
				)
			)
			(property "ki_keywords" "0402, SMT, CAPACITOR, PASSIVE, CERAMIC, MLCC"
				(at 0 0 0)
				(effects
					(font
						(size 1.27 1.27)
					)
					(hide yes)
				)
			)
			(symbol "C_4n7_0402_0_1"
				(polyline
					(pts
						(xy 2.032 -1.524) (xy 2.032 1.524)
					)
					(stroke
						(width 0.3048)
						(type default)
					)
					(fill
						(type none)
					)
				)
				(polyline
					(pts
						(xy 3.048 -1.524) (xy 3.048 1.524)
					)
					(stroke
						(width 0.3302)
						(type default)
					)
					(fill
						(type none)
					)
				)
			)
			(symbol "C_4n7_0402_1_1"
				(pin passive line
					(at 0 0 0)
					(length 2.032)
					(name "~"
						(effects
							(font
								(size 1.27 1.27)
							)
						)
					)
					(number "1"
						(effects
							(font
								(size 1.27 1.27)
							)
						)
					)
				)
				(pin passive line
					(at 5.08 0 180)
					(length 2.032)
					(name "~"
						(effects
							(font
								(size 1.27 1.27)
							)
						)
					)
					(number "2"
						(effects
							(font
								(size 1.27 1.27)
							)
						)
					)
				)
			)
		)
	(symbol "antmicroCapacitors0402:C_4u7_0402"
			(pin_numbers
				(hide yes)
			)
			(pin_names
				(hide yes)
			)
			(exclude_from_sim no)
			(in_bom yes)
			(on_board yes)
			(property "Reference" "C"
				(at 20.32 -5.08 0)
				(effects
					(font
						(size 1.27 1.27)
						(thickness 0.15)
					)
					(justify left bottom)
				)
			)
			(property "Value" "C_4u7_0402"
				(at 20.32 -10.16 0)
				(effects
					(font
						(size 1.27 1.27)
						(thickness 0.15)
					)
					(justify left bottom)
					(hide yes)
				)
			)
			(property "Footprint" "antmicro-footprints:C_0402_1005Metric"
				(at 20.32 -12.7 0)
				(effects
					(font
						(size 1.27 1.27)
						(thickness 0.15)
					)
					(justify left bottom)
					(hide yes)
				)
			)
			(property "Datasheet" "https://www.murata.com/products/productdetail?partno=GRM155R61A475MEAA%23"
				(at 20.32 -15.24 0)
				(effects
					(font
						(size 1.27 1.27)
						(thickness 0.15)
					)
					(justify left bottom)
					(hide yes)
				)
			)
			(property "Description" "SMD Multilayer Ceramic Capacitor, 4.7 µF, 10 V, 0402 [1005 Metric], ± 20%, X5R, GRM Series"
				(at 0 0 0)
				(effects
					(font
						(size 1.27 1.27)
					)
					(hide yes)
				)
			)
			(property "MPN" "GRM155R61A475MEAAD"
				(at 20.32 -17.78 0)
				(effects
					(font
						(size 1.27 1.27)
						(thickness 0.15)
					)
					(justify left bottom)
					(hide yes)
				)
			)
			(property "Manufacturer" "Murata"
				(at 20.32 -20.32 0)
				(effects
					(font
						(size 1.27 1.27)
						(thickness 0.15)
					)
					(justify left bottom)
					(hide yes)
				)
			)
			(property "License" "Apache-2.0"
				(at 20.32 -22.86 0)
				(effects
					(font
						(size 1.27 1.27)
						(thickness 0.15)
					)
					(justify left bottom)
					(hide yes)
				)
			)
			(property "Author" "Antmicro"
				(at 20.32 -25.4 0)
				(effects
					(font
						(size 1.27 1.27)
						(thickness 0.15)
					)
					(justify left bottom)
					(hide yes)
				)
			)
			(property "Val" "4u7"
				(at 20.32 -7.62 0)
				(effects
					(font
						(size 1.27 1.27)
						(thickness 0.15)
					)
					(justify left bottom)
				)
			)
			(property "Voltage" ""
				(at 20.32 -27.94 0)
				(effects
					(font
						(size 1.27 1.27)
					)
					(justify left bottom)
					(hide yes)
				)
			)
			(property "Dielectric" ""
				(at 20.32 -30.48 0)
				(effects
					(font
						(size 1.27 1.27)
					)
					(justify left bottom)
					(hide yes)
				)
			)
			(property "ki_keywords" "0402, SMT, CAPACITOR, PASSIVE"
				(at 0 0 0)
				(effects
					(font
						(size 1.27 1.27)
					)
					(hide yes)
				)
			)
			(symbol "C_4u7_0402_0_1"
				(polyline
					(pts
						(xy 2.032 -1.524) (xy 2.032 1.524)
					)
					(stroke
						(width 0.3048)
						(type default)
					)
					(fill
						(type none)
					)
				)
				(polyline
					(pts
						(xy 3.048 -1.524) (xy 3.048 1.524)
					)
					(stroke
						(width 0.3302)
						(type default)
					)
					(fill
						(type none)
					)
				)
			)
			(symbol "C_4u7_0402_1_1"
				(pin passive line
					(at 0 0 0)
					(length 2.032)
					(name "~"
						(effects
							(font
								(size 1.27 1.27)
							)
						)
					)
					(number "1"
						(effects
							(font
								(size 1.27 1.27)
							)
						)
					)
				)
				(pin passive line
					(at 5.08 0 180)
					(length 2.032)
					(name "~"
						(effects
							(font
								(size 1.27 1.27)
							)
						)
					)
					(number "2"
						(effects
							(font
								(size 1.27 1.27)
							)
						)
					)
				)
			)
		)
	(symbol "antmicroCapacitors0603:C_47u_0603"
			(pin_numbers
				(hide yes)
			)
			(pin_names
				(hide yes)
			)
			(exclude_from_sim no)
			(in_bom yes)
			(on_board yes)
			(property "Reference" "C"
				(at 20.32 -5.08 0)
				(effects
					(font
						(size 1.27 1.27)
						(thickness 0.15)
					)
					(justify left bottom)
				)
			)
			(property "Value" "C_47u_0603"
				(at 20.32 -10.16 0)
				(effects
					(font
						(size 1.27 1.27)
						(thickness 0.15)
					)
					(justify left bottom)
					(hide yes)
				)
			)
			(property "Footprint" "antmicro-footprints:C_0603_1608Metric"
				(at 20.32 -12.7 0)
				(effects
					(font
						(size 1.27 1.27)
						(thickness 0.15)
					)
					(justify left bottom)
					(hide yes)
				)
			)
			(property "Datasheet" "https://www.murata.com/products/productdetail?partno=GRM188R60J476ME15%23"
				(at 20.32 -15.24 0)
				(effects
					(font
						(size 1.27 1.27)
						(thickness 0.15)
					)
					(justify left bottom)
					(hide yes)
				)
			)
			(property "Description" "SMD Multilayer Ceramic Capacitor, 47 µF, 6.3 V, 0603 [1608 Metric], ± 20%, X5R, GRM Series"
				(at 0 0 0)
				(effects
					(font
						(size 1.27 1.27)
					)
					(hide yes)
				)
			)
			(property "MPN" "GRM188R60J476ME15D"
				(at 20.32 -17.78 0)
				(effects
					(font
						(size 1.27 1.27)
						(thickness 0.15)
					)
					(justify left bottom)
					(hide yes)
				)
			)
			(property "Manufacturer" "Murata"
				(at 20.32 -20.32 0)
				(effects
					(font
						(size 1.27 1.27)
						(thickness 0.15)
					)
					(justify left bottom)
					(hide yes)
				)
			)
			(property "License" "Apache-2.0"
				(at 20.32 -22.86 0)
				(effects
					(font
						(size 1.27 1.27)
						(thickness 0.15)
					)
					(justify left bottom)
					(hide yes)
				)
			)
			(property "Author" "Antmicro"
				(at 20.32 -25.4 0)
				(effects
					(font
						(size 1.27 1.27)
						(thickness 0.15)
					)
					(justify left bottom)
					(hide yes)
				)
			)
			(property "Val" "47u"
				(at 20.32 -7.62 0)
				(effects
					(font
						(size 1.27 1.27)
						(thickness 0.15)
					)
					(justify left bottom)
				)
			)
			(property "Voltage" ""
				(at 20.32 -27.94 0)
				(effects
					(font
						(size 1.27 1.27)
					)
					(justify left bottom)
					(hide yes)
				)
			)
			(property "Dielectric" ""
				(at 20.32 -30.48 0)
				(effects
					(font
						(size 1.27 1.27)
					)
					(justify left bottom)
					(hide yes)
				)
			)
			(property "ki_keywords" "0603, SMT, CAPACITOR, PASSIVE, CERAMIC, MLCC"
				(at 0 0 0)
				(effects
					(font
						(size 1.27 1.27)
					)
					(hide yes)
				)
			)
			(symbol "C_47u_0603_0_1"
				(polyline
					(pts
						(xy 2.032 -1.524) (xy 2.032 1.524)
					)
					(stroke
						(width 0.3048)
						(type default)
					)
					(fill
						(type none)
					)
				)
				(polyline
					(pts
						(xy 3.048 -1.524) (xy 3.048 1.524)
					)
					(stroke
						(width 0.3302)
						(type default)
					)
					(fill
						(type none)
					)
				)
			)
			(symbol "C_47u_0603_1_1"
				(pin passive line
					(at 0 0 0)
					(length 2.032)
					(name "~"
						(effects
							(font
								(size 1.27 1.27)
							)
						)
					)
					(number "1"
						(effects
							(font
								(size 1.27 1.27)
							)
						)
					)
				)
				(pin passive line
					(at 5.08 0 180)
					(length 2.032)
					(name "~"
						(effects
							(font
								(size 1.27 1.27)
							)
						)
					)
					(number "2"
						(effects
							(font
								(size 1.27 1.27)
							)
						)
					)
				)
			)
		)
	(symbol "antmicroCapacitorsmisc:C_4x100nF_0508_1220Metric_array"
			(pin_names
				(hide yes)
			)
			(exclude_from_sim no)
			(in_bom yes)
			(on_board yes)
			(property "Reference" "C"
				(at 15.24 -1.27 0)
				(effects
					(font
						(size 1.27 1.27)
						(thickness 0.15)
					)
					(justify left bottom)
				)
			)
			(property "Value" "C_4x100nF_0508_1220Metric_array"
				(at 15.24 -8.89 0)
				(effects
					(font
						(size 1.27 1.27)
						(thickness 0.15)
					)
					(justify left bottom)
					(hide yes)
				)
			)
			(property "Footprint" "antmicro-footprints:C_Array_0508_1220Metric"
				(at 15.24 -11.43 0)
				(effects
					(font
						(size 1.27 1.27)
						(thickness 0.15)
					)
					(justify left bottom)
					(hide yes)
				)
			)
			(property "Datasheet" "https://spicat.kyocera-avx.com/product/mlcc/chartview/W2A4YC104MAT2A/"
				(at 15.24 -13.97 0)
				(effects
					(font
						(size 1.27 1.27)
						(thickness 0.15)
					)
					(justify left bottom)
					(hide yes)
				)
			)
			(property "Description" "4x0.1µF isolated capacitor array 16 V X7R 0508 (1220 Metric)"
				(at 0 0 0)
				(effects
					(font
						(size 1.27 1.27)
					)
					(hide yes)
				)
			)
			(property "MPN" "W2A4YC104MAT2A"
				(at 15.24 -6.35 0)
				(effects
					(font
						(size 1.27 1.27)
						(thickness 0.15)
					)
					(justify left bottom)
					(hide yes)
				)
			)
			(property "Manufacturer" "KYOCERA AVX"
				(at 15.24 -16.51 0)
				(effects
					(font
						(size 1.27 1.27)
						(thickness 0.15)
					)
					(justify left bottom)
					(hide yes)
				)
			)
			(property "Author" "Antmicro"
				(at 15.24 -19.05 0)
				(effects
					(font
						(size 1.27 1.27)
						(thickness 0.15)
					)
					(justify left bottom)
					(hide yes)
				)
			)
			(property "License" "Apache-2.0"
				(at 15.24 -21.59 0)
				(effects
					(font
						(size 1.27 1.27)
						(thickness 0.15)
					)
					(justify left bottom)
					(hide yes)
				)
			)
			(property "Val" "4x100nF"
				(at 15.24 -3.81 0)
				(effects
					(font
						(size 1.27 1.27)
						(thickness 0.15)
					)
					(justify left bottom)
				)
			)
			(property "Voltage" "16V"
				(at 15.24 -26.67 0)
				(effects
					(font
						(size 1.27 1.27)
					)
					(justify left bottom)
					(hide yes)
				)
			)
			(property "Dielectric" "X7R"
				(at 15.24 -24.13 0)
				(effects
					(font
						(size 1.27 1.27)
					)
					(justify left bottom)
					(hide yes)
				)
			)
			(property "ki_keywords" "SMT, CAPACITOR, PASSIVE, ARRAY"
				(at 0 0 0)
				(effects
					(font
						(size 1.27 1.27)
					)
					(hide yes)
				)
			)
			(symbol "C_4x100nF_0508_1220Metric_array_0_1"
				(rectangle
					(start 2.54 1.27)
					(end 6.35 -8.89)
					(stroke
						(width 0.254)
						(type default)
					)
					(fill
						(type background)
					)
				)
				(polyline
					(pts
						(xy 4.064 0.762) (xy 4.064 -0.762)
					)
					(stroke
						(width 0)
						(type default)
					)
					(fill
						(type none)
					)
				)
				(polyline
					(pts
						(xy 4.064 0) (xy 2.54 0)
					)
					(stroke
						(width 0)
						(type default)
					)
					(fill
						(type none)
					)
				)
				(polyline
					(pts
						(xy 4.064 -1.778) (xy 4.064 -3.302)
					)
					(stroke
						(width 0)
						(type default)
					)
					(fill
						(type none)
					)
				)
				(polyline
					(pts
						(xy 4.064 -2.54) (xy 2.54 -2.54)
					)
					(stroke
						(width 0)
						(type default)
					)
					(fill
						(type none)
					)
				)
				(polyline
					(pts
						(xy 4.064 -4.318) (xy 4.064 -5.842)
					)
					(stroke
						(width 0)
						(type default)
					)
					(fill
						(type none)
					)
				)
				(polyline
					(pts
						(xy 4.064 -5.08) (xy 2.54 -5.08)
					)
					(stroke
						(width 0)
						(type default)
					)
					(fill
						(type none)
					)
				)
				(polyline
					(pts
						(xy 4.064 -6.858) (xy 4.064 -8.382)
					)
					(stroke
						(width 0)
						(type default)
					)
					(fill
						(type none)
					)
				)
				(polyline
					(pts
						(xy 4.064 -7.62) (xy 2.54 -7.62)
					)
					(stroke
						(width 0)
						(type default)
					)
					(fill
						(type none)
					)
				)
				(polyline
					(pts
						(xy 4.826 0.762) (xy 4.826 -0.762)
					)
					(stroke
						(width 0)
						(type default)
					)
					(fill
						(type none)
					)
				)
				(polyline
					(pts
						(xy 4.826 0) (xy 6.35 0)
					)
					(stroke
						(width 0)
						(type default)
					)
					(fill
						(type none)
					)
				)
				(polyline
					(pts
						(xy 4.826 -1.778) (xy 4.826 -3.302)
					)
					(stroke
						(width 0)
						(type default)
					)
					(fill
						(type none)
					)
				)
				(polyline
					(pts
						(xy 4.826 -2.54) (xy 6.35 -2.54)
					)
					(stroke
						(width 0)
						(type default)
					)
					(fill
						(type none)
					)
				)
				(polyline
					(pts
						(xy 4.826 -4.318) (xy 4.826 -5.842)
					)
					(stroke
						(width 0)
						(type default)
					)
					(fill
						(type none)
					)
				)
				(polyline
					(pts
						(xy 4.826 -5.08) (xy 6.35 -5.08)
					)
					(stroke
						(width 0)
						(type default)
					)
					(fill
						(type none)
					)
				)
				(polyline
					(pts
						(xy 4.826 -6.858) (xy 4.826 -8.382)
					)
					(stroke
						(width 0)
						(type default)
					)
					(fill
						(type none)
					)
				)
				(polyline
					(pts
						(xy 4.826 -7.62) (xy 6.35 -7.62)
					)
					(stroke
						(width 0)
						(type default)
					)
					(fill
						(type none)
					)
				)
			)
			(symbol "C_4x100nF_0508_1220Metric_array_1_1"
				(pin passive line
					(at 0 0 0)
					(length 2.54)
					(name "R1.1"
						(effects
							(font
								(size 1.27 1.27)
							)
						)
					)
					(number "1"
						(effects
							(font
								(size 1.27 1.27)
							)
						)
					)
				)
				(pin passive line
					(at 0 -2.54 0)
					(length 2.54)
					(name "R2.1"
						(effects
							(font
								(size 1.27 1.27)
							)
						)
					)
					(number "2"
						(effects
							(font
								(size 1.27 1.27)
							)
						)
					)
				)
				(pin passive line
					(at 0 -5.08 0)
					(length 2.54)
					(name "R3.1"
						(effects
							(font
								(size 1.27 1.27)
							)
						)
					)
					(number "3"
						(effects
							(font
								(size 1.27 1.27)
							)
						)
					)
				)
				(pin passive line
					(at 0 -7.62 0)
					(length 2.54)
					(name "R4.1"
						(effects
							(font
								(size 1.27 1.27)
							)
						)
					)
					(number "4"
						(effects
							(font
								(size 1.27 1.27)
							)
						)
					)
				)
				(pin passive line
					(at 8.89 0 180)
					(length 2.54)
					(name "R1.2"
						(effects
							(font
								(size 1.27 1.27)
							)
						)
					)
					(number "8"
						(effects
							(font
								(size 1.27 1.27)
							)
						)
					)
				)
				(pin passive line
					(at 8.89 -2.54 180)
					(length 2.54)
					(name "R2.2"
						(effects
							(font
								(size 1.27 1.27)
							)
						)
					)
					(number "7"
						(effects
							(font
								(size 1.27 1.27)
							)
						)
					)
				)
				(pin passive line
					(at 8.89 -5.08 180)
					(length 2.54)
					(name "R3.2"
						(effects
							(font
								(size 1.27 1.27)
							)
						)
					)
					(number "6"
						(effects
							(font
								(size 1.27 1.27)
							)
						)
					)
				)
				(pin passive line
					(at 8.89 -7.62 180)
					(length 2.54)
					(name "R4.2"
						(effects
							(font
								(size 1.27 1.27)
							)
						)
					)
					(number "5"
						(effects
							(font
								(size 1.27 1.27)
							)
						)
					)
				)
			)
		)
	(symbol "antmicroCapacitorspol:C_Pol_330u_6.3V_KEMET-T520-B"
			(pin_numbers
				(hide yes)
			)
			(pin_names
				(hide yes)
			)
			(exclude_from_sim no)
			(in_bom yes)
			(on_board yes)
			(property "Reference" "C"
				(at 13.97 0 0)
				(effects
					(font
						(size 1.27 1.27)
						(thickness 0.15)
					)
					(justify left bottom)
				)
			)
			(property "Value" "C_Pol_330u_6.3V_KEMET-T520-B"
				(at 13.97 -2.54 0)
				(effects
					(font
						(size 1.27 1.27)
						(thickness 0.15)
					)
					(justify left bottom)
					(hide yes)
				)
			)
			(property "Footprint" "antmicro-footprints:C_Pol_EIA-B"
				(at 13.97 -7.62 0)
				(effects
					(font
						(size 1.27 1.27)
						(thickness 0.15)
					)
					(justify left bottom)
					(hide yes)
				)
			)
			(property "Datasheet" "https://www.kemet.com/en/us/capacitors/product/T520B337M006ATE040.html"
				(at 13.97 -10.16 0)
				(effects
					(font
						(size 1.27 1.27)
						(thickness 0.15)
					)
					(justify left bottom)
					(hide yes)
				)
			)
			(property "Description" "Tantalum Polymer Capacitor, KO-CAP®, 330 µF, ± 20%, 6.3 V, B, 0.04 ohm, 1411 [3528 Metric]"
				(at 0 0 0)
				(effects
					(font
						(size 1.27 1.27)
					)
					(hide yes)
				)
			)
			(property "Val" "330u"
				(at 13.97 -5.08 0)
				(effects
					(font
						(size 1.27 1.27)
						(thickness 0.15)
					)
					(justify left bottom)
				)
			)
			(property "MPN" "T520B337M006ATE040"
				(at 13.97 -12.7 0)
				(effects
					(font
						(size 1.27 1.27)
						(thickness 0.15)
					)
					(justify left bottom)
					(hide yes)
				)
			)
			(property "Manufacturer" "KEMET"
				(at 13.97 -15.24 0)
				(effects
					(font
						(size 1.27 1.27)
						(thickness 0.15)
					)
					(justify left bottom)
					(hide yes)
				)
			)
			(property "License" "Apache-2.0"
				(at 13.97 -17.78 0)
				(effects
					(font
						(size 1.27 1.27)
						(thickness 0.15)
					)
					(justify left bottom)
					(hide yes)
				)
			)
			(property "Author" "Antmicro"
				(at 13.97 -20.32 0)
				(effects
					(font
						(size 1.27 1.27)
						(thickness 0.15)
					)
					(justify left bottom)
					(hide yes)
				)
			)
			(property "Voltage" "6.3V"
				(at 13.97 -22.86 0)
				(effects
					(font
						(size 1.27 1.27)
					)
					(justify left bottom)
					(hide yes)
				)
			)
			(property "Dielectric" "template_dielectric"
				(at 13.97 -25.4 0)
				(effects
					(font
						(size 1.27 1.27)
					)
					(justify left bottom)
					(hide yes)
				)
			)
			(property "ki_keywords" "SMT, CAPACITOR, PASSIVE, POLARIZED, TANTALUM"
				(at 0 0 0)
				(effects
					(font
						(size 1.27 1.27)
					)
					(hide yes)
				)
			)
			(symbol "C_Pol_330u_6.3V_KEMET-T520-B_0_1"
				(polyline
					(pts
						(xy 0.9652 1.27) (xy 0.9652 1.778)
					)
					(stroke
						(width 0)
						(type default)
					)
					(fill
						(type none)
					)
				)
				(polyline
					(pts
						(xy 1.2192 1.524) (xy 0.7112 1.524)
					)
					(stroke
						(width 0)
						(type default)
					)
					(fill
						(type none)
					)
				)
				(rectangle
					(start 1.905 -1.524)
					(end 2.286 1.524)
					(stroke
						(width 0)
						(type default)
					)
					(fill
						(type none)
					)
				)
				(rectangle
					(start 2.921 -1.524)
					(end 3.302 1.524)
					(stroke
						(width 0)
						(type default)
					)
					(fill
						(type outline)
					)
				)
			)
			(symbol "C_Pol_330u_6.3V_KEMET-T520-B_1_1"
				(pin passive line
					(at 0 0 0)
					(length 1.8542)
					(name "~"
						(effects
							(font
								(size 1.27 1.27)
							)
						)
					)
					(number "1"
						(effects
							(font
								(size 1.27 1.27)
							)
						)
					)
				)
				(pin passive line
					(at 5.08 0 180)
					(length 1.8542)
					(name "~"
						(effects
							(font
								(size 1.27 1.27)
							)
						)
					)
					(number "2"
						(effects
							(font
								(size 1.27 1.27)
							)
						)
					)
				)
			)
		)
	(symbol "antmicroClockTimingRealTimeClocks:DSC557-0343FI1"
			(exclude_from_sim no)
			(in_bom yes)
			(on_board yes)
			(property "Reference" "U"
				(at 45.72 -7.62 0)
				(effects
					(font
						(size 1.27 1.27)
						(thickness 0.15)
					)
					(justify left bottom)
				)
			)
			(property "Value" "DSC557-0343FI1"
				(at 45.72 -10.16 0)
				(effects
					(font
						(size 1.27 1.27)
						(thickness 0.15)
					)
					(justify left bottom)
					(hide yes)
				)
			)
			(property "Footprint" "antmicro-footprints:VQFN-14-1EP_3.2x2.5mm_P0.5mm_Layout4x3"
				(at 45.72 -15.24 0)
				(effects
					(font
						(size 1.27 1.27)
						(thickness 0.15)
					)
					(justify left bottom)
					(hide yes)
				)
			)
			(property "Datasheet" "https://ww1.microchip.com/downloads/aemDocuments/documents/TCG/ProductDocuments/DataSheets/DSC557-03-04-05-Multiple-Output-MEMS-PCIe-Gen1-2-3-4-Clock-Generators-DS20006691.pdf"
				(at 45.72 -20.32 0)
				(effects
					(font
						(size 1.27 1.27)
						(thickness 0.15)
					)
					(justify left bottom)
					(hide yes)
				)
			)
			(property "Description" "Two output PCIe Clock Generator"
				(at 61.722 -29.464 0)
				(effects
					(font
						(size 1.27 1.27)
					)
					(hide yes)
				)
			)
			(property "Manufacturer" "Microchip Technology"
				(at 45.72 -22.86 0)
				(effects
					(font
						(size 1.27 1.27)
						(thickness 0.15)
					)
					(justify left bottom)
					(hide yes)
				)
			)
			(property "MPN" "DSC557-0343FI1"
				(at 45.72 -17.78 0)
				(effects
					(font
						(size 1.27 1.27)
						(thickness 0.15)
					)
					(justify left bottom)
				)
			)
			(property "Val" "100 MHz"
				(at 45.72 -12.7 0)
				(effects
					(font
						(size 1.27 1.27)
					)
					(justify left bottom)
				)
			)
			(property "Author" "Antmicro"
				(at 45.72 -25.4 0)
				(effects
					(font
						(size 1.27 1.27)
						(thickness 0.15)
					)
					(justify left bottom)
					(hide yes)
				)
			)
			(property "License" "Apache-2.0"
				(at 45.72 -27.94 0)
				(effects
					(font
						(size 1.27 1.27)
						(thickness 0.15)
					)
					(justify left bottom)
					(hide yes)
				)
			)
			(property "ki_keywords" "SMT, IC, CLOCK, PCIE"
				(at 0 0 0)
				(effects
					(font
						(size 1.27 1.27)
					)
					(hide yes)
				)
			)
			(property "ki_fp_filters" "QFN14_3.2X2.5_MCH QFN14_3.2X2.5_MCH-M QFN14_3.2X2.5_MCH-L"
				(at 0 0 0)
				(effects
					(font
						(size 1.27 1.27)
					)
					(hide yes)
				)
			)
			(symbol "DSC557-0343FI1_0_1"
				(polyline
					(pts
						(xy 24.13 0) (xy 16.51 0) (xy 16.51 -5.08) (xy 24.13 -5.08)
					)
					(stroke
						(width 0)
						(type default)
					)
					(fill
						(type none)
					)
				)
				(polyline
					(pts
						(xy 24.13 -7.62) (xy 16.51 -7.62) (xy 16.51 -12.7) (xy 24.13 -12.7)
					)
					(stroke
						(width 0)
						(type default)
					)
					(fill
						(type none)
					)
				)
			)
			(symbol "DSC557-0343FI1_1_1"
				(rectangle
					(start 2.54 2.54)
					(end 24.13 -15.24)
					(stroke
						(width 0.254)
						(type default)
					)
					(fill
						(type background)
					)
				)
				(polyline
					(pts
						(xy 15.24 -2.54) (xy 16.51 -2.54)
					)
					(stroke
						(width 0)
						(type default)
					)
					(fill
						(type none)
					)
				)
				(polyline
					(pts
						(xy 15.24 -10.16) (xy 16.51 -10.16)
					)
					(stroke
						(width 0)
						(type default)
					)
					(fill
						(type none)
					)
				)
				(text "LVDS"
					(at 12.7 -2.54 0)
					(effects
						(font
							(size 1.27 1.27)
						)
					)
				)
				(text "HCSL"
					(at 12.7 -10.16 0)
					(effects
						(font
							(size 1.27 1.27)
						)
					)
				)
				(pin power_in line
					(at 0 0 0)
					(length 2.54)
					(name "VDD0"
						(effects
							(font
								(size 1.27 1.27)
							)
						)
					)
					(number "13"
						(effects
							(font
								(size 1.27 1.27)
							)
						)
					)
				)
				(pin power_in line
					(at 0 -2.54 0)
					(length 2.54)
					(name "VDD1"
						(effects
							(font
								(size 1.27 1.27)
							)
						)
					)
					(number "12"
						(effects
							(font
								(size 1.27 1.27)
							)
						)
					)
				)
				(pin input line
					(at 0 -6.35 0)
					(length 2.54)
					(name "OE"
						(effects
							(font
								(size 1.27 1.27)
							)
						)
					)
					(number "1"
						(effects
							(font
								(size 1.27 1.27)
							)
						)
					)
				)
				(pin power_in line
					(at 0 -10.16 0)
					(length 2.54)
					(name "VSS"
						(effects
							(font
								(size 1.27 1.27)
							)
						)
					)
					(number "4"
						(effects
							(font
								(size 1.27 1.27)
							)
						)
					)
				)
				(pin unspecified line
					(at 0 -12.7 0)
					(length 2.54)
					(name "EPAD"
						(effects
							(font
								(size 1.27 1.27)
							)
						)
					)
					(number "15"
						(effects
							(font
								(size 1.27 1.27)
							)
						)
					)
				)
				(pin no_connect line
					(at 11.43 -15.24 90)
					(length 2.54)
					(hide yes)
					(name "NC"
						(effects
							(font
								(size 1.27 1.27)
							)
						)
					)
					(number "2"
						(effects
							(font
								(size 1.27 1.27)
							)
						)
					)
				)
				(pin no_connect line
					(at 12.7 -15.24 90)
					(length 2.54)
					(hide yes)
					(name "NC"
						(effects
							(font
								(size 1.27 1.27)
							)
						)
					)
					(number "3"
						(effects
							(font
								(size 1.27 1.27)
							)
						)
					)
				)
				(pin no_connect line
					(at 13.97 -15.24 90)
					(length 2.54)
					(hide yes)
					(name "NC"
						(effects
							(font
								(size 1.27 1.27)
							)
						)
					)
					(number "5"
						(effects
							(font
								(size 1.27 1.27)
							)
						)
					)
				)
				(pin no_connect line
					(at 15.24 -15.24 90)
					(length 2.54)
					(hide yes)
					(name "NC"
						(effects
							(font
								(size 1.27 1.27)
							)
						)
					)
					(number "6"
						(effects
							(font
								(size 1.27 1.27)
							)
						)
					)
				)
				(pin no_connect line
					(at 16.51 -15.24 90)
					(length 2.54)
					(hide yes)
					(name "NC"
						(effects
							(font
								(size 1.27 1.27)
							)
						)
					)
					(number "7"
						(effects
							(font
								(size 1.27 1.27)
							)
						)
					)
				)
				(pin no_connect line
					(at 17.78 -15.24 90)
					(length 2.54)
					(hide yes)
					(name "NC"
						(effects
							(font
								(size 1.27 1.27)
							)
						)
					)
					(number "14"
						(effects
							(font
								(size 1.27 1.27)
							)
						)
					)
				)
				(pin output line
					(at 26.67 -1.27 180)
					(length 2.54)
					(name "CLK0+"
						(effects
							(font
								(size 1.27 1.27)
							)
						)
					)
					(number "11"
						(effects
							(font
								(size 1.27 1.27)
							)
						)
					)
				)
				(pin output line
					(at 26.67 -3.81 180)
					(length 2.54)
					(name "CLK0-"
						(effects
							(font
								(size 1.27 1.27)
							)
						)
					)
					(number "10"
						(effects
							(font
								(size 1.27 1.27)
							)
						)
					)
				)
				(pin output line
					(at 26.67 -8.89 180)
					(length 2.54)
					(name "CLK1+"
						(effects
							(font
								(size 1.27 1.27)
							)
						)
					)
					(number "8"
						(effects
							(font
								(size 1.27 1.27)
							)
						)
					)
				)
				(pin output line
					(at 26.67 -11.43 180)
					(length 2.54)
					(name "CLK1-"
						(effects
							(font
								(size 1.27 1.27)
							)
						)
					)
					(number "9"
						(effects
							(font
								(size 1.27 1.27)
							)
						)
					)
				)
			)
		)
	(symbol "antmicroCoaxialConnectorsRF:U_FL-R-SMT-1"
			(exclude_from_sim no)
			(in_bom yes)
			(on_board yes)
			(property "Reference" "J"
				(at 20.32 -2.54 0)
				(effects
					(font
						(size 1.27 1.27)
						(thickness 0.15)
					)
					(justify left bottom)
				)
			)
			(property "Value" "U_FL-R-SMT-1"
				(at 20.32 -7.62 0)
				(effects
					(font
						(size 1.27 1.27)
						(thickness 0.15)
					)
					(justify left bottom)
					(hide yes)
				)
			)
			(property "Footprint" "antmicro-footprints:Coax_Conn_U.FL"
				(at 20.32 -10.16 0)
				(effects
					(font
						(size 1.27 1.27)
						(thickness 0.15)
					)
					(justify left bottom)
					(hide yes)
				)
			)
			(property "Datasheet" "https://media.digikey.com/pdf/Data%20Sheets/Hirose%20PDFs/UFL%20Series.pdf"
				(at 20.32 -12.7 0)
				(effects
					(font
						(size 1.27 1.27)
						(thickness 0.15)
					)
					(justify left bottom)
					(hide yes)
				)
			)
			(property "Description" "U.FL (UMCC) Connector Receptacle, Male Pin 50Ohm Surface Mount Solder"
				(at 0 0 0)
				(effects
					(font
						(size 1.27 1.27)
					)
					(hide yes)
				)
			)
			(property "MPN" "U.FL-R-SMT-1(10)"
				(at 20.32 -5.08 0)
				(effects
					(font
						(size 1.27 1.27)
						(thickness 0.15)
					)
					(justify left bottom)
				)
			)
			(property "Manufacturer" "Hirose Electric"
				(at 20.32 -15.24 0)
				(effects
					(font
						(size 1.27 1.27)
						(thickness 0.15)
					)
					(justify left bottom)
					(hide yes)
				)
			)
			(property "Author" "Antmicro"
				(at 20.32 -17.78 0)
				(effects
					(font
						(size 1.27 1.27)
						(thickness 0.15)
					)
					(justify left bottom)
					(hide yes)
				)
			)
			(property "License" "Apache-2.0"
				(at 20.32 -20.32 0)
				(effects
					(font
						(size 1.27 1.27)
						(thickness 0.15)
					)
					(justify left bottom)
					(hide yes)
				)
			)
			(property "ki_keywords" "UFL, COAXIAL, CONNECTOR"
				(at 0 0 0)
				(effects
					(font
						(size 1.27 1.27)
					)
					(hide yes)
				)
			)
			(symbol "U_FL-R-SMT-1_0_0"
				(pin passive line
					(at 0 0 0)
					(length 3.81)
					(name "~"
						(effects
							(font
								(size 1.27 1.27)
							)
						)
					)
					(number "1"
						(effects
							(font
								(size 1.27 1.27)
							)
						)
					)
				)
				(pin passive line
					(at 6.35 -6.35 90)
					(length 3.81)
					(name "~"
						(effects
							(font
								(size 1.27 1.27)
							)
						)
					)
					(number "SH1"
						(effects
							(font
								(size 1.27 1.27)
							)
						)
					)
				)
				(pin passive line
					(at 6.35 -6.35 90)
					(length 3.81)
					(hide yes)
					(name "~"
						(effects
							(font
								(size 1.27 1.27)
							)
						)
					)
					(number "SH2"
						(effects
							(font
								(size 1.27 1.27)
							)
						)
					)
				)
			)
			(symbol "U_FL-R-SMT-1_1_1"
				(polyline
					(pts
						(xy 3.81 0) (xy 5.842 0)
					)
					(stroke
						(width 0.254)
						(type default)
					)
					(fill
						(type background)
					)
				)
				(arc
					(start 4.6063 0.5218)
					(mid 6.6063 1.8221)
					(end 8.1623 0.0138)
					(stroke
						(width 0.254)
						(type default)
					)
					(fill
						(type none)
					)
				)
				(circle
					(center 6.35 0)
					(radius 0.508)
					(stroke
						(width 0.254)
						(type default)
					)
					(fill
						(type outline)
					)
				)
				(arc
					(start 8.1623 0.0138)
					(mid 6.6063 -1.7941)
					(end 4.6063 -0.4942)
					(stroke
						(width 0.254)
						(type default)
					)
					(fill
						(type none)
					)
				)
				(polyline
					(pts
						(xy 6.35 -2.54) (xy 6.35 -1.905)
					)
					(stroke
						(width 0.254)
						(type default)
					)
					(fill
						(type background)
					)
				)
			)
		)
	(symbol "antmicroFPGAChips:CrossLink_LIF-MD6000-6JMG80I"
			(exclude_from_sim no)
			(in_bom yes)
			(on_board yes)
			(property "Reference" "U"
				(at 78.74 -6.35 0)
				(effects
					(font
						(size 1.27 1.27)
						(thickness 0.15)
					)
					(justify left bottom)
				)
			)
			(property "Value" "CrossLink_LIF-MD6000-6JMG80I"
				(at 78.74 -11.43 0)
				(effects
					(font
						(size 1.27 1.27)
						(thickness 0.15)
					)
					(justify left bottom)
					(hide yes)
				)
			)
			(property "Footprint" "antmicro-footprints:BGA-80_7x7mm_Layout10x10_P0.65mm"
				(at 78.74 -13.97 0)
				(effects
					(font
						(size 1.27 1.27)
						(thickness 0.15)
					)
					(justify left bottom)
					(hide yes)
				)
			)
			(property "Datasheet" "https://www.latticesemi.com/view_document?document_id=51662"
				(at 78.74 -16.51 0)
				(effects
					(font
						(size 1.27 1.27)
						(thickness 0.15)
					)
					(justify left bottom)
					(hide yes)
				)
			)
			(property "Description" "FPGA, CrossLink, PLL37 I/O, 400 MHz, 5936 Cells, 1.14 V to 1.26 V, CTFBGA-80"
				(at 0 0 0)
				(effects
					(font
						(size 1.27 1.27)
					)
					(hide yes)
				)
			)
			(property "MPN" "LIF-MD6000-6JMG80I"
				(at 78.74 -8.89 0)
				(effects
					(font
						(size 1.27 1.27)
						(thickness 0.15)
					)
					(justify left bottom)
				)
			)
			(property "Manufacturer" "Lattice Semiconductor"
				(at 78.74 -19.05 0)
				(effects
					(font
						(size 1.27 1.27)
						(thickness 0.15)
					)
					(justify left bottom)
					(hide yes)
				)
			)
			(property "Author" "Antmicro"
				(at 78.74 -21.59 0)
				(effects
					(font
						(size 1.27 1.27)
						(thickness 0.15)
					)
					(justify left bottom)
					(hide yes)
				)
			)
			(property "License" "Apache-2.0"
				(at 78.74 -24.13 0)
				(effects
					(font
						(size 1.27 1.27)
						(thickness 0.15)
					)
					(justify left bottom)
					(hide yes)
				)
			)
			(property "ki_keywords" "SMT, FPGA, IC"
				(at 0 0 0)
				(effects
					(font
						(size 1.27 1.27)
					)
					(hide yes)
				)
			)
			(symbol "CrossLink_LIF-MD6000-6JMG80I_1_1"
				(rectangle
					(start 3.81 2.54)
					(end 59.69 -111.76)
					(stroke
						(width 0.254)
						(type default)
					)
					(fill
						(type background)
					)
				)
				(polyline
					(pts
						(xy 25.4 -22.86) (xy 25.4 -62.23)
					)
					(stroke
						(width 0.254)
						(type default)
					)
					(fill
						(type background)
					)
				)
				(polyline
					(pts
						(xy 25.4 -66.04) (xy 25.4 -110.49)
					)
					(stroke
						(width 0.254)
						(type default)
					)
					(fill
						(type background)
					)
				)
				(polyline
					(pts
						(xy 31.75 -20.32) (xy 31.75 1.27)
					)
					(stroke
						(width 0.254)
						(type default)
					)
					(fill
						(type background)
					)
				)
				(polyline
					(pts
						(xy 44.45 -46.99) (xy 44.45 -15.24)
					)
					(stroke
						(width 0.254)
						(type default)
					)
					(fill
						(type background)
					)
				)
				(polyline
					(pts
						(xy 44.45 -53.34) (xy 44.45 -85.09)
					)
					(stroke
						(width 0.254)
						(type default)
					)
					(fill
						(type background)
					)
				)
				(text "Bank_1"
					(at 27.94 -30.48 900)
					(effects
						(font
							(size 1.27 1.27)
							(thickness 0.15)
						)
						(justify left bottom)
					)
				)
				(text "Bank_2"
					(at 27.94 -73.66 900)
					(effects
						(font
							(size 1.27 1.27)
							(thickness 0.15)
						)
						(justify left bottom)
					)
				)
				(text "Bank_0"
					(at 34.29 -5.08 900)
					(effects
						(font
							(size 1.27 1.27)
							(thickness 0.15)
						)
						(justify left bottom)
					)
				)
				(text "DPHY0"
					(at 44.45 -46.99 900)
					(effects
						(font
							(size 1.27 1.27)
							(thickness 0.15)
						)
						(justify left bottom)
					)
				)
				(text "DPHY1"
					(at 44.45 -85.09 900)
					(effects
						(font
							(size 1.27 1.27)
							(thickness 0.15)
						)
						(justify left bottom)
					)
				)
				(pin input line
					(at 0 0 0)
					(length 3.81)
					(name "CRESET_B"
						(effects
							(font
								(size 1.27 1.27)
							)
						)
					)
					(number "H2"
						(effects
							(font
								(size 1.27 1.27)
							)
						)
					)
				)
				(pin passive line
					(at 0 -2.54 0)
					(length 3.81)
					(name "PB49/PMU_WKUPN/CDONE"
						(effects
							(font
								(size 1.27 1.27)
							)
						)
					)
					(number "J2"
						(effects
							(font
								(size 1.27 1.27)
							)
						)
					)
				)
				(pin bidirectional line
					(at 0 -5.08 0)
					(length 3.81)
					(name "PB48/PCLKT0_1/USER_SCL"
						(effects
							(font
								(size 1.27 1.27)
							)
						)
					)
					(number "D1"
						(effects
							(font
								(size 1.27 1.27)
							)
						)
					)
				)
				(pin bidirectional line
					(at 0 -7.62 0)
					(length 3.81)
					(name "PB47/PCLKT0_0/USER_SDA"
						(effects
							(font
								(size 1.27 1.27)
							)
						)
					)
					(number "K2"
						(effects
							(font
								(size 1.27 1.27)
							)
						)
					)
				)
				(pin bidirectional line
					(at 0 -10.16 0)
					(length 3.81)
					(name "PB50/MOSI"
						(effects
							(font
								(size 1.27 1.27)
							)
						)
					)
					(number "G1"
						(effects
							(font
								(size 1.27 1.27)
							)
						)
					)
				)
				(pin bidirectional line
					(at 0 -12.7 0)
					(length 3.81)
					(name "PB52/SPI_SS/CSN/SCL"
						(effects
							(font
								(size 1.27 1.27)
							)
						)
					)
					(number "H1"
						(effects
							(font
								(size 1.27 1.27)
							)
						)
					)
				)
				(pin bidirectional line
					(at 0 -15.24 0)
					(length 3.81)
					(name "PB53/SPI_SCK/MCK/SDA"
						(effects
							(font
								(size 1.27 1.27)
							)
						)
					)
					(number "J1"
						(effects
							(font
								(size 1.27 1.27)
							)
						)
					)
				)
				(pin bidirectional line
					(at 0 -17.78 0)
					(length 3.81)
					(name "PB51/MISO"
						(effects
							(font
								(size 1.27 1.27)
							)
						)
					)
					(number "K1"
						(effects
							(font
								(size 1.27 1.27)
							)
						)
					)
				)
				(pin power_in line
					(at 0 -20.32 0)
					(length 3.81)
					(name "VCCIO0"
						(effects
							(font
								(size 1.27 1.27)
							)
						)
					)
					(number "F4"
						(effects
							(font
								(size 1.27 1.27)
							)
						)
					)
				)
				(pin input line
					(at 0 -25.4 0)
					(length 3.81)
					(name "PB34A/GR_PCLK1_0"
						(effects
							(font
								(size 1.27 1.27)
							)
						)
					)
					(number "E1"
						(effects
							(font
								(size 1.27 1.27)
							)
						)
					)
				)
				(pin bidirectional line
					(at 0 -27.94 0)
					(length 3.81)
					(name "PB34B"
						(effects
							(font
								(size 1.27 1.27)
							)
						)
					)
					(number "E2"
						(effects
							(font
								(size 1.27 1.27)
							)
						)
					)
				)
				(pin bidirectional line
					(at 0 -30.48 0)
					(length 3.81)
					(name "PB38A"
						(effects
							(font
								(size 1.27 1.27)
							)
						)
					)
					(number "F1"
						(effects
							(font
								(size 1.27 1.27)
							)
						)
					)
				)
				(pin bidirectional line
					(at 0 -33.02 0)
					(length 3.81)
					(name "PB38B"
						(effects
							(font
								(size 1.27 1.27)
							)
						)
					)
					(number "F2"
						(effects
							(font
								(size 1.27 1.27)
							)
						)
					)
				)
				(pin bidirectional line
					(at 0 -35.56 0)
					(length 3.81)
					(name "PB29A/PCLKT1_0"
						(effects
							(font
								(size 1.27 1.27)
							)
						)
					)
					(number "J7"
						(effects
							(font
								(size 1.27 1.27)
							)
						)
					)
				)
				(pin bidirectional line
					(at 0 -38.1 0)
					(length 3.81)
					(name "PB29D/PCLKC1_1"
						(effects
							(font
								(size 1.27 1.27)
							)
						)
					)
					(number "J6"
						(effects
							(font
								(size 1.27 1.27)
							)
						)
					)
				)
				(pin bidirectional line
					(at 0 -40.64 0)
					(length 3.81)
					(name "PB34D/MIPI_CLKC1_0"
						(effects
							(font
								(size 1.27 1.27)
							)
						)
					)
					(number "J5"
						(effects
							(font
								(size 1.27 1.27)
							)
						)
					)
				)
				(pin bidirectional line
					(at 0 -43.18 0)
					(length 3.81)
					(name "PB38D"
						(effects
							(font
								(size 1.27 1.27)
							)
						)
					)
					(number "J4"
						(effects
							(font
								(size 1.27 1.27)
							)
						)
					)
				)
				(pin bidirectional line
					(at 0 -45.72 0)
					(length 3.81)
					(name "PB43D"
						(effects
							(font
								(size 1.27 1.27)
							)
						)
					)
					(number "J3"
						(effects
							(font
								(size 1.27 1.27)
							)
						)
					)
				)
				(pin bidirectional line
					(at 0 -48.26 0)
					(length 3.81)
					(name "PB29B/PCLKC1_0"
						(effects
							(font
								(size 1.27 1.27)
							)
						)
					)
					(number "K7"
						(effects
							(font
								(size 1.27 1.27)
							)
						)
					)
				)
				(pin bidirectional line
					(at 0 -50.8 0)
					(length 3.81)
					(name "PB29C/PCLKT1_1"
						(effects
							(font
								(size 1.27 1.27)
							)
						)
					)
					(number "K6"
						(effects
							(font
								(size 1.27 1.27)
							)
						)
					)
				)
				(pin bidirectional line
					(at 0 -53.34 0)
					(length 3.81)
					(name "PB34C/MIPI_CLKT1_0"
						(effects
							(font
								(size 1.27 1.27)
							)
						)
					)
					(number "K5"
						(effects
							(font
								(size 1.27 1.27)
							)
						)
					)
				)
				(pin bidirectional line
					(at 0 -55.88 0)
					(length 3.81)
					(name "PB38C"
						(effects
							(font
								(size 1.27 1.27)
							)
						)
					)
					(number "K4"
						(effects
							(font
								(size 1.27 1.27)
							)
						)
					)
				)
				(pin bidirectional line
					(at 0 -58.42 0)
					(length 3.81)
					(name "PB43C"
						(effects
							(font
								(size 1.27 1.27)
							)
						)
					)
					(number "K3"
						(effects
							(font
								(size 1.27 1.27)
							)
						)
					)
				)
				(pin power_in line
					(at 0 -60.96 0)
					(length 3.81)
					(name "VCCIO1"
						(effects
							(font
								(size 1.27 1.27)
							)
						)
					)
					(number "F5"
						(effects
							(font
								(size 1.27 1.27)
							)
						)
					)
				)
				(pin passive line
					(at 0 -60.96 0)
					(length 3.81)
					(hide yes)
					(name "VCCIO1"
						(effects
							(font
								(size 1.27 1.27)
							)
						)
					)
					(number "G4"
						(effects
							(font
								(size 1.27 1.27)
							)
						)
					)
				)
				(pin bidirectional line
					(at 0 -68.58 0)
					(length 3.81)
					(name "PB16A/PCLKT2_0"
						(effects
							(font
								(size 1.27 1.27)
							)
						)
					)
					(number "D9"
						(effects
							(font
								(size 1.27 1.27)
							)
						)
					)
				)
				(pin bidirectional line
					(at 0 -71.12 0)
					(length 3.81)
					(name "PB16B/PCLKC2_0"
						(effects
							(font
								(size 1.27 1.27)
							)
						)
					)
					(number "D10"
						(effects
							(font
								(size 1.27 1.27)
							)
						)
					)
				)
				(pin input line
					(at 0 -73.66 0)
					(length 3.81)
					(name "PB12A/GPLLT2_0"
						(effects
							(font
								(size 1.27 1.27)
							)
						)
					)
					(number "E9"
						(effects
							(font
								(size 1.27 1.27)
							)
						)
					)
				)
				(pin input line
					(at 0 -76.2 0)
					(length 3.81)
					(name "PB12B/GPLLC2_0"
						(effects
							(font
								(size 1.27 1.27)
							)
						)
					)
					(number "E10"
						(effects
							(font
								(size 1.27 1.27)
							)
						)
					)
				)
				(pin input line
					(at 0 -78.74 0)
					(length 3.81)
					(name "PB6A/GR_PCLK2_0"
						(effects
							(font
								(size 1.27 1.27)
							)
						)
					)
					(number "F9"
						(effects
							(font
								(size 1.27 1.27)
							)
						)
					)
				)
				(pin bidirectional line
					(at 0 -81.28 0)
					(length 3.81)
					(name "PB6B"
						(effects
							(font
								(size 1.27 1.27)
							)
						)
					)
					(number "F10"
						(effects
							(font
								(size 1.27 1.27)
							)
						)
					)
				)
				(pin bidirectional line
					(at 0 -83.82 0)
					(length 3.81)
					(name "PB2A"
						(effects
							(font
								(size 1.27 1.27)
							)
						)
					)
					(number "G9"
						(effects
							(font
								(size 1.27 1.27)
							)
						)
					)
				)
				(pin bidirectional line
					(at 0 -86.36 0)
					(length 3.81)
					(name "PB2B"
						(effects
							(font
								(size 1.27 1.27)
							)
						)
					)
					(number "G10"
						(effects
							(font
								(size 1.27 1.27)
							)
						)
					)
				)
				(pin bidirectional line
					(at 0 -88.9 0)
					(length 3.81)
					(name "PB2D/MIPI_CLKC2_0"
						(effects
							(font
								(size 1.27 1.27)
							)
						)
					)
					(number "H9"
						(effects
							(font
								(size 1.27 1.27)
							)
						)
					)
				)
				(pin bidirectional line
					(at 0 -91.44 0)
					(length 3.81)
					(name "PB2C/MIPI_CLKT2_0"
						(effects
							(font
								(size 1.27 1.27)
							)
						)
					)
					(number "H10"
						(effects
							(font
								(size 1.27 1.27)
							)
						)
					)
				)
				(pin bidirectional line
					(at 0 -93.98 0)
					(length 3.81)
					(name "PB16D/PCLKC2_1"
						(effects
							(font
								(size 1.27 1.27)
							)
						)
					)
					(number "J8"
						(effects
							(font
								(size 1.27 1.27)
							)
						)
					)
				)
				(pin bidirectional line
					(at 0 -96.52 0)
					(length 3.81)
					(name "PB6D"
						(effects
							(font
								(size 1.27 1.27)
							)
						)
					)
					(number "J9"
						(effects
							(font
								(size 1.27 1.27)
							)
						)
					)
				)
				(pin bidirectional line
					(at 0 -99.06 0)
					(length 3.81)
					(name "PB6C"
						(effects
							(font
								(size 1.27 1.27)
							)
						)
					)
					(number "J10"
						(effects
							(font
								(size 1.27 1.27)
							)
						)
					)
				)
				(pin bidirectional line
					(at 0 -101.6 0)
					(length 3.81)
					(name "PB16C/PCLKT2_1"
						(effects
							(font
								(size 1.27 1.27)
							)
						)
					)
					(number "K8"
						(effects
							(font
								(size 1.27 1.27)
							)
						)
					)
				)
				(pin bidirectional line
					(at 0 -104.14 0)
					(length 3.81)
					(name "PB12D"
						(effects
							(font
								(size 1.27 1.27)
							)
						)
					)
					(number "K9"
						(effects
							(font
								(size 1.27 1.27)
							)
						)
					)
				)
				(pin bidirectional line
					(at 0 -106.68 0)
					(length 3.81)
					(name "PB12C"
						(effects
							(font
								(size 1.27 1.27)
							)
						)
					)
					(number "K10"
						(effects
							(font
								(size 1.27 1.27)
							)
						)
					)
				)
				(pin power_in line
					(at 0 -109.22 0)
					(length 3.81)
					(name "VCCIO2"
						(effects
							(font
								(size 1.27 1.27)
							)
						)
					)
					(number "F6"
						(effects
							(font
								(size 1.27 1.27)
							)
						)
					)
				)
				(pin passive line
					(at 0 -109.22 0)
					(length 3.81)
					(hide yes)
					(name "VCCIO2"
						(effects
							(font
								(size 1.27 1.27)
							)
						)
					)
					(number "F7"
						(effects
							(font
								(size 1.27 1.27)
							)
						)
					)
				)
				(pin power_in line
					(at 63.5 0 180)
					(length 3.81)
					(name "VCC"
						(effects
							(font
								(size 1.27 1.27)
							)
						)
					)
					(number "E4"
						(effects
							(font
								(size 1.27 1.27)
							)
						)
					)
				)
				(pin passive line
					(at 63.5 0 180)
					(length 3.81)
					(hide yes)
					(name "VCC"
						(effects
							(font
								(size 1.27 1.27)
							)
						)
					)
					(number "E6"
						(effects
							(font
								(size 1.27 1.27)
							)
						)
					)
				)
				(pin power_in line
					(at 63.5 -5.08 180)
					(length 3.81)
					(name "VCCAUX"
						(effects
							(font
								(size 1.27 1.27)
							)
						)
					)
					(number "D5"
						(effects
							(font
								(size 1.27 1.27)
							)
						)
					)
				)
				(pin power_in line
					(at 63.5 -10.16 180)
					(length 3.81)
					(name "VCCGPLL"
						(effects
							(font
								(size 1.27 1.27)
							)
						)
					)
					(number "G6"
						(effects
							(font
								(size 1.27 1.27)
							)
						)
					)
				)
				(pin bidirectional line
					(at 63.5 -15.24 180)
					(length 3.81)
					(name "DPHY0_CKP"
						(effects
							(font
								(size 1.27 1.27)
							)
						)
					)
					(number "B8"
						(effects
							(font
								(size 1.27 1.27)
							)
						)
					)
				)
				(pin bidirectional line
					(at 63.5 -17.78 180)
					(length 3.81)
					(name "DPHY0_CKN"
						(effects
							(font
								(size 1.27 1.27)
							)
						)
					)
					(number "A8"
						(effects
							(font
								(size 1.27 1.27)
							)
						)
					)
				)
				(pin bidirectional line
					(at 63.5 -20.32 180)
					(length 3.81)
					(name "DPHY0_DP0"
						(effects
							(font
								(size 1.27 1.27)
							)
						)
					)
					(number "B7"
						(effects
							(font
								(size 1.27 1.27)
							)
						)
					)
				)
				(pin bidirectional line
					(at 63.5 -22.86 180)
					(length 3.81)
					(name "DPHY0_DN0"
						(effects
							(font
								(size 1.27 1.27)
							)
						)
					)
					(number "A7"
						(effects
							(font
								(size 1.27 1.27)
							)
						)
					)
				)
				(pin bidirectional line
					(at 63.5 -25.4 180)
					(length 3.81)
					(name "DPHY0_DP1"
						(effects
							(font
								(size 1.27 1.27)
							)
						)
					)
					(number "B9"
						(effects
							(font
								(size 1.27 1.27)
							)
						)
					)
				)
				(pin bidirectional line
					(at 63.5 -27.94 180)
					(length 3.81)
					(name "DPHY0_DN1"
						(effects
							(font
								(size 1.27 1.27)
							)
						)
					)
					(number "A9"
						(effects
							(font
								(size 1.27 1.27)
							)
						)
					)
				)
				(pin bidirectional line
					(at 63.5 -30.48 180)
					(length 3.81)
					(name "DPHY0_DP2"
						(effects
							(font
								(size 1.27 1.27)
							)
						)
					)
					(number "B6"
						(effects
							(font
								(size 1.27 1.27)
							)
						)
					)
				)
				(pin bidirectional line
					(at 63.5 -33.02 180)
					(length 3.81)
					(name "DPHY0_DN2"
						(effects
							(font
								(size 1.27 1.27)
							)
						)
					)
					(number "A6"
						(effects
							(font
								(size 1.27 1.27)
							)
						)
					)
				)
				(pin bidirectional line
					(at 63.5 -35.56 180)
					(length 3.81)
					(name "DPHY0_DP3"
						(effects
							(font
								(size 1.27 1.27)
							)
						)
					)
					(number "B10"
						(effects
							(font
								(size 1.27 1.27)
							)
						)
					)
				)
				(pin bidirectional line
					(at 63.5 -38.1 180)
					(length 3.81)
					(name "DPHY0_DN3"
						(effects
							(font
								(size 1.27 1.27)
							)
						)
					)
					(number "A10"
						(effects
							(font
								(size 1.27 1.27)
							)
						)
					)
				)
				(pin power_in line
					(at 63.5 -40.64 180)
					(length 3.81)
					(name "GNDA_DPHY0"
						(effects
							(font
								(size 1.27 1.27)
							)
						)
					)
					(number "C9"
						(effects
							(font
								(size 1.27 1.27)
							)
						)
					)
				)
				(pin power_in line
					(at 63.5 -43.18 180)
					(length 3.81)
					(name "VCCA_DPHY0"
						(effects
							(font
								(size 1.27 1.27)
							)
						)
					)
					(number "E7"
						(effects
							(font
								(size 1.27 1.27)
							)
						)
					)
				)
				(pin bidirectional line
					(at 63.5 -45.72 180)
					(length 3.81)
					(name "VCCPLL_DPHY0"
						(effects
							(font
								(size 1.27 1.27)
							)
						)
					)
					(number "D7"
						(effects
							(font
								(size 1.27 1.27)
							)
						)
					)
				)
				(pin bidirectional line
					(at 63.5 -53.34 180)
					(length 3.81)
					(name "DPHY1_CKP"
						(effects
							(font
								(size 1.27 1.27)
							)
						)
					)
					(number "B3"
						(effects
							(font
								(size 1.27 1.27)
							)
						)
					)
				)
				(pin bidirectional line
					(at 63.5 -55.88 180)
					(length 3.81)
					(name "DPHY1_CKN"
						(effects
							(font
								(size 1.27 1.27)
							)
						)
					)
					(number "A3"
						(effects
							(font
								(size 1.27 1.27)
							)
						)
					)
				)
				(pin bidirectional line
					(at 63.5 -58.42 180)
					(length 3.81)
					(name "DPHY1_DP0"
						(effects
							(font
								(size 1.27 1.27)
							)
						)
					)
					(number "B2"
						(effects
							(font
								(size 1.27 1.27)
							)
						)
					)
				)
				(pin bidirectional line
					(at 63.5 -60.96 180)
					(length 3.81)
					(name "DPHY1_DN0"
						(effects
							(font
								(size 1.27 1.27)
							)
						)
					)
					(number "A2"
						(effects
							(font
								(size 1.27 1.27)
							)
						)
					)
				)
				(pin bidirectional line
					(at 63.5 -63.5 180)
					(length 3.81)
					(name "DPHY1_DP1"
						(effects
							(font
								(size 1.27 1.27)
							)
						)
					)
					(number "B4"
						(effects
							(font
								(size 1.27 1.27)
							)
						)
					)
				)
				(pin bidirectional line
					(at 63.5 -66.04 180)
					(length 3.81)
					(name "DPHY1_DN1"
						(effects
							(font
								(size 1.27 1.27)
							)
						)
					)
					(number "A4"
						(effects
							(font
								(size 1.27 1.27)
							)
						)
					)
				)
				(pin bidirectional line
					(at 63.5 -68.58 180)
					(length 3.81)
					(name "DPHY1_DP2"
						(effects
							(font
								(size 1.27 1.27)
							)
						)
					)
					(number "B1"
						(effects
							(font
								(size 1.27 1.27)
							)
						)
					)
				)
				(pin bidirectional line
					(at 63.5 -71.12 180)
					(length 3.81)
					(name "DPHY1_DN2"
						(effects
							(font
								(size 1.27 1.27)
							)
						)
					)
					(number "A1"
						(effects
							(font
								(size 1.27 1.27)
							)
						)
					)
				)
				(pin bidirectional line
					(at 63.5 -73.66 180)
					(length 3.81)
					(name "DPHY1_DP3"
						(effects
							(font
								(size 1.27 1.27)
							)
						)
					)
					(number "B5"
						(effects
							(font
								(size 1.27 1.27)
							)
						)
					)
				)
				(pin bidirectional line
					(at 63.5 -76.2 180)
					(length 3.81)
					(name "DPHY1_DN3"
						(effects
							(font
								(size 1.27 1.27)
							)
						)
					)
					(number "A5"
						(effects
							(font
								(size 1.27 1.27)
							)
						)
					)
				)
				(pin power_in line
					(at 63.5 -78.74 180)
					(length 3.81)
					(name "GNDA_DPHY1"
						(effects
							(font
								(size 1.27 1.27)
							)
						)
					)
					(number "C2"
						(effects
							(font
								(size 1.27 1.27)
							)
						)
					)
				)
				(pin power_in line
					(at 63.5 -81.28 180)
					(length 3.81)
					(name "VCCA_DPHY1"
						(effects
							(font
								(size 1.27 1.27)
							)
						)
					)
					(number "D4"
						(effects
							(font
								(size 1.27 1.27)
							)
						)
					)
				)
				(pin power_in line
					(at 63.5 -83.82 180)
					(length 3.81)
					(name "VCCPLL_DPHY1"
						(effects
							(font
								(size 1.27 1.27)
							)
						)
					)
					(number "D2"
						(effects
							(font
								(size 1.27 1.27)
							)
						)
					)
				)
				(pin power_in line
					(at 63.5 -101.6 180)
					(length 3.81)
					(name "GNDPLL_DPHY_X"
						(effects
							(font
								(size 1.27 1.27)
							)
						)
					)
					(number "D6"
						(effects
							(font
								(size 1.27 1.27)
							)
						)
					)
				)
				(pin power_in line
					(at 63.5 -104.14 180)
					(length 3.81)
					(name "GNDGPLL"
						(effects
							(font
								(size 1.27 1.27)
							)
						)
					)
					(number "G7"
						(effects
							(font
								(size 1.27 1.27)
							)
						)
					)
				)
				(pin power_in line
					(at 63.5 -106.68 180)
					(length 3.81)
					(name "GND"
						(effects
							(font
								(size 1.27 1.27)
							)
						)
					)
					(number "C1"
						(effects
							(font
								(size 1.27 1.27)
							)
						)
					)
				)
				(pin passive line
					(at 63.5 -106.68 180)
					(length 3.81)
					(hide yes)
					(name "GND"
						(effects
							(font
								(size 1.27 1.27)
							)
						)
					)
					(number "C10"
						(effects
							(font
								(size 1.27 1.27)
							)
						)
					)
				)
				(pin passive line
					(at 63.5 -106.68 180)
					(length 3.81)
					(hide yes)
					(name "GND"
						(effects
							(font
								(size 1.27 1.27)
							)
						)
					)
					(number "E5"
						(effects
							(font
								(size 1.27 1.27)
							)
						)
					)
				)
				(pin passive line
					(at 63.5 -106.68 180)
					(length 3.81)
					(hide yes)
					(name "GND"
						(effects
							(font
								(size 1.27 1.27)
							)
						)
					)
					(number "G2"
						(effects
							(font
								(size 1.27 1.27)
							)
						)
					)
				)
				(pin passive line
					(at 63.5 -106.68 180)
					(length 3.81)
					(hide yes)
					(name "GND"
						(effects
							(font
								(size 1.27 1.27)
							)
						)
					)
					(number "G5"
						(effects
							(font
								(size 1.27 1.27)
							)
						)
					)
				)
			)
		)
	(symbol "antmicroFPGAChips:MPFS250T-FCVG484E"
			(exclude_from_sim no)
			(in_bom yes)
			(on_board yes)
			(property "Reference" "U"
				(at 105.41 0 0)
				(effects
					(font
						(size 1.27 1.27)
						(thickness 0.15)
					)
					(justify left bottom)
				)
			)
			(property "Value" "MPFS250T-FCVG484E"
				(at 105.41 -5.08 0)
				(effects
					(font
						(size 1.27 1.27)
						(thickness 0.15)
					)
					(justify left bottom)
					(hide yes)
				)
			)
			(property "Footprint" "antmicro-footprints:BGA-484_19x19mm_Layout22x22_P0.8mm_FCVG484"
				(at 105.41 -7.62 0)
				(effects
					(font
						(size 1.27 1.27)
						(thickness 0.15)
					)
					(justify left bottom)
					(hide yes)
				)
			)
			(property "Datasheet" "https://ww1.microchip.com/downloads/aemDocuments/documents/FPGA/ProductDocuments/DataSheets/PolarFire-SoC-Datasheet-DS00004248.pdf"
				(at 105.41 -10.16 0)
				(effects
					(font
						(size 1.27 1.27)
						(thickness 0.15)
					)
					(justify left bottom)
					(hide yes)
				)
			)
			(property "Description" "RISC-V System On Chip (SOC) IC PolarFire® FPGA - 254K Logic Modules 484-FCBGA (19x19)"
				(at 105.41 -20.32 0)
				(effects
					(font
						(size 1.27 1.27)
					)
					(justify left bottom)
					(hide yes)
				)
			)
			(property "MPN" "MPFS250T-FCVG484E"
				(at 105.41 -2.54 0)
				(effects
					(font
						(size 1.27 1.27)
						(thickness 0.15)
					)
					(justify left bottom)
				)
			)
			(property "Manufacturer" "Microchip Technology"
				(at 105.41 -12.7 0)
				(effects
					(font
						(size 1.27 1.27)
						(thickness 0.15)
					)
					(justify left bottom)
					(hide yes)
				)
			)
			(property "Author" "Antmicro"
				(at 105.41 -15.24 0)
				(effects
					(font
						(size 1.27 1.27)
						(thickness 0.15)
					)
					(justify left bottom)
					(hide yes)
				)
			)
			(property "License" "Apache-2.0"
				(at 105.41 -17.78 0)
				(effects
					(font
						(size 1.27 1.27)
						(thickness 0.15)
					)
					(justify left bottom)
					(hide yes)
				)
			)
			(property "ki_locked" ""
				(at 0 0 0)
				(effects
					(font
						(size 1.27 1.27)
					)
				)
			)
			(property "ki_keywords" "IC, FPGA, SOC"
				(at 0 0 0)
				(effects
					(font
						(size 1.27 1.27)
					)
					(hide yes)
				)
			)
			(symbol "MPFS250T-FCVG484E_1_1"
				(rectangle
					(start 5.08 5.08)
					(end 86.36 -76.2)
					(stroke
						(width 0.254)
						(type default)
					)
					(fill
						(type background)
					)
				)
				(text "BANK 0"
					(at 40.64 1.27 0)
					(effects
						(font
							(size 1.27 1.27)
							(thickness 0.15)
						)
						(justify left bottom)
					)
				)
				(pin bidirectional line
					(at 0 0 0)
					(length 5.08)
					(name "HSIO66PB0/CCC_NE_CLKIN_N_11"
						(effects
							(font
								(size 1.27 1.27)
							)
						)
					)
					(number "W22"
						(effects
							(font
								(size 1.27 1.27)
							)
						)
					)
				)
				(pin bidirectional line
					(at 0 -2.54 0)
					(length 5.08)
					(name "HSIO66NB0"
						(effects
							(font
								(size 1.27 1.27)
							)
						)
					)
					(number "V22"
						(effects
							(font
								(size 1.27 1.27)
							)
						)
					)
				)
				(pin bidirectional line
					(at 0 -5.08 0)
					(length 5.08)
					(name "HSIO67PB0/CCC_NE_PLL0_OUT1"
						(effects
							(font
								(size 1.27 1.27)
							)
						)
					)
					(number "Y20"
						(effects
							(font
								(size 1.27 1.27)
							)
						)
					)
				)
				(pin bidirectional line
					(at 0 -7.62 0)
					(length 5.08)
					(name "HSIO67NB0"
						(effects
							(font
								(size 1.27 1.27)
							)
						)
					)
					(number "Y21"
						(effects
							(font
								(size 1.27 1.27)
							)
						)
					)
				)
				(pin bidirectional line
					(at 0 -10.16 0)
					(length 5.08)
					(name "HSIO68PB0/CCC_NE_CLKIN_N_10/CCC_NE_PLL0_OUT0"
						(effects
							(font
								(size 1.27 1.27)
							)
						)
					)
					(number "W21"
						(effects
							(font
								(size 1.27 1.27)
							)
						)
					)
				)
				(pin bidirectional line
					(at 0 -12.7 0)
					(length 5.08)
					(name "HSIO68NB0"
						(effects
							(font
								(size 1.27 1.27)
							)
						)
					)
					(number "V21"
						(effects
							(font
								(size 1.27 1.27)
							)
						)
					)
				)
				(pin bidirectional line
					(at 0 -15.24 0)
					(length 5.08)
					(name "HSIO69PB0/DQS/CCC_NE_PLL0_OUT0"
						(effects
							(font
								(size 1.27 1.27)
							)
						)
					)
					(number "AA21"
						(effects
							(font
								(size 1.27 1.27)
							)
						)
					)
				)
				(pin bidirectional line
					(at 0 -17.78 0)
					(length 5.08)
					(name "HSIO69NB0/DQS"
						(effects
							(font
								(size 1.27 1.27)
							)
						)
					)
					(number "AA22"
						(effects
							(font
								(size 1.27 1.27)
							)
						)
					)
				)
				(pin bidirectional line
					(at 0 -20.32 0)
					(length 5.08)
					(name "HSIO70PB0"
						(effects
							(font
								(size 1.27 1.27)
							)
						)
					)
					(number "AB19"
						(effects
							(font
								(size 1.27 1.27)
							)
						)
					)
				)
				(pin bidirectional line
					(at 0 -22.86 0)
					(length 5.08)
					(name "HSIO70NB0"
						(effects
							(font
								(size 1.27 1.27)
							)
						)
					)
					(number "AB20"
						(effects
							(font
								(size 1.27 1.27)
							)
						)
					)
				)
				(pin bidirectional line
					(at 0 -25.4 0)
					(length 5.08)
					(name "HSIO71PB0"
						(effects
							(font
								(size 1.27 1.27)
							)
						)
					)
					(number "AB21"
						(effects
							(font
								(size 1.27 1.27)
							)
						)
					)
				)
				(pin bidirectional line
					(at 0 -27.94 0)
					(length 5.08)
					(name "HSIO71NB0"
						(effects
							(font
								(size 1.27 1.27)
							)
						)
					)
					(number "AA20"
						(effects
							(font
								(size 1.27 1.27)
							)
						)
					)
				)
				(pin bidirectional line
					(at 0 -30.48 0)
					(length 5.08)
					(name "HSIO72PB0/CLKIN_N_9/CCC_NE_CLKIN_N_9"
						(effects
							(font
								(size 1.27 1.27)
							)
						)
					)
					(number "V20"
						(effects
							(font
								(size 1.27 1.27)
							)
						)
					)
				)
				(pin bidirectional line
					(at 0 -33.02 0)
					(length 5.08)
					(name "HSIO72NB0"
						(effects
							(font
								(size 1.27 1.27)
							)
						)
					)
					(number "V19"
						(effects
							(font
								(size 1.27 1.27)
							)
						)
					)
				)
				(pin bidirectional line
					(at 0 -35.56 0)
					(length 5.08)
					(name "HSIO73PB0/CCC_NE_PLL1_OUT1"
						(effects
							(font
								(size 1.27 1.27)
							)
						)
					)
					(number "T17"
						(effects
							(font
								(size 1.27 1.27)
							)
						)
					)
				)
				(pin bidirectional line
					(at 0 -38.1 0)
					(length 5.08)
					(name "HSIO73NB0"
						(effects
							(font
								(size 1.27 1.27)
							)
						)
					)
					(number "U17"
						(effects
							(font
								(size 1.27 1.27)
							)
						)
					)
				)
				(pin bidirectional line
					(at 0 -40.64 0)
					(length 5.08)
					(name "HSIO74PB0/CLKIN_N_8/CCC_NE_CLKIN_N_8/CCC_NE_PLL1_OUT0"
						(effects
							(font
								(size 1.27 1.27)
							)
						)
					)
					(number "U19"
						(effects
							(font
								(size 1.27 1.27)
							)
						)
					)
				)
				(pin bidirectional line
					(at 0 -43.18 0)
					(length 5.08)
					(name "HSIO74NB0"
						(effects
							(font
								(size 1.27 1.27)
							)
						)
					)
					(number "U18"
						(effects
							(font
								(size 1.27 1.27)
							)
						)
					)
				)
				(pin bidirectional line
					(at 0 -45.72 0)
					(length 5.08)
					(name "HSIO75PB0/DQS/CCC_NE_PLL1_OUT0"
						(effects
							(font
								(size 1.27 1.27)
							)
						)
					)
					(number "T16"
						(effects
							(font
								(size 1.27 1.27)
							)
						)
					)
				)
				(pin bidirectional line
					(at 0 -48.26 0)
					(length 5.08)
					(name "HSIO75NB0/DQS"
						(effects
							(font
								(size 1.27 1.27)
							)
						)
					)
					(number "R16"
						(effects
							(font
								(size 1.27 1.27)
							)
						)
					)
				)
				(pin bidirectional line
					(at 0 -50.8 0)
					(length 5.08)
					(name "HSIO76PB0"
						(effects
							(font
								(size 1.27 1.27)
							)
						)
					)
					(number "V17"
						(effects
							(font
								(size 1.27 1.27)
							)
						)
					)
				)
				(pin bidirectional line
					(at 0 -53.34 0)
					(length 5.08)
					(name "HSIO76NB0"
						(effects
							(font
								(size 1.27 1.27)
							)
						)
					)
					(number "V16"
						(effects
							(font
								(size 1.27 1.27)
							)
						)
					)
				)
				(pin bidirectional line
					(at 0 -55.88 0)
					(length 5.08)
					(name "HSIO77PB0"
						(effects
							(font
								(size 1.27 1.27)
							)
						)
					)
					(number "R15"
						(effects
							(font
								(size 1.27 1.27)
							)
						)
					)
				)
				(pin bidirectional line
					(at 0 -58.42 0)
					(length 5.08)
					(name "HSIO77NB0"
						(effects
							(font
								(size 1.27 1.27)
							)
						)
					)
					(number "R14"
						(effects
							(font
								(size 1.27 1.27)
							)
						)
					)
				)
				(pin bidirectional line
					(at 0 -60.96 0)
					(length 5.08)
					(name "HSIO78PB0/CLKIN_N_7"
						(effects
							(font
								(size 1.27 1.27)
							)
						)
					)
					(number "AB18"
						(effects
							(font
								(size 1.27 1.27)
							)
						)
					)
				)
				(pin bidirectional line
					(at 0 -63.5 0)
					(length 5.08)
					(name "HSIO78NB0"
						(effects
							(font
								(size 1.27 1.27)
							)
						)
					)
					(number "AA18"
						(effects
							(font
								(size 1.27 1.27)
							)
						)
					)
				)
				(pin bidirectional line
					(at 0 -66.04 0)
					(length 5.08)
					(name "HSIO79PB0"
						(effects
							(font
								(size 1.27 1.27)
							)
						)
					)
					(number "W19"
						(effects
							(font
								(size 1.27 1.27)
							)
						)
					)
				)
				(pin bidirectional line
					(at 0 -68.58 0)
					(length 5.08)
					(name "HSIO79NB0"
						(effects
							(font
								(size 1.27 1.27)
							)
						)
					)
					(number "W18"
						(effects
							(font
								(size 1.27 1.27)
							)
						)
					)
				)
				(pin bidirectional line
					(at 0 -71.12 0)
					(length 5.08)
					(name "HSIO80PB0/CLKIN_N_6"
						(effects
							(font
								(size 1.27 1.27)
							)
						)
					)
					(number "Y19"
						(effects
							(font
								(size 1.27 1.27)
							)
						)
					)
				)
				(pin bidirectional line
					(at 0 -73.66 0)
					(length 5.08)
					(name "HSIO80NB0"
						(effects
							(font
								(size 1.27 1.27)
							)
						)
					)
					(number "Y18"
						(effects
							(font
								(size 1.27 1.27)
							)
						)
					)
				)
				(pin bidirectional line
					(at 91.44 0 180)
					(length 5.08)
					(name "HSIO81PB0/DQS"
						(effects
							(font
								(size 1.27 1.27)
							)
						)
					)
					(number "AB17"
						(effects
							(font
								(size 1.27 1.27)
							)
						)
					)
				)
				(pin bidirectional line
					(at 91.44 -2.54 180)
					(length 5.08)
					(name "HSIO81NB0/DQS"
						(effects
							(font
								(size 1.27 1.27)
							)
						)
					)
					(number "AA17"
						(effects
							(font
								(size 1.27 1.27)
							)
						)
					)
				)
				(pin bidirectional line
					(at 91.44 -5.08 180)
					(length 5.08)
					(name "HSIO82PB0"
						(effects
							(font
								(size 1.27 1.27)
							)
						)
					)
					(number "AA16"
						(effects
							(font
								(size 1.27 1.27)
							)
						)
					)
				)
				(pin bidirectional line
					(at 91.44 -7.62 180)
					(length 5.08)
					(name "HSIO82NB0"
						(effects
							(font
								(size 1.27 1.27)
							)
						)
					)
					(number "Y16"
						(effects
							(font
								(size 1.27 1.27)
							)
						)
					)
				)
				(pin bidirectional line
					(at 91.44 -10.16 180)
					(length 5.08)
					(name "HSIO83PB0"
						(effects
							(font
								(size 1.27 1.27)
							)
						)
					)
					(number "W16"
						(effects
							(font
								(size 1.27 1.27)
							)
						)
					)
				)
				(pin bidirectional line
					(at 91.44 -12.7 180)
					(length 5.08)
					(name "HSIO83NB0"
						(effects
							(font
								(size 1.27 1.27)
							)
						)
					)
					(number "W17"
						(effects
							(font
								(size 1.27 1.27)
							)
						)
					)
				)
				(pin bidirectional line
					(at 91.44 -15.24 180)
					(length 5.08)
					(name "HSIO84PB0/CLKIN_N_5"
						(effects
							(font
								(size 1.27 1.27)
							)
						)
					)
					(number "AB14"
						(effects
							(font
								(size 1.27 1.27)
							)
						)
					)
				)
				(pin bidirectional line
					(at 91.44 -17.78 180)
					(length 5.08)
					(name "HSIO84NB0"
						(effects
							(font
								(size 1.27 1.27)
							)
						)
					)
					(number "AB15"
						(effects
							(font
								(size 1.27 1.27)
							)
						)
					)
				)
				(pin bidirectional line
					(at 91.44 -20.32 180)
					(length 5.08)
					(name "HSIO85PB0/CCC_NW_PLL0_OUT1"
						(effects
							(font
								(size 1.27 1.27)
							)
						)
					)
					(number "Y15"
						(effects
							(font
								(size 1.27 1.27)
							)
						)
					)
				)
				(pin bidirectional line
					(at 91.44 -22.86 180)
					(length 5.08)
					(name "HSIO85NB0"
						(effects
							(font
								(size 1.27 1.27)
							)
						)
					)
					(number "AA15"
						(effects
							(font
								(size 1.27 1.27)
							)
						)
					)
				)
				(pin bidirectional line
					(at 91.44 -25.4 180)
					(length 5.08)
					(name "HSIO86PB0/CLKIN_N_4/CCC_NW_PLL0_OUT0"
						(effects
							(font
								(size 1.27 1.27)
							)
						)
					)
					(number "AA13"
						(effects
							(font
								(size 1.27 1.27)
							)
						)
					)
				)
				(pin bidirectional line
					(at 91.44 -27.94 180)
					(length 5.08)
					(name "HSIO86NB0"
						(effects
							(font
								(size 1.27 1.27)
							)
						)
					)
					(number "AB13"
						(effects
							(font
								(size 1.27 1.27)
							)
						)
					)
				)
				(pin bidirectional line
					(at 91.44 -30.48 180)
					(length 5.08)
					(name "HSIO87PB0/DQS/CCC_NW_PLL0_OUT0"
						(effects
							(font
								(size 1.27 1.27)
							)
						)
					)
					(number "Y14"
						(effects
							(font
								(size 1.27 1.27)
							)
						)
					)
				)
				(pin bidirectional line
					(at 91.44 -33.02 180)
					(length 5.08)
					(name "HSIO87NB0/DQS"
						(effects
							(font
								(size 1.27 1.27)
							)
						)
					)
					(number "W14"
						(effects
							(font
								(size 1.27 1.27)
							)
						)
					)
				)
				(pin bidirectional line
					(at 91.44 -35.56 180)
					(length 5.08)
					(name "HSIO88PB0"
						(effects
							(font
								(size 1.27 1.27)
							)
						)
					)
					(number "AA12"
						(effects
							(font
								(size 1.27 1.27)
							)
						)
					)
				)
				(pin bidirectional line
					(at 91.44 -38.1 180)
					(length 5.08)
					(name "HSIO88NB0"
						(effects
							(font
								(size 1.27 1.27)
							)
						)
					)
					(number "AB12"
						(effects
							(font
								(size 1.27 1.27)
							)
						)
					)
				)
				(pin bidirectional line
					(at 91.44 -40.64 180)
					(length 5.08)
					(name "HSIO89PB0"
						(effects
							(font
								(size 1.27 1.27)
							)
						)
					)
					(number "W13"
						(effects
							(font
								(size 1.27 1.27)
							)
						)
					)
				)
				(pin bidirectional line
					(at 91.44 -43.18 180)
					(length 5.08)
					(name "HSIO89NB0"
						(effects
							(font
								(size 1.27 1.27)
							)
						)
					)
					(number "Y13"
						(effects
							(font
								(size 1.27 1.27)
							)
						)
					)
				)
				(pin bidirectional line
					(at 91.44 -45.72 180)
					(length 5.08)
					(name "HSIO90PB0/CLKIN_N_3/CCC_NW_CLKIN_N_3"
						(effects
							(font
								(size 1.27 1.27)
							)
						)
					)
					(number "V14"
						(effects
							(font
								(size 1.27 1.27)
							)
						)
					)
				)
				(pin bidirectional line
					(at 91.44 -48.26 180)
					(length 5.08)
					(name "HSIO90NB0"
						(effects
							(font
								(size 1.27 1.27)
							)
						)
					)
					(number "V15"
						(effects
							(font
								(size 1.27 1.27)
							)
						)
					)
				)
				(pin bidirectional line
					(at 91.44 -50.8 180)
					(length 5.08)
					(name "HSIO91PB0/CCC_NW_PLL1_OUT1"
						(effects
							(font
								(size 1.27 1.27)
							)
						)
					)
					(number "U15"
						(effects
							(font
								(size 1.27 1.27)
							)
						)
					)
				)
				(pin bidirectional line
					(at 91.44 -53.34 180)
					(length 5.08)
					(name "HSIO91NB0"
						(effects
							(font
								(size 1.27 1.27)
							)
						)
					)
					(number "T15"
						(effects
							(font
								(size 1.27 1.27)
							)
						)
					)
				)
				(pin bidirectional line
					(at 91.44 -55.88 180)
					(length 5.08)
					(name "HSIO92PB0/CLKIN_N_2/CCC_NW_CLKIN_N_2/CCC_NW_PLL1_OUT0"
						(effects
							(font
								(size 1.27 1.27)
							)
						)
					)
					(number "W12"
						(effects
							(font
								(size 1.27 1.27)
							)
						)
					)
				)
				(pin bidirectional line
					(at 91.44 -58.42 180)
					(length 5.08)
					(name "HSIO92NB0"
						(effects
							(font
								(size 1.27 1.27)
							)
						)
					)
					(number "V12"
						(effects
							(font
								(size 1.27 1.27)
							)
						)
					)
				)
				(pin bidirectional line
					(at 91.44 -60.96 180)
					(length 5.08)
					(name "HSIO93PB0/DQS/CCC_NW_PLL1_OUT0"
						(effects
							(font
								(size 1.27 1.27)
							)
						)
					)
					(number "U14"
						(effects
							(font
								(size 1.27 1.27)
							)
						)
					)
				)
				(pin bidirectional line
					(at 91.44 -63.5 180)
					(length 5.08)
					(name "HSIO93NB0/DQS"
						(effects
							(font
								(size 1.27 1.27)
							)
						)
					)
					(number "U13"
						(effects
							(font
								(size 1.27 1.27)
							)
						)
					)
				)
				(pin bidirectional line
					(at 91.44 -66.04 180)
					(length 5.08)
					(name "HSIO94PB0/CCC_NW_CLKIN_N_1"
						(effects
							(font
								(size 1.27 1.27)
							)
						)
					)
					(number "U12"
						(effects
							(font
								(size 1.27 1.27)
							)
						)
					)
				)
				(pin bidirectional line
					(at 91.44 -68.58 180)
					(length 5.08)
					(name "HSIO94NB0"
						(effects
							(font
								(size 1.27 1.27)
							)
						)
					)
					(number "T12"
						(effects
							(font
								(size 1.27 1.27)
							)
						)
					)
				)
				(pin bidirectional line
					(at 91.44 -71.12 180)
					(length 5.08)
					(name "HSIO95PB0/CCC_NW_CLKIN_N_0"
						(effects
							(font
								(size 1.27 1.27)
							)
						)
					)
					(number "R12"
						(effects
							(font
								(size 1.27 1.27)
							)
						)
					)
				)
				(pin bidirectional line
					(at 91.44 -73.66 180)
					(length 5.08)
					(name "HSIO95NB0"
						(effects
							(font
								(size 1.27 1.27)
							)
						)
					)
					(number "T13"
						(effects
							(font
								(size 1.27 1.27)
							)
						)
					)
				)
			)
			(symbol "MPFS250T-FCVG484E_2_1"
				(rectangle
					(start 5.08 5.08)
					(end 86.36 -106.68)
					(stroke
						(width 0.254)
						(type default)
					)
					(fill
						(type background)
					)
				)
				(text "BANK 1"
					(at 41.91 1.27 0)
					(effects
						(font
							(size 1.27 1.27)
							(thickness 0.15)
						)
						(justify left bottom)
					)
				)
				(pin bidirectional line
					(at 0 0 0)
					(length 5.08)
					(name "GPIO0PB1/CLKIN_S_4"
						(effects
							(font
								(size 1.27 1.27)
							)
						)
					)
					(number "B12"
						(effects
							(font
								(size 1.27 1.27)
							)
						)
					)
				)
				(pin bidirectional line
					(at 0 -2.54 0)
					(length 5.08)
					(name "GPIO0NB1"
						(effects
							(font
								(size 1.27 1.27)
							)
						)
					)
					(number "C12"
						(effects
							(font
								(size 1.27 1.27)
							)
						)
					)
				)
				(pin bidirectional line
					(at 0 -5.08 0)
					(length 5.08)
					(name "GPIO1PB1/CLKIN_S_5"
						(effects
							(font
								(size 1.27 1.27)
							)
						)
					)
					(number "A13"
						(effects
							(font
								(size 1.27 1.27)
							)
						)
					)
				)
				(pin bidirectional line
					(at 0 -7.62 0)
					(length 5.08)
					(name "GPIO1NB1"
						(effects
							(font
								(size 1.27 1.27)
							)
						)
					)
					(number "A12"
						(effects
							(font
								(size 1.27 1.27)
							)
						)
					)
				)
				(pin bidirectional line
					(at 0 -10.16 0)
					(length 5.08)
					(name "GPIO2PB1/DQS"
						(effects
							(font
								(size 1.27 1.27)
							)
						)
					)
					(number "D13"
						(effects
							(font
								(size 1.27 1.27)
							)
						)
					)
				)
				(pin bidirectional line
					(at 0 -12.7 0)
					(length 5.08)
					(name "GPIO2NB1/DQS"
						(effects
							(font
								(size 1.27 1.27)
							)
						)
					)
					(number "D14"
						(effects
							(font
								(size 1.27 1.27)
							)
						)
					)
				)
				(pin bidirectional line
					(at 0 -15.24 0)
					(length 5.08)
					(name "GPIO3PB1/CLKIN_S_6"
						(effects
							(font
								(size 1.27 1.27)
							)
						)
					)
					(number "B13"
						(effects
							(font
								(size 1.27 1.27)
							)
						)
					)
				)
				(pin bidirectional line
					(at 0 -17.78 0)
					(length 5.08)
					(name "GPIO3NB1"
						(effects
							(font
								(size 1.27 1.27)
							)
						)
					)
					(number "B14"
						(effects
							(font
								(size 1.27 1.27)
							)
						)
					)
				)
				(pin bidirectional line
					(at 0 -20.32 0)
					(length 5.08)
					(name "GPIO4PB1/LPRB_A"
						(effects
							(font
								(size 1.27 1.27)
							)
						)
					)
					(number "C14"
						(effects
							(font
								(size 1.27 1.27)
							)
						)
					)
				)
				(pin bidirectional line
					(at 0 -22.86 0)
					(length 5.08)
					(name "GPIO4NB1/LPRB_B"
						(effects
							(font
								(size 1.27 1.27)
							)
						)
					)
					(number "C15"
						(effects
							(font
								(size 1.27 1.27)
							)
						)
					)
				)
				(pin bidirectional line
					(at 0 -25.4 0)
					(length 5.08)
					(name "GPIO5PB1/CLKIN_S_7"
						(effects
							(font
								(size 1.27 1.27)
							)
						)
					)
					(number "A15"
						(effects
							(font
								(size 1.27 1.27)
							)
						)
					)
				)
				(pin bidirectional line
					(at 0 -27.94 0)
					(length 5.08)
					(name "GPIO5NB1"
						(effects
							(font
								(size 1.27 1.27)
							)
						)
					)
					(number "B15"
						(effects
							(font
								(size 1.27 1.27)
							)
						)
					)
				)
				(pin bidirectional line
					(at 0 -30.48 0)
					(length 5.08)
					(name "GPIO6PB1"
						(effects
							(font
								(size 1.27 1.27)
							)
						)
					)
					(number "F15"
						(effects
							(font
								(size 1.27 1.27)
							)
						)
					)
				)
				(pin bidirectional line
					(at 0 -33.02 0)
					(length 5.08)
					(name "GPIO6NB1"
						(effects
							(font
								(size 1.27 1.27)
							)
						)
					)
					(number "G14"
						(effects
							(font
								(size 1.27 1.27)
							)
						)
					)
				)
				(pin bidirectional line
					(at 0 -35.56 0)
					(length 5.08)
					(name "GPIO7PB1"
						(effects
							(font
								(size 1.27 1.27)
							)
						)
					)
					(number "G15"
						(effects
							(font
								(size 1.27 1.27)
							)
						)
					)
				)
				(pin bidirectional line
					(at 0 -38.1 0)
					(length 5.08)
					(name "GPIO7NB1"
						(effects
							(font
								(size 1.27 1.27)
							)
						)
					)
					(number "H15"
						(effects
							(font
								(size 1.27 1.27)
							)
						)
					)
				)
				(pin bidirectional line
					(at 0 -40.64 0)
					(length 5.08)
					(name "GPIO8PB1/DQS/CCC_SE_PLL0_OUT0"
						(effects
							(font
								(size 1.27 1.27)
							)
						)
					)
					(number "G17"
						(effects
							(font
								(size 1.27 1.27)
							)
						)
					)
				)
				(pin bidirectional line
					(at 0 -43.18 0)
					(length 5.08)
					(name "GPIO8NB1/DQS"
						(effects
							(font
								(size 1.27 1.27)
							)
						)
					)
					(number "H17"
						(effects
							(font
								(size 1.27 1.27)
							)
						)
					)
				)
				(pin bidirectional line
					(at 0 -45.72 0)
					(length 5.08)
					(name "GPIO9PB1/CLKIN_S_8/CCC_SE_CLKIN_S_8/CCC_SE_PLL0_OUT0"
						(effects
							(font
								(size 1.27 1.27)
							)
						)
					)
					(number "E15"
						(effects
							(font
								(size 1.27 1.27)
							)
						)
					)
				)
				(pin bidirectional line
					(at 0 -48.26 0)
					(length 5.08)
					(name "GPIO9NB1"
						(effects
							(font
								(size 1.27 1.27)
							)
						)
					)
					(number "E14"
						(effects
							(font
								(size 1.27 1.27)
							)
						)
					)
				)
				(pin bidirectional line
					(at 0 -50.8 0)
					(length 5.08)
					(name "GPIO10PB1/CCC_SE_PLL0_OUT1"
						(effects
							(font
								(size 1.27 1.27)
							)
						)
					)
					(number "E16"
						(effects
							(font
								(size 1.27 1.27)
							)
						)
					)
				)
				(pin bidirectional line
					(at 0 -53.34 0)
					(length 5.08)
					(name "GPIO10NB1"
						(effects
							(font
								(size 1.27 1.27)
							)
						)
					)
					(number "D16"
						(effects
							(font
								(size 1.27 1.27)
							)
						)
					)
				)
				(pin bidirectional line
					(at 0 -55.88 0)
					(length 5.08)
					(name "GPIO11PB1/CLKIN_S_9/CCC_SE_CLKIN_S_9"
						(effects
							(font
								(size 1.27 1.27)
							)
						)
					)
					(number "F17"
						(effects
							(font
								(size 1.27 1.27)
							)
						)
					)
				)
				(pin bidirectional line
					(at 0 -58.42 0)
					(length 5.08)
					(name "GPIO11NB1"
						(effects
							(font
								(size 1.27 1.27)
							)
						)
					)
					(number "F16"
						(effects
							(font
								(size 1.27 1.27)
							)
						)
					)
				)
				(pin bidirectional line
					(at 0 -60.96 0)
					(length 5.08)
					(name "GPIO12PB1"
						(effects
							(font
								(size 1.27 1.27)
							)
						)
					)
					(number "C16"
						(effects
							(font
								(size 1.27 1.27)
							)
						)
					)
				)
				(pin bidirectional line
					(at 0 -63.5 0)
					(length 5.08)
					(name "GPIO12NB1"
						(effects
							(font
								(size 1.27 1.27)
							)
						)
					)
					(number "D17"
						(effects
							(font
								(size 1.27 1.27)
							)
						)
					)
				)
				(pin bidirectional line
					(at 0 -66.04 0)
					(length 5.08)
					(name "GPIO13PB1"
						(effects
							(font
								(size 1.27 1.27)
							)
						)
					)
					(number "A16"
						(effects
							(font
								(size 1.27 1.27)
							)
						)
					)
				)
				(pin bidirectional line
					(at 0 -68.58 0)
					(length 5.08)
					(name "GPIO13NB1"
						(effects
							(font
								(size 1.27 1.27)
							)
						)
					)
					(number "A17"
						(effects
							(font
								(size 1.27 1.27)
							)
						)
					)
				)
				(pin bidirectional line
					(at 0 -71.12 0)
					(length 5.08)
					(name "GPIO14PB1/DQS/CCC_SE_PLL1_OUT0"
						(effects
							(font
								(size 1.27 1.27)
							)
						)
					)
					(number "E19"
						(effects
							(font
								(size 1.27 1.27)
							)
						)
					)
				)
				(pin bidirectional line
					(at 0 -73.66 0)
					(length 5.08)
					(name "GPIO14NB1/DQS"
						(effects
							(font
								(size 1.27 1.27)
							)
						)
					)
					(number "D19"
						(effects
							(font
								(size 1.27 1.27)
							)
						)
					)
				)
				(pin bidirectional line
					(at 0 -76.2 0)
					(length 5.08)
					(name "GPIO15PB1/CCC_SE_CLKIN_S_10/CCC_SE_PLL1_OUT0"
						(effects
							(font
								(size 1.27 1.27)
							)
						)
					)
					(number "B17"
						(effects
							(font
								(size 1.27 1.27)
							)
						)
					)
				)
				(pin bidirectional line
					(at 0 -78.74 0)
					(length 5.08)
					(name "GPIO15NB1"
						(effects
							(font
								(size 1.27 1.27)
							)
						)
					)
					(number "C17"
						(effects
							(font
								(size 1.27 1.27)
							)
						)
					)
				)
				(pin bidirectional line
					(at 0 -81.28 0)
					(length 5.08)
					(name "GPIO16PB1/CCC_SE_PLL1_OUT1"
						(effects
							(font
								(size 1.27 1.27)
							)
						)
					)
					(number "D18"
						(effects
							(font
								(size 1.27 1.27)
							)
						)
					)
				)
				(pin bidirectional line
					(at 0 -83.82 0)
					(length 5.08)
					(name "GPIO16NB1"
						(effects
							(font
								(size 1.27 1.27)
							)
						)
					)
					(number "E18"
						(effects
							(font
								(size 1.27 1.27)
							)
						)
					)
				)
				(pin bidirectional line
					(at 0 -86.36 0)
					(length 5.08)
					(name "GPIO17PB1/CCC_SE_CLKIN_S_11"
						(effects
							(font
								(size 1.27 1.27)
							)
						)
					)
					(number "A18"
						(effects
							(font
								(size 1.27 1.27)
							)
						)
					)
				)
				(pin bidirectional line
					(at 0 -88.9 0)
					(length 5.08)
					(name "GPIO17NB1"
						(effects
							(font
								(size 1.27 1.27)
							)
						)
					)
					(number "B18"
						(effects
							(font
								(size 1.27 1.27)
							)
						)
					)
				)
				(pin bidirectional line
					(at 0 -91.44 0)
					(length 5.08)
					(name "GPIO18PB9"
						(effects
							(font
								(size 1.27 1.27)
							)
						)
					)
					(number "C19"
						(effects
							(font
								(size 1.27 1.27)
							)
						)
					)
				)
				(pin bidirectional line
					(at 0 -93.98 0)
					(length 5.08)
					(name "GPIO18NB9"
						(effects
							(font
								(size 1.27 1.27)
							)
						)
					)
					(number "C20"
						(effects
							(font
								(size 1.27 1.27)
							)
						)
					)
				)
				(pin bidirectional line
					(at 0 -96.52 0)
					(length 5.08)
					(name "GPIO19PB9"
						(effects
							(font
								(size 1.27 1.27)
							)
						)
					)
					(number "B20"
						(effects
							(font
								(size 1.27 1.27)
							)
						)
					)
				)
				(pin bidirectional line
					(at 0 -99.06 0)
					(length 5.08)
					(name "GPIO19NB9"
						(effects
							(font
								(size 1.27 1.27)
							)
						)
					)
					(number "B19"
						(effects
							(font
								(size 1.27 1.27)
							)
						)
					)
				)
				(pin bidirectional line
					(at 0 -101.6 0)
					(length 5.08)
					(name "GPIO20PB9/DQS"
						(effects
							(font
								(size 1.27 1.27)
							)
						)
					)
					(number "A20"
						(effects
							(font
								(size 1.27 1.27)
							)
						)
					)
				)
				(pin bidirectional line
					(at 0 -104.14 0)
					(length 5.08)
					(name "GPIO20NB9/DQS"
						(effects
							(font
								(size 1.27 1.27)
							)
						)
					)
					(number "A21"
						(effects
							(font
								(size 1.27 1.27)
							)
						)
					)
				)
				(pin bidirectional line
					(at 91.44 0 180)
					(length 5.08)
					(name "GPIO21PB9"
						(effects
							(font
								(size 1.27 1.27)
							)
						)
					)
					(number "D21"
						(effects
							(font
								(size 1.27 1.27)
							)
						)
					)
				)
				(pin bidirectional line
					(at 91.44 -2.54 180)
					(length 5.08)
					(name "GPIO21NB9"
						(effects
							(font
								(size 1.27 1.27)
							)
						)
					)
					(number "D20"
						(effects
							(font
								(size 1.27 1.27)
							)
						)
					)
				)
				(pin bidirectional line
					(at 91.44 -5.08 180)
					(length 5.08)
					(name "GPIO22PB9"
						(effects
							(font
								(size 1.27 1.27)
							)
						)
					)
					(number "B21"
						(effects
							(font
								(size 1.27 1.27)
							)
						)
					)
				)
				(pin bidirectional line
					(at 91.44 -7.62 180)
					(length 5.08)
					(name "GPIO22NB9"
						(effects
							(font
								(size 1.27 1.27)
							)
						)
					)
					(number "B22"
						(effects
							(font
								(size 1.27 1.27)
							)
						)
					)
				)
				(pin bidirectional line
					(at 91.44 -10.16 180)
					(length 5.08)
					(name "GPIO23PB9"
						(effects
							(font
								(size 1.27 1.27)
							)
						)
					)
					(number "C22"
						(effects
							(font
								(size 1.27 1.27)
							)
						)
					)
				)
				(pin bidirectional line
					(at 91.44 -12.7 180)
					(length 5.08)
					(name "GPIO23NB9"
						(effects
							(font
								(size 1.27 1.27)
							)
						)
					)
					(number "D22"
						(effects
							(font
								(size 1.27 1.27)
							)
						)
					)
				)
				(pin bidirectional line
					(at 91.44 -15.24 180)
					(length 5.08)
					(name "GPIO168PB1/CCC_SW_CLKIN_S_0"
						(effects
							(font
								(size 1.27 1.27)
							)
						)
					)
					(number "D7"
						(effects
							(font
								(size 1.27 1.27)
							)
						)
					)
				)
				(pin bidirectional line
					(at 91.44 -17.78 180)
					(length 5.08)
					(name "GPIO168NB1"
						(effects
							(font
								(size 1.27 1.27)
							)
						)
					)
					(number "D6"
						(effects
							(font
								(size 1.27 1.27)
							)
						)
					)
				)
				(pin bidirectional line
					(at 91.44 -20.32 180)
					(length 5.08)
					(name "GPIO169PB1/CCC_SW_CLKIN_S_1"
						(effects
							(font
								(size 1.27 1.27)
							)
						)
					)
					(number "C4"
						(effects
							(font
								(size 1.27 1.27)
							)
						)
					)
				)
				(pin bidirectional line
					(at 91.44 -22.86 180)
					(length 5.08)
					(name "GPIO169NB1"
						(effects
							(font
								(size 1.27 1.27)
							)
						)
					)
					(number "B4"
						(effects
							(font
								(size 1.27 1.27)
							)
						)
					)
				)
				(pin bidirectional line
					(at 91.44 -25.4 180)
					(length 5.08)
					(name "GPIO170PB1/DQS/CCC_SW_PLL1_OUT0"
						(effects
							(font
								(size 1.27 1.27)
							)
						)
					)
					(number "C5"
						(effects
							(font
								(size 1.27 1.27)
							)
						)
					)
				)
				(pin bidirectional line
					(at 91.44 -27.94 180)
					(length 5.08)
					(name "GPIO170NB1/DQS"
						(effects
							(font
								(size 1.27 1.27)
							)
						)
					)
					(number "B5"
						(effects
							(font
								(size 1.27 1.27)
							)
						)
					)
				)
				(pin bidirectional line
					(at 91.44 -30.48 180)
					(length 5.08)
					(name "GPIO171PB1/CLKIN_S_2/CCC_SW_CLKIN_S_2/CCC_SW_PLL1_OUT0"
						(effects
							(font
								(size 1.27 1.27)
							)
						)
					)
					(number "C6"
						(effects
							(font
								(size 1.27 1.27)
							)
						)
					)
				)
				(pin bidirectional line
					(at 91.44 -33.02 180)
					(length 5.08)
					(name "GPIO171NB1"
						(effects
							(font
								(size 1.27 1.27)
							)
						)
					)
					(number "C7"
						(effects
							(font
								(size 1.27 1.27)
							)
						)
					)
				)
				(pin bidirectional line
					(at 91.44 -35.56 180)
					(length 5.08)
					(name "GPIO172PB1/CCC_SW_PLL1_OUT1"
						(effects
							(font
								(size 1.27 1.27)
							)
						)
					)
					(number "A6"
						(effects
							(font
								(size 1.27 1.27)
							)
						)
					)
				)
				(pin bidirectional line
					(at 91.44 -38.1 180)
					(length 5.08)
					(name "GPIO172NB1"
						(effects
							(font
								(size 1.27 1.27)
							)
						)
					)
					(number "A5"
						(effects
							(font
								(size 1.27 1.27)
							)
						)
					)
				)
				(pin bidirectional line
					(at 91.44 -40.64 180)
					(length 5.08)
					(name "GPIO173PB1/CLKIN_S_3/CCC_SW_CLKIN_S_3"
						(effects
							(font
								(size 1.27 1.27)
							)
						)
					)
					(number "A7"
						(effects
							(font
								(size 1.27 1.27)
							)
						)
					)
				)
				(pin bidirectional line
					(at 91.44 -43.18 180)
					(length 5.08)
					(name "GPIO173NB1"
						(effects
							(font
								(size 1.27 1.27)
							)
						)
					)
					(number "B7"
						(effects
							(font
								(size 1.27 1.27)
							)
						)
					)
				)
				(pin bidirectional line
					(at 91.44 -45.72 180)
					(length 5.08)
					(name "GPIO174PB1"
						(effects
							(font
								(size 1.27 1.27)
							)
						)
					)
					(number "D9"
						(effects
							(font
								(size 1.27 1.27)
							)
						)
					)
				)
				(pin bidirectional line
					(at 91.44 -48.26 180)
					(length 5.08)
					(name "GPIO174NB1"
						(effects
							(font
								(size 1.27 1.27)
							)
						)
					)
					(number "D8"
						(effects
							(font
								(size 1.27 1.27)
							)
						)
					)
				)
				(pin bidirectional line
					(at 91.44 -50.8 180)
					(length 5.08)
					(name "GPIO175PB1"
						(effects
							(font
								(size 1.27 1.27)
							)
						)
					)
					(number "A8"
						(effects
							(font
								(size 1.27 1.27)
							)
						)
					)
				)
				(pin bidirectional line
					(at 91.44 -53.34 180)
					(length 5.08)
					(name "GPIO175NB1"
						(effects
							(font
								(size 1.27 1.27)
							)
						)
					)
					(number "B8"
						(effects
							(font
								(size 1.27 1.27)
							)
						)
					)
				)
				(pin bidirectional line
					(at 91.44 -55.88 180)
					(length 5.08)
					(name "GPIO176PB1/DQS/CCC_SW_PLL0_OUT0"
						(effects
							(font
								(size 1.27 1.27)
							)
						)
					)
					(number "C10"
						(effects
							(font
								(size 1.27 1.27)
							)
						)
					)
				)
				(pin bidirectional line
					(at 91.44 -58.42 180)
					(length 5.08)
					(name "GPIO176NB1/DQS"
						(effects
							(font
								(size 1.27 1.27)
							)
						)
					)
					(number "C9"
						(effects
							(font
								(size 1.27 1.27)
							)
						)
					)
				)
				(pin bidirectional line
					(at 91.44 -60.96 180)
					(length 5.08)
					(name "GPIO177PB1/CCC_SW_PLL0_OUT0"
						(effects
							(font
								(size 1.27 1.27)
							)
						)
					)
					(number "A10"
						(effects
							(font
								(size 1.27 1.27)
							)
						)
					)
				)
				(pin bidirectional line
					(at 91.44 -63.5 180)
					(length 5.08)
					(name "GPIO177NB1"
						(effects
							(font
								(size 1.27 1.27)
							)
						)
					)
					(number "A11"
						(effects
							(font
								(size 1.27 1.27)
							)
						)
					)
				)
				(pin bidirectional line
					(at 91.44 -66.04 180)
					(length 5.08)
					(name "GPIO178PB1/CCC_SW_PLL0_OUT1"
						(effects
							(font
								(size 1.27 1.27)
							)
						)
					)
					(number "C11"
						(effects
							(font
								(size 1.27 1.27)
							)
						)
					)
				)
				(pin bidirectional line
					(at 91.44 -68.58 180)
					(length 5.08)
					(name "GPIO178NB1"
						(effects
							(font
								(size 1.27 1.27)
							)
						)
					)
					(number "D11"
						(effects
							(font
								(size 1.27 1.27)
							)
						)
					)
				)
				(pin bidirectional line
					(at 91.44 -71.12 180)
					(length 5.08)
					(name "GPIO179PB1"
						(effects
							(font
								(size 1.27 1.27)
							)
						)
					)
					(number "B10"
						(effects
							(font
								(size 1.27 1.27)
							)
						)
					)
				)
				(pin bidirectional line
					(at 91.44 -73.66 180)
					(length 5.08)
					(name "GPIO179NB1"
						(effects
							(font
								(size 1.27 1.27)
							)
						)
					)
					(number "B9"
						(effects
							(font
								(size 1.27 1.27)
							)
						)
					)
				)
				(pin bidirectional line
					(at 91.44 -76.2 180)
					(length 5.08)
					(name "GPIO180PB1"
						(effects
							(font
								(size 1.27 1.27)
							)
						)
					)
					(number "E10"
						(effects
							(font
								(size 1.27 1.27)
							)
						)
					)
				)
				(pin bidirectional line
					(at 91.44 -78.74 180)
					(length 5.08)
					(name "GPIO180NB1"
						(effects
							(font
								(size 1.27 1.27)
							)
						)
					)
					(number "F10"
						(effects
							(font
								(size 1.27 1.27)
							)
						)
					)
				)
				(pin bidirectional line
					(at 91.44 -81.28 180)
					(length 5.08)
					(name "GPIO181PB1"
						(effects
							(font
								(size 1.27 1.27)
							)
						)
					)
					(number "F12"
						(effects
							(font
								(size 1.27 1.27)
							)
						)
					)
				)
				(pin bidirectional line
					(at 91.44 -83.82 180)
					(length 5.08)
					(name "GPIO181NB1"
						(effects
							(font
								(size 1.27 1.27)
							)
						)
					)
					(number "F11"
						(effects
							(font
								(size 1.27 1.27)
							)
						)
					)
				)
				(pin bidirectional line
					(at 91.44 -86.36 180)
					(length 5.08)
					(name "GPIO182PB1/DQS"
						(effects
							(font
								(size 1.27 1.27)
							)
						)
					)
					(number "H12"
						(effects
							(font
								(size 1.27 1.27)
							)
						)
					)
				)
				(pin bidirectional line
					(at 91.44 -88.9 180)
					(length 5.08)
					(name "GPIO182NB1/DQS"
						(effects
							(font
								(size 1.27 1.27)
							)
						)
					)
					(number "G12"
						(effects
							(font
								(size 1.27 1.27)
							)
						)
					)
				)
				(pin bidirectional line
					(at 91.44 -91.44 180)
					(length 5.08)
					(name "GPIO183PB1"
						(effects
							(font
								(size 1.27 1.27)
							)
						)
					)
					(number "D12"
						(effects
							(font
								(size 1.27 1.27)
							)
						)
					)
				)
				(pin bidirectional line
					(at 91.44 -93.98 180)
					(length 5.08)
					(name "GPIO183NB1"
						(effects
							(font
								(size 1.27 1.27)
							)
						)
					)
					(number "E11"
						(effects
							(font
								(size 1.27 1.27)
							)
						)
					)
				)
				(pin bidirectional line
					(at 91.44 -96.52 180)
					(length 5.08)
					(name "GPIO184PB1"
						(effects
							(font
								(size 1.27 1.27)
							)
						)
					)
					(number "E13"
						(effects
							(font
								(size 1.27 1.27)
							)
						)
					)
				)
				(pin bidirectional line
					(at 91.44 -99.06 180)
					(length 5.08)
					(name "GPIO184NB1"
						(effects
							(font
								(size 1.27 1.27)
							)
						)
					)
					(number "F13"
						(effects
							(font
								(size 1.27 1.27)
							)
						)
					)
				)
				(pin bidirectional line
					(at 91.44 -101.6 180)
					(length 5.08)
					(name "GPIO185PB1"
						(effects
							(font
								(size 1.27 1.27)
							)
						)
					)
					(number "G13"
						(effects
							(font
								(size 1.27 1.27)
							)
						)
					)
				)
				(pin bidirectional line
					(at 91.44 -104.14 180)
					(length 5.08)
					(name "GPIO185NB1"
						(effects
							(font
								(size 1.27 1.27)
							)
						)
					)
					(number "H13"
						(effects
							(font
								(size 1.27 1.27)
							)
						)
					)
				)
			)
			(symbol "MPFS250T-FCVG484E_3_1"
				(rectangle
					(start 5.08 5.08)
					(end 30.48 -30.48)
					(stroke
						(width 0.254)
						(type default)
					)
					(fill
						(type background)
					)
				)
				(text "BANK 2"
					(at 13.97 2.54 0)
					(effects
						(font
							(size 1.27 1.27)
							(thickness 0.15)
						)
						(justify left bottom)
					)
				)
				(pin bidirectional line
					(at 0 0 0)
					(length 5.08)
					(name "MSSIO14B2"
						(effects
							(font
								(size 1.27 1.27)
							)
						)
					)
					(number "G2"
						(effects
							(font
								(size 1.27 1.27)
							)
						)
					)
				)
				(pin bidirectional line
					(at 0 -2.54 0)
					(length 5.08)
					(name "MSSIO15B2"
						(effects
							(font
								(size 1.27 1.27)
							)
						)
					)
					(number "F1"
						(effects
							(font
								(size 1.27 1.27)
							)
						)
					)
				)
				(pin bidirectional line
					(at 0 -5.08 0)
					(length 5.08)
					(name "MSSIO16B2"
						(effects
							(font
								(size 1.27 1.27)
							)
						)
					)
					(number "G5"
						(effects
							(font
								(size 1.27 1.27)
							)
						)
					)
				)
				(pin bidirectional line
					(at 0 -7.62 0)
					(length 5.08)
					(name "MSSIO17B2"
						(effects
							(font
								(size 1.27 1.27)
							)
						)
					)
					(number "G4"
						(effects
							(font
								(size 1.27 1.27)
							)
						)
					)
				)
				(pin bidirectional line
					(at 0 -10.16 0)
					(length 5.08)
					(name "MSSIO18B2"
						(effects
							(font
								(size 1.27 1.27)
							)
						)
					)
					(number "F2"
						(effects
							(font
								(size 1.27 1.27)
							)
						)
					)
				)
				(pin bidirectional line
					(at 0 -12.7 0)
					(length 5.08)
					(name "MSSIO19B2"
						(effects
							(font
								(size 1.27 1.27)
							)
						)
					)
					(number "E1"
						(effects
							(font
								(size 1.27 1.27)
							)
						)
					)
				)
				(pin bidirectional line
					(at 0 -15.24 0)
					(length 5.08)
					(name "MSSIO20B2"
						(effects
							(font
								(size 1.27 1.27)
							)
						)
					)
					(number "G3"
						(effects
							(font
								(size 1.27 1.27)
							)
						)
					)
				)
				(pin bidirectional line
					(at 0 -17.78 0)
					(length 5.08)
					(name "MSSIO21B2"
						(effects
							(font
								(size 1.27 1.27)
							)
						)
					)
					(number "F5"
						(effects
							(font
								(size 1.27 1.27)
							)
						)
					)
				)
				(pin bidirectional line
					(at 0 -20.32 0)
					(length 5.08)
					(name "MSSIO22B2"
						(effects
							(font
								(size 1.27 1.27)
							)
						)
					)
					(number "D1"
						(effects
							(font
								(size 1.27 1.27)
							)
						)
					)
				)
				(pin bidirectional line
					(at 0 -22.86 0)
					(length 5.08)
					(name "MSSIO23B2"
						(effects
							(font
								(size 1.27 1.27)
							)
						)
					)
					(number "D2"
						(effects
							(font
								(size 1.27 1.27)
							)
						)
					)
				)
				(pin bidirectional line
					(at 0 -25.4 0)
					(length 5.08)
					(name "MSSIO24B2"
						(effects
							(font
								(size 1.27 1.27)
							)
						)
					)
					(number "F6"
						(effects
							(font
								(size 1.27 1.27)
							)
						)
					)
				)
				(pin bidirectional line
					(at 0 -27.94 0)
					(length 5.08)
					(name "MSSIO25B2"
						(effects
							(font
								(size 1.27 1.27)
							)
						)
					)
					(number "F3"
						(effects
							(font
								(size 1.27 1.27)
							)
						)
					)
				)
				(pin bidirectional line
					(at 35.56 0 180)
					(length 5.08)
					(name "MSSIO26B2"
						(effects
							(font
								(size 1.27 1.27)
							)
						)
					)
					(number "C1"
						(effects
							(font
								(size 1.27 1.27)
							)
						)
					)
				)
				(pin bidirectional line
					(at 35.56 -2.54 180)
					(length 5.08)
					(name "MSSIO27B2"
						(effects
							(font
								(size 1.27 1.27)
							)
						)
					)
					(number "B1"
						(effects
							(font
								(size 1.27 1.27)
							)
						)
					)
				)
				(pin bidirectional line
					(at 35.56 -5.08 180)
					(length 5.08)
					(name "MSSIO28B2"
						(effects
							(font
								(size 1.27 1.27)
							)
						)
					)
					(number "D3"
						(effects
							(font
								(size 1.27 1.27)
							)
						)
					)
				)
				(pin bidirectional line
					(at 35.56 -7.62 180)
					(length 5.08)
					(name "MSSIO29B2"
						(effects
							(font
								(size 1.27 1.27)
							)
						)
					)
					(number "C2"
						(effects
							(font
								(size 1.27 1.27)
							)
						)
					)
				)
				(pin bidirectional line
					(at 35.56 -10.16 180)
					(length 5.08)
					(name "MSSIO30B2"
						(effects
							(font
								(size 1.27 1.27)
							)
						)
					)
					(number "E5"
						(effects
							(font
								(size 1.27 1.27)
							)
						)
					)
				)
				(pin bidirectional line
					(at 35.56 -12.7 180)
					(length 5.08)
					(name "MSSIO31B2"
						(effects
							(font
								(size 1.27 1.27)
							)
						)
					)
					(number "E4"
						(effects
							(font
								(size 1.27 1.27)
							)
						)
					)
				)
				(pin bidirectional line
					(at 35.56 -15.24 180)
					(length 5.08)
					(name "MSSIO32B2"
						(effects
							(font
								(size 1.27 1.27)
							)
						)
					)
					(number "B2"
						(effects
							(font
								(size 1.27 1.27)
							)
						)
					)
				)
				(pin bidirectional line
					(at 35.56 -17.78 180)
					(length 5.08)
					(name "MSSIO33B2"
						(effects
							(font
								(size 1.27 1.27)
							)
						)
					)
					(number "A2"
						(effects
							(font
								(size 1.27 1.27)
							)
						)
					)
				)
				(pin bidirectional line
					(at 35.56 -20.32 180)
					(length 5.08)
					(name "MSSIO34B2"
						(effects
							(font
								(size 1.27 1.27)
							)
						)
					)
					(number "B3"
						(effects
							(font
								(size 1.27 1.27)
							)
						)
					)
				)
				(pin bidirectional line
					(at 35.56 -22.86 180)
					(length 5.08)
					(name "MSSIO35B2"
						(effects
							(font
								(size 1.27 1.27)
							)
						)
					)
					(number "A3"
						(effects
							(font
								(size 1.27 1.27)
							)
						)
					)
				)
				(pin bidirectional line
					(at 35.56 -25.4 180)
					(length 5.08)
					(name "MSSIO36B2"
						(effects
							(font
								(size 1.27 1.27)
							)
						)
					)
					(number "E3"
						(effects
							(font
								(size 1.27 1.27)
							)
						)
					)
				)
				(pin bidirectional line
					(at 35.56 -27.94 180)
					(length 5.08)
					(name "MSSIO37B2"
						(effects
							(font
								(size 1.27 1.27)
							)
						)
					)
					(number "D4"
						(effects
							(font
								(size 1.27 1.27)
							)
						)
					)
				)
			)
			(symbol "MPFS250T-FCVG484E_4_1"
				(rectangle
					(start 5.08 5.08)
					(end 30.48 -17.78)
					(stroke
						(width 0.254)
						(type default)
					)
					(fill
						(type background)
					)
				)
				(text "BANK 3"
					(at 13.97 2.54 0)
					(effects
						(font
							(size 1.27 1.27)
							(thickness 0.15)
						)
						(justify left bottom)
					)
				)
				(pin input line
					(at 0 0 0)
					(length 5.08)
					(name "FF_EXIT_N"
						(effects
							(font
								(size 1.27 1.27)
							)
						)
					)
					(number "G10"
						(effects
							(font
								(size 1.27 1.27)
							)
						)
					)
				)
				(pin input line
					(at 0 -2.54 0)
					(length 5.08)
					(name "IO_CFG_INTF"
						(effects
							(font
								(size 1.27 1.27)
							)
						)
					)
					(number "H9"
						(effects
							(font
								(size 1.27 1.27)
							)
						)
					)
				)
				(pin input line
					(at 0 -5.08 0)
					(length 5.08)
					(name "SPI_EN"
						(effects
							(font
								(size 1.27 1.27)
							)
						)
					)
					(number "H11"
						(effects
							(font
								(size 1.27 1.27)
							)
						)
					)
				)
				(pin bidirectional line
					(at 0 -7.62 0)
					(length 5.08)
					(name "SCK"
						(effects
							(font
								(size 1.27 1.27)
							)
						)
					)
					(number "E6"
						(effects
							(font
								(size 1.27 1.27)
							)
						)
					)
				)
				(pin output line
					(at 0 -10.16 0)
					(length 5.08)
					(name "SDO"
						(effects
							(font
								(size 1.27 1.27)
							)
						)
					)
					(number "F7"
						(effects
							(font
								(size 1.27 1.27)
							)
						)
					)
				)
				(pin input line
					(at 0 -12.7 0)
					(length 5.08)
					(name "SDI"
						(effects
							(font
								(size 1.27 1.27)
							)
						)
					)
					(number "H10"
						(effects
							(font
								(size 1.27 1.27)
							)
						)
					)
				)
				(pin bidirectional line
					(at 0 -15.24 0)
					(length 5.08)
					(name "SS"
						(effects
							(font
								(size 1.27 1.27)
							)
						)
					)
					(number "G7"
						(effects
							(font
								(size 1.27 1.27)
							)
						)
					)
				)
				(pin input line
					(at 35.56 0 180)
					(length 5.08)
					(name "DEVRST_N"
						(effects
							(font
								(size 1.27 1.27)
							)
						)
					)
					(number "H7"
						(effects
							(font
								(size 1.27 1.27)
							)
						)
					)
				)
				(pin input line
					(at 35.56 -2.54 180)
					(length 5.08)
					(name "TCK"
						(effects
							(font
								(size 1.27 1.27)
							)
						)
					)
					(number "E9"
						(effects
							(font
								(size 1.27 1.27)
							)
						)
					)
				)
				(pin input line
					(at 35.56 -5.08 180)
					(length 5.08)
					(name "TDI"
						(effects
							(font
								(size 1.27 1.27)
							)
						)
					)
					(number "G9"
						(effects
							(font
								(size 1.27 1.27)
							)
						)
					)
				)
				(pin output line
					(at 35.56 -7.62 180)
					(length 5.08)
					(name "TDO"
						(effects
							(font
								(size 1.27 1.27)
							)
						)
					)
					(number "E8"
						(effects
							(font
								(size 1.27 1.27)
							)
						)
					)
				)
				(pin input line
					(at 35.56 -10.16 180)
					(length 5.08)
					(name "TMS"
						(effects
							(font
								(size 1.27 1.27)
							)
						)
					)
					(number "F8"
						(effects
							(font
								(size 1.27 1.27)
							)
						)
					)
				)
				(pin input line
					(at 35.56 -12.7 180)
					(length 5.08)
					(name "TRSTB"
						(effects
							(font
								(size 1.27 1.27)
							)
						)
					)
					(number "G8"
						(effects
							(font
								(size 1.27 1.27)
							)
						)
					)
				)
			)
			(symbol "MPFS250T-FCVG484E_5_1"
				(rectangle
					(start 5.08 5.08)
					(end 30.48 -17.78)
					(stroke
						(width 0.254)
						(type default)
					)
					(fill
						(type background)
					)
				)
				(text "BANK 4"
					(at 13.97 2.54 0)
					(effects
						(font
							(size 1.27 1.27)
							(thickness 0.15)
						)
						(justify left bottom)
					)
				)
				(pin bidirectional line
					(at 0 0 0)
					(length 5.08)
					(name "MSSIO0B4"
						(effects
							(font
								(size 1.27 1.27)
							)
						)
					)
					(number "J1"
						(effects
							(font
								(size 1.27 1.27)
							)
						)
					)
				)
				(pin bidirectional line
					(at 0 -2.54 0)
					(length 5.08)
					(name "MSSIO1B4"
						(effects
							(font
								(size 1.27 1.27)
							)
						)
					)
					(number "K5"
						(effects
							(font
								(size 1.27 1.27)
							)
						)
					)
				)
				(pin bidirectional line
					(at 0 -5.08 0)
					(length 5.08)
					(name "MSSIO2B4"
						(effects
							(font
								(size 1.27 1.27)
							)
						)
					)
					(number "H1"
						(effects
							(font
								(size 1.27 1.27)
							)
						)
					)
				)
				(pin bidirectional line
					(at 0 -7.62 0)
					(length 5.08)
					(name "MSSIO3B4"
						(effects
							(font
								(size 1.27 1.27)
							)
						)
					)
					(number "J4"
						(effects
							(font
								(size 1.27 1.27)
							)
						)
					)
				)
				(pin bidirectional line
					(at 0 -10.16 0)
					(length 5.08)
					(name "MSSIO4B4"
						(effects
							(font
								(size 1.27 1.27)
							)
						)
					)
					(number "K4"
						(effects
							(font
								(size 1.27 1.27)
							)
						)
					)
				)
				(pin bidirectional line
					(at 0 -12.7 0)
					(length 5.08)
					(name "MSSIO5B4"
						(effects
							(font
								(size 1.27 1.27)
							)
						)
					)
					(number "J7"
						(effects
							(font
								(size 1.27 1.27)
							)
						)
					)
				)
				(pin bidirectional line
					(at 0 -15.24 0)
					(length 5.08)
					(name "MSSIO6B4"
						(effects
							(font
								(size 1.27 1.27)
							)
						)
					)
					(number "K3"
						(effects
							(font
								(size 1.27 1.27)
							)
						)
					)
				)
				(pin bidirectional line
					(at 35.56 0 180)
					(length 5.08)
					(name "MSSIO7B4"
						(effects
							(font
								(size 1.27 1.27)
							)
						)
					)
					(number "H4"
						(effects
							(font
								(size 1.27 1.27)
							)
						)
					)
				)
				(pin bidirectional line
					(at 35.56 -2.54 180)
					(length 5.08)
					(name "MSSIO8B4"
						(effects
							(font
								(size 1.27 1.27)
							)
						)
					)
					(number "J6"
						(effects
							(font
								(size 1.27 1.27)
							)
						)
					)
				)
				(pin bidirectional line
					(at 35.56 -5.08 180)
					(length 5.08)
					(name "MSSIO9B4"
						(effects
							(font
								(size 1.27 1.27)
							)
						)
					)
					(number "H6"
						(effects
							(font
								(size 1.27 1.27)
							)
						)
					)
				)
				(pin bidirectional line
					(at 35.56 -7.62 180)
					(length 5.08)
					(name "MSSIO10B4"
						(effects
							(font
								(size 1.27 1.27)
							)
						)
					)
					(number "J3"
						(effects
							(font
								(size 1.27 1.27)
							)
						)
					)
				)
				(pin bidirectional line
					(at 35.56 -10.16 180)
					(length 5.08)
					(name "MSSIO11B4"
						(effects
							(font
								(size 1.27 1.27)
							)
						)
					)
					(number "H2"
						(effects
							(font
								(size 1.27 1.27)
							)
						)
					)
				)
				(pin bidirectional line
					(at 35.56 -12.7 180)
					(length 5.08)
					(name "MSSIO12B4"
						(effects
							(font
								(size 1.27 1.27)
							)
						)
					)
					(number "H5"
						(effects
							(font
								(size 1.27 1.27)
							)
						)
					)
				)
				(pin bidirectional line
					(at 35.56 -15.24 180)
					(length 5.08)
					(name "MSSIO13B4"
						(effects
							(font
								(size 1.27 1.27)
							)
						)
					)
					(number "J2"
						(effects
							(font
								(size 1.27 1.27)
							)
						)
					)
				)
			)
			(symbol "MPFS250T-FCVG484E_6_1"
				(rectangle
					(start 5.08 5.08)
					(end 40.64 -20.32)
					(stroke
						(width 0.254)
						(type default)
					)
					(fill
						(type background)
					)
				)
				(text "BANK 5"
					(at 19.05 2.54 0)
					(effects
						(font
							(size 1.27 1.27)
							(thickness 0.15)
						)
						(justify left bottom)
					)
				)
				(pin bidirectional line
					(at 0 0 0)
					(length 5.08)
					(name "MSS_SGMII_TXP1"
						(effects
							(font
								(size 1.27 1.27)
							)
						)
					)
					(number "M7"
						(effects
							(font
								(size 1.27 1.27)
							)
						)
					)
				)
				(pin bidirectional line
					(at 0 -2.54 0)
					(length 5.08)
					(name "MSS_SGMII_TXN1"
						(effects
							(font
								(size 1.27 1.27)
							)
						)
					)
					(number "N8"
						(effects
							(font
								(size 1.27 1.27)
							)
						)
					)
				)
				(pin bidirectional line
					(at 0 -7.62 0)
					(length 5.08)
					(name "MSS_SGMII_RXP1"
						(effects
							(font
								(size 1.27 1.27)
							)
						)
					)
					(number "K6"
						(effects
							(font
								(size 1.27 1.27)
							)
						)
					)
				)
				(pin bidirectional line
					(at 0 -10.16 0)
					(length 5.08)
					(name "MSS_SGMII_RXN1"
						(effects
							(font
								(size 1.27 1.27)
							)
						)
					)
					(number "K7"
						(effects
							(font
								(size 1.27 1.27)
							)
						)
					)
				)
				(pin bidirectional line
					(at 45.72 0 180)
					(length 5.08)
					(name "MSS_SGMII_TXP0"
						(effects
							(font
								(size 1.27 1.27)
							)
						)
					)
					(number "N6"
						(effects
							(font
								(size 1.27 1.27)
							)
						)
					)
				)
				(pin bidirectional line
					(at 45.72 -2.54 180)
					(length 5.08)
					(name "MSS_SGMII_TXN0"
						(effects
							(font
								(size 1.27 1.27)
							)
						)
					)
					(number "N7"
						(effects
							(font
								(size 1.27 1.27)
							)
						)
					)
				)
				(pin bidirectional line
					(at 45.72 -7.62 180)
					(length 5.08)
					(name "MSS_SGMII_RXP0"
						(effects
							(font
								(size 1.27 1.27)
							)
						)
					)
					(number "L5"
						(effects
							(font
								(size 1.27 1.27)
							)
						)
					)
				)
				(pin bidirectional line
					(at 45.72 -10.16 180)
					(length 5.08)
					(name "MSS_SGMII_RXN0"
						(effects
							(font
								(size 1.27 1.27)
							)
						)
					)
					(number "L6"
						(effects
							(font
								(size 1.27 1.27)
							)
						)
					)
				)
				(pin bidirectional line
					(at 45.72 -15.24 180)
					(length 5.08)
					(name "MSS_REFCLK_IN_P"
						(effects
							(font
								(size 1.27 1.27)
							)
						)
					)
					(number "L7"
						(effects
							(font
								(size 1.27 1.27)
							)
						)
					)
				)
				(pin bidirectional line
					(at 45.72 -17.78 180)
					(length 5.08)
					(name "MSS_REFCLK_IN_N"
						(effects
							(font
								(size 1.27 1.27)
							)
						)
					)
					(number "L8"
						(effects
							(font
								(size 1.27 1.27)
							)
						)
					)
				)
			)
			(symbol "MPFS250T-FCVG484E_7_1"
				(rectangle
					(start 5.08 5.08)
					(end 58.42 -139.7)
					(stroke
						(width 0.254)
						(type default)
					)
					(fill
						(type background)
					)
				)
				(text "BANK 6"
					(at 27.94 2.54 0)
					(effects
						(font
							(size 1.27 1.27)
							(thickness 0.15)
						)
						(justify left bottom)
					)
				)
				(pin bidirectional line
					(at 0 0 0)
					(length 5.08)
					(name "MSS_DDR_DQ0"
						(effects
							(font
								(size 1.27 1.27)
							)
						)
					)
					(number "Y3"
						(effects
							(font
								(size 1.27 1.27)
							)
						)
					)
				)
				(pin bidirectional line
					(at 0 -2.54 0)
					(length 5.08)
					(name "MSS_DDR_DQ1"
						(effects
							(font
								(size 1.27 1.27)
							)
						)
					)
					(number "Y4"
						(effects
							(font
								(size 1.27 1.27)
							)
						)
					)
				)
				(pin bidirectional line
					(at 0 -5.08 0)
					(length 5.08)
					(name "MSS_DDR_DQ2"
						(effects
							(font
								(size 1.27 1.27)
							)
						)
					)
					(number "Y1"
						(effects
							(font
								(size 1.27 1.27)
							)
						)
					)
				)
				(pin bidirectional line
					(at 0 -7.62 0)
					(length 5.08)
					(name "MSS_DDR_DQ3"
						(effects
							(font
								(size 1.27 1.27)
							)
						)
					)
					(number "AA1"
						(effects
							(font
								(size 1.27 1.27)
							)
						)
					)
				)
				(pin bidirectional line
					(at 0 -10.16 0)
					(length 5.08)
					(name "MSS_DDR_DQ4"
						(effects
							(font
								(size 1.27 1.27)
							)
						)
					)
					(number "Y5"
						(effects
							(font
								(size 1.27 1.27)
							)
						)
					)
				)
				(pin bidirectional line
					(at 0 -12.7 0)
					(length 5.08)
					(name "MSS_DDR_DQ5"
						(effects
							(font
								(size 1.27 1.27)
							)
						)
					)
					(number "AA5"
						(effects
							(font
								(size 1.27 1.27)
							)
						)
					)
				)
				(pin bidirectional line
					(at 0 -15.24 0)
					(length 5.08)
					(name "MSS_DDR_DQ6"
						(effects
							(font
								(size 1.27 1.27)
							)
						)
					)
					(number "AB2"
						(effects
							(font
								(size 1.27 1.27)
							)
						)
					)
				)
				(pin bidirectional line
					(at 0 -17.78 0)
					(length 5.08)
					(name "MSS_DDR_DQ7"
						(effects
							(font
								(size 1.27 1.27)
							)
						)
					)
					(number "AB3"
						(effects
							(font
								(size 1.27 1.27)
							)
						)
					)
				)
				(pin bidirectional line
					(at 0 -20.32 0)
					(length 5.08)
					(name "MSS_DDR_DQS_P0"
						(effects
							(font
								(size 1.27 1.27)
							)
						)
					)
					(number "AA2"
						(effects
							(font
								(size 1.27 1.27)
							)
						)
					)
				)
				(pin bidirectional line
					(at 0 -22.86 0)
					(length 5.08)
					(name "MSS_DDR_DQS_N0"
						(effects
							(font
								(size 1.27 1.27)
							)
						)
					)
					(number "AA3"
						(effects
							(font
								(size 1.27 1.27)
							)
						)
					)
				)
				(pin bidirectional line
					(at 0 -25.4 0)
					(length 5.08)
					(name "MSS_DDR_DM0"
						(effects
							(font
								(size 1.27 1.27)
							)
						)
					)
					(number "AB4"
						(effects
							(font
								(size 1.27 1.27)
							)
						)
					)
				)
				(pin bidirectional line
					(at 0 -30.48 0)
					(length 5.08)
					(name "MSS_DDR_DQ8"
						(effects
							(font
								(size 1.27 1.27)
							)
						)
					)
					(number "W8"
						(effects
							(font
								(size 1.27 1.27)
							)
						)
					)
				)
				(pin bidirectional line
					(at 0 -33.02 0)
					(length 5.08)
					(name "MSS_DDR_DQ9"
						(effects
							(font
								(size 1.27 1.27)
							)
						)
					)
					(number "W7"
						(effects
							(font
								(size 1.27 1.27)
							)
						)
					)
				)
				(pin bidirectional line
					(at 0 -35.56 0)
					(length 5.08)
					(name "MSS_DDR_DQ10"
						(effects
							(font
								(size 1.27 1.27)
							)
						)
					)
					(number "AB5"
						(effects
							(font
								(size 1.27 1.27)
							)
						)
					)
				)
				(pin bidirectional line
					(at 0 -38.1 0)
					(length 5.08)
					(name "MSS_DDR_DQ11"
						(effects
							(font
								(size 1.27 1.27)
							)
						)
					)
					(number "AA6"
						(effects
							(font
								(size 1.27 1.27)
							)
						)
					)
				)
				(pin bidirectional line
					(at 0 -40.64 0)
					(length 5.08)
					(name "MSS_DDR_DQ12"
						(effects
							(font
								(size 1.27 1.27)
							)
						)
					)
					(number "AB7"
						(effects
							(font
								(size 1.27 1.27)
							)
						)
					)
				)
				(pin bidirectional line
					(at 0 -43.18 0)
					(length 5.08)
					(name "MSS_DDR_DQ13"
						(effects
							(font
								(size 1.27 1.27)
							)
						)
					)
					(number "AB8"
						(effects
							(font
								(size 1.27 1.27)
							)
						)
					)
				)
				(pin bidirectional line
					(at 0 -45.72 0)
					(length 5.08)
					(name "MSS_DDR_DQ14"
						(effects
							(font
								(size 1.27 1.27)
							)
						)
					)
					(number "Y8"
						(effects
							(font
								(size 1.27 1.27)
							)
						)
					)
				)
				(pin bidirectional line
					(at 0 -48.26 0)
					(length 5.08)
					(name "MSS_DDR_DQ15"
						(effects
							(font
								(size 1.27 1.27)
							)
						)
					)
					(number "AA8"
						(effects
							(font
								(size 1.27 1.27)
							)
						)
					)
				)
				(pin bidirectional line
					(at 0 -50.8 0)
					(length 5.08)
					(name "MSS_DDR_DQS_P1"
						(effects
							(font
								(size 1.27 1.27)
							)
						)
					)
					(number "Y6"
						(effects
							(font
								(size 1.27 1.27)
							)
						)
					)
				)
				(pin bidirectional line
					(at 0 -53.34 0)
					(length 5.08)
					(name "MSS_DDR_DQS_N1"
						(effects
							(font
								(size 1.27 1.27)
							)
						)
					)
					(number "W6"
						(effects
							(font
								(size 1.27 1.27)
							)
						)
					)
				)
				(pin bidirectional line
					(at 0 -55.88 0)
					(length 5.08)
					(name "MSS_DDR_DM1"
						(effects
							(font
								(size 1.27 1.27)
							)
						)
					)
					(number "AA7"
						(effects
							(font
								(size 1.27 1.27)
							)
						)
					)
				)
				(pin bidirectional line
					(at 0 -60.96 0)
					(length 5.08)
					(name "MSS_DDR_DQ16"
						(effects
							(font
								(size 1.27 1.27)
							)
						)
					)
					(number "Y9"
						(effects
							(font
								(size 1.27 1.27)
							)
						)
					)
				)
				(pin bidirectional line
					(at 0 -63.5 0)
					(length 5.08)
					(name "MSS_DDR_DQ17"
						(effects
							(font
								(size 1.27 1.27)
							)
						)
					)
					(number "W9"
						(effects
							(font
								(size 1.27 1.27)
							)
						)
					)
				)
				(pin bidirectional line
					(at 0 -66.04 0)
					(length 5.08)
					(name "MSS_DDR_DQ18"
						(effects
							(font
								(size 1.27 1.27)
							)
						)
					)
					(number "AB9"
						(effects
							(font
								(size 1.27 1.27)
							)
						)
					)
				)
				(pin bidirectional line
					(at 0 -68.58 0)
					(length 5.08)
					(name "MSS_DDR_DQ19"
						(effects
							(font
								(size 1.27 1.27)
							)
						)
					)
					(number "AB10"
						(effects
							(font
								(size 1.27 1.27)
							)
						)
					)
				)
				(pin bidirectional line
					(at 0 -71.12 0)
					(length 5.08)
					(name "MSS_DDR_DQ20"
						(effects
							(font
								(size 1.27 1.27)
							)
						)
					)
					(number "V11"
						(effects
							(font
								(size 1.27 1.27)
							)
						)
					)
				)
				(pin bidirectional line
					(at 0 -73.66 0)
					(length 5.08)
					(name "MSS_DDR_DQ21"
						(effects
							(font
								(size 1.27 1.27)
							)
						)
					)
					(number "V10"
						(effects
							(font
								(size 1.27 1.27)
							)
						)
					)
				)
				(pin bidirectional line
					(at 0 -76.2 0)
					(length 5.08)
					(name "MSS_DDR_DQ22"
						(effects
							(font
								(size 1.27 1.27)
							)
						)
					)
					(number "Y11"
						(effects
							(font
								(size 1.27 1.27)
							)
						)
					)
				)
				(pin bidirectional line
					(at 0 -78.74 0)
					(length 5.08)
					(name "MSS_DDR_DQ23"
						(effects
							(font
								(size 1.27 1.27)
							)
						)
					)
					(number "W11"
						(effects
							(font
								(size 1.27 1.27)
							)
						)
					)
				)
				(pin bidirectional line
					(at 0 -81.28 0)
					(length 5.08)
					(name "MSS_DDR_DQS_P2"
						(effects
							(font
								(size 1.27 1.27)
							)
						)
					)
					(number "AA11"
						(effects
							(font
								(size 1.27 1.27)
							)
						)
					)
				)
				(pin bidirectional line
					(at 0 -83.82 0)
					(length 5.08)
					(name "MSS_DDR_DQS_N2"
						(effects
							(font
								(size 1.27 1.27)
							)
						)
					)
					(number "AA10"
						(effects
							(font
								(size 1.27 1.27)
							)
						)
					)
				)
				(pin bidirectional line
					(at 0 -86.36 0)
					(length 5.08)
					(name "MSS_DDR_DM2"
						(effects
							(font
								(size 1.27 1.27)
							)
						)
					)
					(number "Y10"
						(effects
							(font
								(size 1.27 1.27)
							)
						)
					)
				)
				(pin bidirectional line
					(at 0 -91.44 0)
					(length 5.08)
					(name "MSS_DDR_DQ24"
						(effects
							(font
								(size 1.27 1.27)
							)
						)
					)
					(number "U8"
						(effects
							(font
								(size 1.27 1.27)
							)
						)
					)
				)
				(pin bidirectional line
					(at 0 -93.98 0)
					(length 5.08)
					(name "MSS_DDR_DQ25"
						(effects
							(font
								(size 1.27 1.27)
							)
						)
					)
					(number "T8"
						(effects
							(font
								(size 1.27 1.27)
							)
						)
					)
				)
				(pin bidirectional line
					(at 0 -96.52 0)
					(length 5.08)
					(name "MSS_DDR_DQ26"
						(effects
							(font
								(size 1.27 1.27)
							)
						)
					)
					(number "T11"
						(effects
							(font
								(size 1.27 1.27)
							)
						)
					)
				)
				(pin bidirectional line
					(at 0 -99.06 0)
					(length 5.08)
					(name "MSS_DDR_DQ27"
						(effects
							(font
								(size 1.27 1.27)
							)
						)
					)
					(number "U10"
						(effects
							(font
								(size 1.27 1.27)
							)
						)
					)
				)
				(pin bidirectional line
					(at 0 -101.6 0)
					(length 5.08)
					(name "MSS_DDR_DQ28"
						(effects
							(font
								(size 1.27 1.27)
							)
						)
					)
					(number "R11"
						(effects
							(font
								(size 1.27 1.27)
							)
						)
					)
				)
				(pin bidirectional line
					(at 0 -104.14 0)
					(length 5.08)
					(name "MSS_DDR_DQ29"
						(effects
							(font
								(size 1.27 1.27)
							)
						)
					)
					(number "R10"
						(effects
							(font
								(size 1.27 1.27)
							)
						)
					)
				)
				(pin bidirectional line
					(at 0 -106.68 0)
					(length 5.08)
					(name "MSS_DDR_DQ30"
						(effects
							(font
								(size 1.27 1.27)
							)
						)
					)
					(number "R8"
						(effects
							(font
								(size 1.27 1.27)
							)
						)
					)
				)
				(pin bidirectional line
					(at 0 -109.22 0)
					(length 5.08)
					(name "MSS_DDR_DQ31"
						(effects
							(font
								(size 1.27 1.27)
							)
						)
					)
					(number "P8"
						(effects
							(font
								(size 1.27 1.27)
							)
						)
					)
				)
				(pin bidirectional line
					(at 0 -111.76 0)
					(length 5.08)
					(name "MSS_DDR_DQS_P3"
						(effects
							(font
								(size 1.27 1.27)
							)
						)
					)
					(number "U9"
						(effects
							(font
								(size 1.27 1.27)
							)
						)
					)
				)
				(pin bidirectional line
					(at 0 -114.3 0)
					(length 5.08)
					(name "MSS_DDR_DQS_N3"
						(effects
							(font
								(size 1.27 1.27)
							)
						)
					)
					(number "V9"
						(effects
							(font
								(size 1.27 1.27)
							)
						)
					)
				)
				(pin bidirectional line
					(at 0 -116.84 0)
					(length 5.08)
					(name "MSS_DDR_DM3"
						(effects
							(font
								(size 1.27 1.27)
							)
						)
					)
					(number "T10"
						(effects
							(font
								(size 1.27 1.27)
							)
						)
					)
				)
				(pin bidirectional line
					(at 0 -121.92 0)
					(length 5.08)
					(name "MSS_DDR_DQ32"
						(effects
							(font
								(size 1.27 1.27)
							)
						)
					)
					(number "W4"
						(effects
							(font
								(size 1.27 1.27)
							)
						)
					)
				)
				(pin bidirectional line
					(at 0 -124.46 0)
					(length 5.08)
					(name "MSS_DDR_DQ33"
						(effects
							(font
								(size 1.27 1.27)
							)
						)
					)
					(number "W3"
						(effects
							(font
								(size 1.27 1.27)
							)
						)
					)
				)
				(pin bidirectional line
					(at 0 -127 0)
					(length 5.08)
					(name "MSS_DDR_DQ34"
						(effects
							(font
								(size 1.27 1.27)
							)
						)
					)
					(number "W2"
						(effects
							(font
								(size 1.27 1.27)
							)
						)
					)
				)
				(pin bidirectional line
					(at 0 -129.54 0)
					(length 5.08)
					(name "MSS_DDR_DQ35"
						(effects
							(font
								(size 1.27 1.27)
							)
						)
					)
					(number "W1"
						(effects
							(font
								(size 1.27 1.27)
							)
						)
					)
				)
				(pin bidirectional line
					(at 0 -132.08 0)
					(length 5.08)
					(name "MSS_DDR_DQS_P4"
						(effects
							(font
								(size 1.27 1.27)
							)
						)
					)
					(number "V2"
						(effects
							(font
								(size 1.27 1.27)
							)
						)
					)
				)
				(pin bidirectional line
					(at 0 -134.62 0)
					(length 5.08)
					(name "MSS_DDR_DQS_N4"
						(effects
							(font
								(size 1.27 1.27)
							)
						)
					)
					(number "V1"
						(effects
							(font
								(size 1.27 1.27)
							)
						)
					)
				)
				(pin bidirectional line
					(at 0 -137.16 0)
					(length 5.08)
					(name "MSS_DDR_DM4"
						(effects
							(font
								(size 1.27 1.27)
							)
						)
					)
					(number "V5"
						(effects
							(font
								(size 1.27 1.27)
							)
						)
					)
				)
				(pin bidirectional line
					(at 63.5 0 180)
					(length 5.08)
					(name "MSS_DDR_A0"
						(effects
							(font
								(size 1.27 1.27)
							)
						)
					)
					(number "T5"
						(effects
							(font
								(size 1.27 1.27)
							)
						)
					)
				)
				(pin bidirectional line
					(at 63.5 -2.54 180)
					(length 5.08)
					(name "MSS_DDR_A1"
						(effects
							(font
								(size 1.27 1.27)
							)
						)
					)
					(number "T6"
						(effects
							(font
								(size 1.27 1.27)
							)
						)
					)
				)
				(pin bidirectional line
					(at 63.5 -5.08 180)
					(length 5.08)
					(name "MSS_DDR_A2"
						(effects
							(font
								(size 1.27 1.27)
							)
						)
					)
					(number "V7"
						(effects
							(font
								(size 1.27 1.27)
							)
						)
					)
				)
				(pin bidirectional line
					(at 63.5 -7.62 180)
					(length 5.08)
					(name "MSS_DDR_A3"
						(effects
							(font
								(size 1.27 1.27)
							)
						)
					)
					(number "V6"
						(effects
							(font
								(size 1.27 1.27)
							)
						)
					)
				)
				(pin bidirectional line
					(at 63.5 -10.16 180)
					(length 5.08)
					(name "MSS_DDR_A4"
						(effects
							(font
								(size 1.27 1.27)
							)
						)
					)
					(number "R6"
						(effects
							(font
								(size 1.27 1.27)
							)
						)
					)
				)
				(pin bidirectional line
					(at 63.5 -12.7 180)
					(length 5.08)
					(name "MSS_DDR_A5"
						(effects
							(font
								(size 1.27 1.27)
							)
						)
					)
					(number "R5"
						(effects
							(font
								(size 1.27 1.27)
							)
						)
					)
				)
				(pin bidirectional line
					(at 63.5 -15.24 180)
					(length 5.08)
					(name "MSS_DDR_A6"
						(effects
							(font
								(size 1.27 1.27)
							)
						)
					)
					(number "P6"
						(effects
							(font
								(size 1.27 1.27)
							)
						)
					)
				)
				(pin bidirectional line
					(at 63.5 -17.78 180)
					(length 5.08)
					(name "MSS_DDR_A7"
						(effects
							(font
								(size 1.27 1.27)
							)
						)
					)
					(number "T7"
						(effects
							(font
								(size 1.27 1.27)
							)
						)
					)
				)
				(pin bidirectional line
					(at 63.5 -20.32 180)
					(length 5.08)
					(name "MSS_DDR_A8"
						(effects
							(font
								(size 1.27 1.27)
							)
						)
					)
					(number "P7"
						(effects
							(font
								(size 1.27 1.27)
							)
						)
					)
				)
				(pin bidirectional line
					(at 63.5 -22.86 180)
					(length 5.08)
					(name "MSS_DDR_A9"
						(effects
							(font
								(size 1.27 1.27)
							)
						)
					)
					(number "U7"
						(effects
							(font
								(size 1.27 1.27)
							)
						)
					)
				)
				(pin bidirectional line
					(at 63.5 -25.4 180)
					(length 5.08)
					(name "MSS_DDR_A10"
						(effects
							(font
								(size 1.27 1.27)
							)
						)
					)
					(number "U2"
						(effects
							(font
								(size 1.27 1.27)
							)
						)
					)
				)
				(pin bidirectional line
					(at 63.5 -27.94 180)
					(length 5.08)
					(name "MSS_DDR_A11"
						(effects
							(font
								(size 1.27 1.27)
							)
						)
					)
					(number "R1"
						(effects
							(font
								(size 1.27 1.27)
							)
						)
					)
				)
				(pin bidirectional line
					(at 63.5 -30.48 180)
					(length 5.08)
					(name "MSS_DDR_A12"
						(effects
							(font
								(size 1.27 1.27)
							)
						)
					)
					(number "P1"
						(effects
							(font
								(size 1.27 1.27)
							)
						)
					)
				)
				(pin bidirectional line
					(at 63.5 -33.02 180)
					(length 5.08)
					(name "MSS_DDR_A13"
						(effects
							(font
								(size 1.27 1.27)
							)
						)
					)
					(number "P2"
						(effects
							(font
								(size 1.27 1.27)
							)
						)
					)
				)
				(pin bidirectional line
					(at 63.5 -35.56 180)
					(length 5.08)
					(name "MSS_DDR_A14"
						(effects
							(font
								(size 1.27 1.27)
							)
						)
					)
					(number "P3"
						(effects
							(font
								(size 1.27 1.27)
							)
						)
					)
				)
				(pin bidirectional line
					(at 63.5 -38.1 180)
					(length 5.08)
					(name "MSS_DDR_A15"
						(effects
							(font
								(size 1.27 1.27)
							)
						)
					)
					(number "R3"
						(effects
							(font
								(size 1.27 1.27)
							)
						)
					)
				)
				(pin bidirectional line
					(at 63.5 -40.64 180)
					(length 5.08)
					(name "MSS_DDR_A16"
						(effects
							(font
								(size 1.27 1.27)
							)
						)
					)
					(number "R4"
						(effects
							(font
								(size 1.27 1.27)
							)
						)
					)
				)
				(pin bidirectional line
					(at 63.5 -58.42 180)
					(length 5.08)
					(name "MSS_DDR_RAM_RST_N/DDR_PLL0_OUT1"
						(effects
							(font
								(size 1.27 1.27)
							)
						)
					)
					(number "L2"
						(effects
							(font
								(size 1.27 1.27)
							)
						)
					)
				)
				(pin bidirectional line
					(at 63.5 -60.96 180)
					(length 5.08)
					(name "MSS_DDR_CS0"
						(effects
							(font
								(size 1.27 1.27)
							)
						)
					)
					(number "L3"
						(effects
							(font
								(size 1.27 1.27)
							)
						)
					)
				)
				(pin bidirectional line
					(at 63.5 -63.5 180)
					(length 5.08)
					(name "MSS_DDR_CS1"
						(effects
							(font
								(size 1.27 1.27)
							)
						)
					)
					(number "M3"
						(effects
							(font
								(size 1.27 1.27)
							)
						)
					)
				)
				(pin bidirectional line
					(at 63.5 -66.04 180)
					(length 5.08)
					(name "MSS_DDR_CKE0"
						(effects
							(font
								(size 1.27 1.27)
							)
						)
					)
					(number "K1"
						(effects
							(font
								(size 1.27 1.27)
							)
						)
					)
				)
				(pin bidirectional line
					(at 63.5 -68.58 180)
					(length 5.08)
					(name "MSS_DDR_CKE1"
						(effects
							(font
								(size 1.27 1.27)
							)
						)
					)
					(number "N2"
						(effects
							(font
								(size 1.27 1.27)
							)
						)
					)
				)
				(pin bidirectional line
					(at 63.5 -71.12 180)
					(length 5.08)
					(name "MSS_DDR_ACT_N"
						(effects
							(font
								(size 1.27 1.27)
							)
						)
					)
					(number "N5"
						(effects
							(font
								(size 1.27 1.27)
							)
						)
					)
				)
				(pin bidirectional line
					(at 63.5 -73.66 180)
					(length 5.08)
					(name "MSS_DDR_BG0"
						(effects
							(font
								(size 1.27 1.27)
							)
						)
					)
					(number "N1"
						(effects
							(font
								(size 1.27 1.27)
							)
						)
					)
				)
				(pin bidirectional line
					(at 63.5 -76.2 180)
					(length 5.08)
					(name "MSS_DDR_BG1"
						(effects
							(font
								(size 1.27 1.27)
							)
						)
					)
					(number "M2"
						(effects
							(font
								(size 1.27 1.27)
							)
						)
					)
				)
				(pin bidirectional line
					(at 63.5 -78.74 180)
					(length 5.08)
					(name "MSS_DDR_BA0"
						(effects
							(font
								(size 1.27 1.27)
							)
						)
					)
					(number "P4"
						(effects
							(font
								(size 1.27 1.27)
							)
						)
					)
				)
				(pin bidirectional line
					(at 63.5 -81.28 180)
					(length 5.08)
					(name "MSS_DDR_BA1"
						(effects
							(font
								(size 1.27 1.27)
							)
						)
					)
					(number "T3"
						(effects
							(font
								(size 1.27 1.27)
							)
						)
					)
				)
				(pin bidirectional line
					(at 63.5 -114.3 180)
					(length 5.08)
					(name "MSS_DDR3_WE_N"
						(effects
							(font
								(size 1.27 1.27)
							)
						)
					)
					(number "U3"
						(effects
							(font
								(size 1.27 1.27)
							)
						)
					)
				)
				(pin bidirectional line
					(at 63.5 -116.84 180)
					(length 5.08)
					(name "MSS_DDR_CK0/DDR_PLL0_OUT0"
						(effects
							(font
								(size 1.27 1.27)
							)
						)
					)
					(number "U5"
						(effects
							(font
								(size 1.27 1.27)
							)
						)
					)
				)
				(pin bidirectional line
					(at 63.5 -119.38 180)
					(length 5.08)
					(name "MSS_DDR_CK_N0"
						(effects
							(font
								(size 1.27 1.27)
							)
						)
					)
					(number "U4"
						(effects
							(font
								(size 1.27 1.27)
							)
						)
					)
				)
				(pin bidirectional line
					(at 63.5 -121.92 180)
					(length 5.08)
					(name "MSS_DDR_CK1/DDR_PLL0_OUT0"
						(effects
							(font
								(size 1.27 1.27)
							)
						)
					)
					(number "T1"
						(effects
							(font
								(size 1.27 1.27)
							)
						)
					)
				)
				(pin bidirectional line
					(at 63.5 -124.46 180)
					(length 5.08)
					(name "MSS_DDR_CK_N1"
						(effects
							(font
								(size 1.27 1.27)
							)
						)
					)
					(number "T2"
						(effects
							(font
								(size 1.27 1.27)
							)
						)
					)
				)
				(pin bidirectional line
					(at 63.5 -127 180)
					(length 5.08)
					(name "MSS_DDR_PARITY"
						(effects
							(font
								(size 1.27 1.27)
							)
						)
					)
					(number "M5"
						(effects
							(font
								(size 1.27 1.27)
							)
						)
					)
				)
				(pin bidirectional line
					(at 63.5 -129.54 180)
					(length 5.08)
					(name "MSS_DDR_ODT0"
						(effects
							(font
								(size 1.27 1.27)
							)
						)
					)
					(number "L1"
						(effects
							(font
								(size 1.27 1.27)
							)
						)
					)
				)
				(pin bidirectional line
					(at 63.5 -132.08 180)
					(length 5.08)
					(name "MSS_DDR_ODT1"
						(effects
							(font
								(size 1.27 1.27)
							)
						)
					)
					(number "M4"
						(effects
							(font
								(size 1.27 1.27)
							)
						)
					)
				)
				(pin bidirectional line
					(at 63.5 -134.62 180)
					(length 5.08)
					(name "MSS_DDR_ALERT_N"
						(effects
							(font
								(size 1.27 1.27)
							)
						)
					)
					(number "N4"
						(effects
							(font
								(size 1.27 1.27)
							)
						)
					)
				)
				(pin input line
					(at 63.5 -137.16 180)
					(length 5.08)
					(name "MSS_DDR_VREF_IN"
						(effects
							(font
								(size 1.27 1.27)
							)
						)
					)
					(number "V4"
						(effects
							(font
								(size 1.27 1.27)
							)
						)
					)
				)
			)
			(symbol "MPFS250T-FCVG484E_8_1"
				(rectangle
					(start 5.08 5.08)
					(end 45.72 -43.18)
					(stroke
						(width 0.254)
						(type default)
					)
					(fill
						(type background)
					)
				)
				(text "XCVR"
					(at 22.86 2.54 0)
					(effects
						(font
							(size 1.27 1.27)
							(thickness 0.15)
						)
						(justify left bottom)
					)
				)
				(pin output line
					(at 0 0 0)
					(length 5.08)
					(name "XCVR_0_TX0_P"
						(effects
							(font
								(size 1.27 1.27)
							)
						)
					)
					(number "F22"
						(effects
							(font
								(size 1.27 1.27)
							)
						)
					)
				)
				(pin output line
					(at 0 -2.54 0)
					(length 5.08)
					(name "XCVR_0_TX0_N"
						(effects
							(font
								(size 1.27 1.27)
							)
						)
					)
					(number "F21"
						(effects
							(font
								(size 1.27 1.27)
							)
						)
					)
				)
				(pin output line
					(at 0 -7.62 0)
					(length 5.08)
					(name "XCVR_0_TX1_P"
						(effects
							(font
								(size 1.27 1.27)
							)
						)
					)
					(number "H22"
						(effects
							(font
								(size 1.27 1.27)
							)
						)
					)
				)
				(pin output line
					(at 0 -10.16 0)
					(length 5.08)
					(name "XCVR_0_TX1_N"
						(effects
							(font
								(size 1.27 1.27)
							)
						)
					)
					(number "H21"
						(effects
							(font
								(size 1.27 1.27)
							)
						)
					)
				)
				(pin output line
					(at 0 -15.24 0)
					(length 5.08)
					(name "XCVR_0_TX2_P"
						(effects
							(font
								(size 1.27 1.27)
							)
						)
					)
					(number "P22"
						(effects
							(font
								(size 1.27 1.27)
							)
						)
					)
				)
				(pin output line
					(at 0 -17.78 0)
					(length 5.08)
					(name "XCVR_0_TX2_N"
						(effects
							(font
								(size 1.27 1.27)
							)
						)
					)
					(number "P21"
						(effects
							(font
								(size 1.27 1.27)
							)
						)
					)
				)
				(pin output line
					(at 0 -22.86 0)
					(length 5.08)
					(name "XCVR_0_TX3_P"
						(effects
							(font
								(size 1.27 1.27)
							)
						)
					)
					(number "T22"
						(effects
							(font
								(size 1.27 1.27)
							)
						)
					)
				)
				(pin output line
					(at 0 -25.4 0)
					(length 5.08)
					(name "XCVR_0_TX3_N"
						(effects
							(font
								(size 1.27 1.27)
							)
						)
					)
					(number "T21"
						(effects
							(font
								(size 1.27 1.27)
							)
						)
					)
				)
				(pin input line
					(at 0 -30.48 0)
					(length 5.08)
					(name "XCVR_0A_REFCLK_P"
						(effects
							(font
								(size 1.27 1.27)
							)
						)
					)
					(number "L19"
						(effects
							(font
								(size 1.27 1.27)
							)
						)
					)
				)
				(pin input line
					(at 0 -33.02 0)
					(length 5.08)
					(name "XCVR_0A_REFCLK_N"
						(effects
							(font
								(size 1.27 1.27)
							)
						)
					)
					(number "L20"
						(effects
							(font
								(size 1.27 1.27)
							)
						)
					)
				)
				(pin input line
					(at 0 -38.1 0)
					(length 5.08)
					(name "XCVR_0C_REFCLK_P"
						(effects
							(font
								(size 1.27 1.27)
							)
						)
					)
					(number "J19"
						(effects
							(font
								(size 1.27 1.27)
							)
						)
					)
				)
				(pin input line
					(at 0 -40.64 0)
					(length 5.08)
					(name "XCVR_0C_REFCLK_N"
						(effects
							(font
								(size 1.27 1.27)
							)
						)
					)
					(number "J20"
						(effects
							(font
								(size 1.27 1.27)
							)
						)
					)
				)
				(pin input line
					(at 50.8 0 180)
					(length 5.08)
					(name "XCVR_0_RX0_P"
						(effects
							(font
								(size 1.27 1.27)
							)
						)
					)
					(number "G20"
						(effects
							(font
								(size 1.27 1.27)
							)
						)
					)
				)
				(pin input line
					(at 50.8 -2.54 180)
					(length 5.08)
					(name "XCVR_0_RX0_N"
						(effects
							(font
								(size 1.27 1.27)
							)
						)
					)
					(number "G19"
						(effects
							(font
								(size 1.27 1.27)
							)
						)
					)
				)
				(pin input line
					(at 50.8 -7.62 180)
					(length 5.08)
					(name "XCVR_0_RX1_P"
						(effects
							(font
								(size 1.27 1.27)
							)
						)
					)
					(number "K22"
						(effects
							(font
								(size 1.27 1.27)
							)
						)
					)
				)
				(pin input line
					(at 50.8 -10.16 180)
					(length 5.08)
					(name "XCVR_0_RX1_N"
						(effects
							(font
								(size 1.27 1.27)
							)
						)
					)
					(number "K21"
						(effects
							(font
								(size 1.27 1.27)
							)
						)
					)
				)
				(pin input line
					(at 50.8 -15.24 180)
					(length 5.08)
					(name "XCVR_0_RX2_P"
						(effects
							(font
								(size 1.27 1.27)
							)
						)
					)
					(number "M22"
						(effects
							(font
								(size 1.27 1.27)
							)
						)
					)
				)
				(pin input line
					(at 50.8 -17.78 180)
					(length 5.08)
					(name "XCVR_0_RX2_N"
						(effects
							(font
								(size 1.27 1.27)
							)
						)
					)
					(number "M21"
						(effects
							(font
								(size 1.27 1.27)
							)
						)
					)
				)
				(pin input line
					(at 50.8 -22.86 180)
					(length 5.08)
					(name "XCVR_0_RX3_P"
						(effects
							(font
								(size 1.27 1.27)
							)
						)
					)
					(number "R20"
						(effects
							(font
								(size 1.27 1.27)
							)
						)
					)
				)
				(pin input line
					(at 50.8 -25.4 180)
					(length 5.08)
					(name "XCVR_0_RX3_N"
						(effects
							(font
								(size 1.27 1.27)
							)
						)
					)
					(number "R19"
						(effects
							(font
								(size 1.27 1.27)
							)
						)
					)
				)
				(pin input line
					(at 50.8 -30.48 180)
					(length 5.08)
					(name "XCVR_0B_REFCLK_P"
						(effects
							(font
								(size 1.27 1.27)
							)
						)
					)
					(number "N19"
						(effects
							(font
								(size 1.27 1.27)
							)
						)
					)
				)
				(pin input line
					(at 50.8 -33.02 180)
					(length 5.08)
					(name "XCVR_0B_REFCLK_N"
						(effects
							(font
								(size 1.27 1.27)
							)
						)
					)
					(number "N20"
						(effects
							(font
								(size 1.27 1.27)
							)
						)
					)
				)
			)
			(symbol "MPFS250T-FCVG484E_9_1"
				(rectangle
					(start 5.08 2.54)
					(end 27.94 -22.86)
					(stroke
						(width 0.254)
						(type default)
					)
					(fill
						(type background)
					)
				)
				(pin power_in line
					(at 0 0 0)
					(length 5.08)
					(name "VDD"
						(effects
							(font
								(size 1.27 1.27)
							)
						)
					)
					(number "J15"
						(effects
							(font
								(size 1.27 1.27)
							)
						)
					)
				)
				(pin passive line
					(at 0 0 0)
					(length 5.08)
					(hide yes)
					(name "VDD"
						(effects
							(font
								(size 1.27 1.27)
							)
						)
					)
					(number "K12"
						(effects
							(font
								(size 1.27 1.27)
							)
						)
					)
				)
				(pin passive line
					(at 0 0 0)
					(length 5.08)
					(hide yes)
					(name "VDD"
						(effects
							(font
								(size 1.27 1.27)
							)
						)
					)
					(number "K14"
						(effects
							(font
								(size 1.27 1.27)
							)
						)
					)
				)
				(pin passive line
					(at 0 0 0)
					(length 5.08)
					(hide yes)
					(name "VDD"
						(effects
							(font
								(size 1.27 1.27)
							)
						)
					)
					(number "K16"
						(effects
							(font
								(size 1.27 1.27)
							)
						)
					)
				)
				(pin passive line
					(at 0 0 0)
					(length 5.08)
					(hide yes)
					(name "VDD"
						(effects
							(font
								(size 1.27 1.27)
							)
						)
					)
					(number "L11"
						(effects
							(font
								(size 1.27 1.27)
							)
						)
					)
				)
				(pin passive line
					(at 0 0 0)
					(length 5.08)
					(hide yes)
					(name "VDD"
						(effects
							(font
								(size 1.27 1.27)
							)
						)
					)
					(number "L13"
						(effects
							(font
								(size 1.27 1.27)
							)
						)
					)
				)
				(pin passive line
					(at 0 0 0)
					(length 5.08)
					(hide yes)
					(name "VDD"
						(effects
							(font
								(size 1.27 1.27)
							)
						)
					)
					(number "L17"
						(effects
							(font
								(size 1.27 1.27)
							)
						)
					)
				)
				(pin passive line
					(at 0 0 0)
					(length 5.08)
					(hide yes)
					(name "VDD"
						(effects
							(font
								(size 1.27 1.27)
							)
						)
					)
					(number "M12"
						(effects
							(font
								(size 1.27 1.27)
							)
						)
					)
				)
				(pin passive line
					(at 0 0 0)
					(length 5.08)
					(hide yes)
					(name "VDD"
						(effects
							(font
								(size 1.27 1.27)
							)
						)
					)
					(number "M14"
						(effects
							(font
								(size 1.27 1.27)
							)
						)
					)
				)
				(pin passive line
					(at 0 0 0)
					(length 5.08)
					(hide yes)
					(name "VDD"
						(effects
							(font
								(size 1.27 1.27)
							)
						)
					)
					(number "M16"
						(effects
							(font
								(size 1.27 1.27)
							)
						)
					)
				)
				(pin passive line
					(at 0 0 0)
					(length 5.08)
					(hide yes)
					(name "VDD"
						(effects
							(font
								(size 1.27 1.27)
							)
						)
					)
					(number "N11"
						(effects
							(font
								(size 1.27 1.27)
							)
						)
					)
				)
				(pin passive line
					(at 0 0 0)
					(length 5.08)
					(hide yes)
					(name "VDD"
						(effects
							(font
								(size 1.27 1.27)
							)
						)
					)
					(number "N13"
						(effects
							(font
								(size 1.27 1.27)
							)
						)
					)
				)
				(pin passive line
					(at 0 0 0)
					(length 5.08)
					(hide yes)
					(name "VDD"
						(effects
							(font
								(size 1.27 1.27)
							)
						)
					)
					(number "N15"
						(effects
							(font
								(size 1.27 1.27)
							)
						)
					)
				)
				(pin passive line
					(at 0 0 0)
					(length 5.08)
					(hide yes)
					(name "VDD"
						(effects
							(font
								(size 1.27 1.27)
							)
						)
					)
					(number "N17"
						(effects
							(font
								(size 1.27 1.27)
							)
						)
					)
				)
				(pin power_in line
					(at 0 -2.54 0)
					(length 5.08)
					(name "VDD18"
						(effects
							(font
								(size 1.27 1.27)
							)
						)
					)
					(number "P10"
						(effects
							(font
								(size 1.27 1.27)
							)
						)
					)
				)
				(pin passive line
					(at 0 -2.54 0)
					(length 5.08)
					(hide yes)
					(name "VDD18"
						(effects
							(font
								(size 1.27 1.27)
							)
						)
					)
					(number "P12"
						(effects
							(font
								(size 1.27 1.27)
							)
						)
					)
				)
				(pin passive line
					(at 0 -2.54 0)
					(length 5.08)
					(hide yes)
					(name "VDD18"
						(effects
							(font
								(size 1.27 1.27)
							)
						)
					)
					(number "P14"
						(effects
							(font
								(size 1.27 1.27)
							)
						)
					)
				)
				(pin passive line
					(at 0 -2.54 0)
					(length 5.08)
					(hide yes)
					(name "VDD18"
						(effects
							(font
								(size 1.27 1.27)
							)
						)
					)
					(number "P16"
						(effects
							(font
								(size 1.27 1.27)
							)
						)
					)
				)
				(pin passive line
					(at 0 -2.54 0)
					(length 5.08)
					(hide yes)
					(name "VDD18"
						(effects
							(font
								(size 1.27 1.27)
							)
						)
					)
					(number "R13"
						(effects
							(font
								(size 1.27 1.27)
							)
						)
					)
				)
				(pin power_in line
					(at 0 -5.08 0)
					(length 5.08)
					(name "VDD25"
						(effects
							(font
								(size 1.27 1.27)
							)
						)
					)
					(number "H8"
						(effects
							(font
								(size 1.27 1.27)
							)
						)
					)
				)
				(pin passive line
					(at 0 -5.08 0)
					(length 5.08)
					(hide yes)
					(name "VDD25"
						(effects
							(font
								(size 1.27 1.27)
							)
						)
					)
					(number "J17"
						(effects
							(font
								(size 1.27 1.27)
							)
						)
					)
				)
				(pin passive line
					(at 0 -5.08 0)
					(length 5.08)
					(hide yes)
					(name "VDD25"
						(effects
							(font
								(size 1.27 1.27)
							)
						)
					)
					(number "L15"
						(effects
							(font
								(size 1.27 1.27)
							)
						)
					)
				)
				(pin passive line
					(at 0 -5.08 0)
					(length 5.08)
					(hide yes)
					(name "VDD25"
						(effects
							(font
								(size 1.27 1.27)
							)
						)
					)
					(number "R17"
						(effects
							(font
								(size 1.27 1.27)
							)
						)
					)
				)
				(pin passive line
					(at 0 -5.08 0)
					(length 5.08)
					(hide yes)
					(name "VDD25"
						(effects
							(font
								(size 1.27 1.27)
							)
						)
					)
					(number "R9"
						(effects
							(font
								(size 1.27 1.27)
							)
						)
					)
				)
				(pin power_in line
					(at 0 -7.62 0)
					(length 5.08)
					(name "VDDA"
						(effects
							(font
								(size 1.27 1.27)
							)
						)
					)
					(number "G21"
						(effects
							(font
								(size 1.27 1.27)
							)
						)
					)
				)
				(pin passive line
					(at 0 -7.62 0)
					(length 5.08)
					(hide yes)
					(name "VDDA"
						(effects
							(font
								(size 1.27 1.27)
							)
						)
					)
					(number "J21"
						(effects
							(font
								(size 1.27 1.27)
							)
						)
					)
				)
				(pin passive line
					(at 0 -7.62 0)
					(length 5.08)
					(hide yes)
					(name "VDDA"
						(effects
							(font
								(size 1.27 1.27)
							)
						)
					)
					(number "K19"
						(effects
							(font
								(size 1.27 1.27)
							)
						)
					)
				)
				(pin passive line
					(at 0 -7.62 0)
					(length 5.08)
					(hide yes)
					(name "VDDA"
						(effects
							(font
								(size 1.27 1.27)
							)
						)
					)
					(number "L21"
						(effects
							(font
								(size 1.27 1.27)
							)
						)
					)
				)
				(pin passive line
					(at 0 -7.62 0)
					(length 5.08)
					(hide yes)
					(name "VDDA"
						(effects
							(font
								(size 1.27 1.27)
							)
						)
					)
					(number "N21"
						(effects
							(font
								(size 1.27 1.27)
							)
						)
					)
				)
				(pin passive line
					(at 0 -7.62 0)
					(length 5.08)
					(hide yes)
					(name "VDDA"
						(effects
							(font
								(size 1.27 1.27)
							)
						)
					)
					(number "P19"
						(effects
							(font
								(size 1.27 1.27)
							)
						)
					)
				)
				(pin passive line
					(at 0 -7.62 0)
					(length 5.08)
					(hide yes)
					(name "VDDA"
						(effects
							(font
								(size 1.27 1.27)
							)
						)
					)
					(number "R21"
						(effects
							(font
								(size 1.27 1.27)
							)
						)
					)
				)
				(pin power_in line
					(at 0 -10.16 0)
					(length 5.08)
					(name "VDDA25"
						(effects
							(font
								(size 1.27 1.27)
							)
						)
					)
					(number "J18"
						(effects
							(font
								(size 1.27 1.27)
							)
						)
					)
				)
				(pin passive line
					(at 0 -10.16 0)
					(length 5.08)
					(hide yes)
					(name "VDDA25"
						(effects
							(font
								(size 1.27 1.27)
							)
						)
					)
					(number "M18"
						(effects
							(font
								(size 1.27 1.27)
							)
						)
					)
				)
				(pin power_in line
					(at 0 -12.7 0)
					(length 5.08)
					(name "VDDAUX1"
						(effects
							(font
								(size 1.27 1.27)
							)
						)
					)
					(number "H14"
						(effects
							(font
								(size 1.27 1.27)
							)
						)
					)
				)
				(pin passive line
					(at 0 -12.7 0)
					(length 5.08)
					(hide yes)
					(name "VDDAUX1"
						(effects
							(font
								(size 1.27 1.27)
							)
						)
					)
					(number "H16"
						(effects
							(font
								(size 1.27 1.27)
							)
						)
					)
				)
				(pin passive line
					(at 0 -12.7 0)
					(length 5.08)
					(hide yes)
					(name "VDDAUX1"
						(effects
							(font
								(size 1.27 1.27)
							)
						)
					)
					(number "J13"
						(effects
							(font
								(size 1.27 1.27)
							)
						)
					)
				)
				(pin passive line
					(at 0 -12.7 0)
					(length 5.08)
					(hide yes)
					(name "VDDAUX1"
						(effects
							(font
								(size 1.27 1.27)
							)
						)
					)
					(number "J9"
						(effects
							(font
								(size 1.27 1.27)
							)
						)
					)
				)
				(pin passive line
					(at 0 -12.7 0)
					(length 5.08)
					(hide yes)
					(name "VDDAUX1"
						(effects
							(font
								(size 1.27 1.27)
							)
						)
					)
					(number "K10"
						(effects
							(font
								(size 1.27 1.27)
							)
						)
					)
				)
				(pin power_in line
					(at 0 -15.24 0)
					(length 5.08)
					(name "VDDAUX2"
						(effects
							(font
								(size 1.27 1.27)
							)
						)
					)
					(number "K8"
						(effects
							(font
								(size 1.27 1.27)
							)
						)
					)
				)
				(pin passive line
					(at 0 -15.24 0)
					(length 5.08)
					(hide yes)
					(name "VDDAUX2"
						(effects
							(font
								(size 1.27 1.27)
							)
						)
					)
					(number "L9"
						(effects
							(font
								(size 1.27 1.27)
							)
						)
					)
				)
				(pin power_in line
					(at 0 -17.78 0)
					(length 5.08)
					(name "VDDAUX4"
						(effects
							(font
								(size 1.27 1.27)
							)
						)
					)
					(number "M10"
						(effects
							(font
								(size 1.27 1.27)
							)
						)
					)
				)
				(pin passive line
					(at 0 -17.78 0)
					(length 5.08)
					(hide yes)
					(name "VDDAUX4"
						(effects
							(font
								(size 1.27 1.27)
							)
						)
					)
					(number "N9"
						(effects
							(font
								(size 1.27 1.27)
							)
						)
					)
				)
				(pin passive line
					(at 0 -20.32 0)
					(length 5.08)
					(name "VSS"
						(effects
							(font
								(size 1.27 1.27)
							)
						)
					)
					(number "A1"
						(effects
							(font
								(size 1.27 1.27)
							)
						)
					)
				)
				(pin passive line
					(at 0 -20.32 0)
					(length 5.08)
					(hide yes)
					(name "VSS"
						(effects
							(font
								(size 1.27 1.27)
							)
						)
					)
					(number "A14"
						(effects
							(font
								(size 1.27 1.27)
							)
						)
					)
				)
				(pin passive line
					(at 0 -20.32 0)
					(length 5.08)
					(hide yes)
					(name "VSS"
						(effects
							(font
								(size 1.27 1.27)
							)
						)
					)
					(number "A22"
						(effects
							(font
								(size 1.27 1.27)
							)
						)
					)
				)
				(pin passive line
					(at 0 -20.32 0)
					(length 5.08)
					(hide yes)
					(name "VSS"
						(effects
							(font
								(size 1.27 1.27)
							)
						)
					)
					(number "A4"
						(effects
							(font
								(size 1.27 1.27)
							)
						)
					)
				)
				(pin passive line
					(at 0 -20.32 0)
					(length 5.08)
					(hide yes)
					(name "VSS"
						(effects
							(font
								(size 1.27 1.27)
							)
						)
					)
					(number "AA14"
						(effects
							(font
								(size 1.27 1.27)
							)
						)
					)
				)
				(pin passive line
					(at 0 -20.32 0)
					(length 5.08)
					(hide yes)
					(name "VSS"
						(effects
							(font
								(size 1.27 1.27)
							)
						)
					)
					(number "AA4"
						(effects
							(font
								(size 1.27 1.27)
							)
						)
					)
				)
				(pin passive line
					(at 0 -20.32 0)
					(length 5.08)
					(hide yes)
					(name "VSS"
						(effects
							(font
								(size 1.27 1.27)
							)
						)
					)
					(number "AB1"
						(effects
							(font
								(size 1.27 1.27)
							)
						)
					)
				)
				(pin passive line
					(at 0 -20.32 0)
					(length 5.08)
					(hide yes)
					(name "VSS"
						(effects
							(font
								(size 1.27 1.27)
							)
						)
					)
					(number "AB11"
						(effects
							(font
								(size 1.27 1.27)
							)
						)
					)
				)
				(pin passive line
					(at 0 -20.32 0)
					(length 5.08)
					(hide yes)
					(name "VSS"
						(effects
							(font
								(size 1.27 1.27)
							)
						)
					)
					(number "AB22"
						(effects
							(font
								(size 1.27 1.27)
							)
						)
					)
				)
				(pin passive line
					(at 0 -20.32 0)
					(length 5.08)
					(hide yes)
					(name "VSS"
						(effects
							(font
								(size 1.27 1.27)
							)
						)
					)
					(number "B11"
						(effects
							(font
								(size 1.27 1.27)
							)
						)
					)
				)
				(pin passive line
					(at 0 -20.32 0)
					(length 5.08)
					(hide yes)
					(name "VSS"
						(effects
							(font
								(size 1.27 1.27)
							)
						)
					)
					(number "C18"
						(effects
							(font
								(size 1.27 1.27)
							)
						)
					)
				)
				(pin passive line
					(at 0 -20.32 0)
					(length 5.08)
					(hide yes)
					(name "VSS"
						(effects
							(font
								(size 1.27 1.27)
							)
						)
					)
					(number "C8"
						(effects
							(font
								(size 1.27 1.27)
							)
						)
					)
				)
				(pin passive line
					(at 0 -20.32 0)
					(length 5.08)
					(hide yes)
					(name "VSS"
						(effects
							(font
								(size 1.27 1.27)
							)
						)
					)
					(number "D15"
						(effects
							(font
								(size 1.27 1.27)
							)
						)
					)
				)
				(pin passive line
					(at 0 -20.32 0)
					(length 5.08)
					(hide yes)
					(name "VSS"
						(effects
							(font
								(size 1.27 1.27)
							)
						)
					)
					(number "D5"
						(effects
							(font
								(size 1.27 1.27)
							)
						)
					)
				)
				(pin passive line
					(at 0 -20.32 0)
					(length 5.08)
					(hide yes)
					(name "VSS"
						(effects
							(font
								(size 1.27 1.27)
							)
						)
					)
					(number "E12"
						(effects
							(font
								(size 1.27 1.27)
							)
						)
					)
				)
				(pin passive line
					(at 0 -20.32 0)
					(length 5.08)
					(hide yes)
					(name "VSS"
						(effects
							(font
								(size 1.27 1.27)
							)
						)
					)
					(number "E2"
						(effects
							(font
								(size 1.27 1.27)
							)
						)
					)
				)
				(pin passive line
					(at 0 -20.32 0)
					(length 5.08)
					(hide yes)
					(name "VSS"
						(effects
							(font
								(size 1.27 1.27)
							)
						)
					)
					(number "E20"
						(effects
							(font
								(size 1.27 1.27)
							)
						)
					)
				)
				(pin passive line
					(at 0 -20.32 0)
					(length 5.08)
					(hide yes)
					(name "VSS"
						(effects
							(font
								(size 1.27 1.27)
							)
						)
					)
					(number "E21"
						(effects
							(font
								(size 1.27 1.27)
							)
						)
					)
				)
				(pin passive line
					(at 0 -20.32 0)
					(length 5.08)
					(hide yes)
					(name "VSS"
						(effects
							(font
								(size 1.27 1.27)
							)
						)
					)
					(number "E22"
						(effects
							(font
								(size 1.27 1.27)
							)
						)
					)
				)
				(pin passive line
					(at 0 -20.32 0)
					(length 5.08)
					(hide yes)
					(name "VSS"
						(effects
							(font
								(size 1.27 1.27)
							)
						)
					)
					(number "F18"
						(effects
							(font
								(size 1.27 1.27)
							)
						)
					)
				)
				(pin passive line
					(at 0 -20.32 0)
					(length 5.08)
					(hide yes)
					(name "VSS"
						(effects
							(font
								(size 1.27 1.27)
							)
						)
					)
					(number "F19"
						(effects
							(font
								(size 1.27 1.27)
							)
						)
					)
				)
				(pin passive line
					(at 0 -20.32 0)
					(length 5.08)
					(hide yes)
					(name "VSS"
						(effects
							(font
								(size 1.27 1.27)
							)
						)
					)
					(number "F20"
						(effects
							(font
								(size 1.27 1.27)
							)
						)
					)
				)
				(pin passive line
					(at 0 -20.32 0)
					(length 5.08)
					(hide yes)
					(name "VSS"
						(effects
							(font
								(size 1.27 1.27)
							)
						)
					)
					(number "F9"
						(effects
							(font
								(size 1.27 1.27)
							)
						)
					)
				)
				(pin passive line
					(at 0 -20.32 0)
					(length 5.08)
					(hide yes)
					(name "VSS"
						(effects
							(font
								(size 1.27 1.27)
							)
						)
					)
					(number "G16"
						(effects
							(font
								(size 1.27 1.27)
							)
						)
					)
				)
				(pin passive line
					(at 0 -20.32 0)
					(length 5.08)
					(hide yes)
					(name "VSS"
						(effects
							(font
								(size 1.27 1.27)
							)
						)
					)
					(number "G18"
						(effects
							(font
								(size 1.27 1.27)
							)
						)
					)
				)
				(pin passive line
					(at 0 -20.32 0)
					(length 5.08)
					(hide yes)
					(name "VSS"
						(effects
							(font
								(size 1.27 1.27)
							)
						)
					)
					(number "G22"
						(effects
							(font
								(size 1.27 1.27)
							)
						)
					)
				)
				(pin passive line
					(at 0 -20.32 0)
					(length 5.08)
					(hide yes)
					(name "VSS"
						(effects
							(font
								(size 1.27 1.27)
							)
						)
					)
					(number "G6"
						(effects
							(font
								(size 1.27 1.27)
							)
						)
					)
				)
				(pin passive line
					(at 0 -20.32 0)
					(length 5.08)
					(hide yes)
					(name "VSS"
						(effects
							(font
								(size 1.27 1.27)
							)
						)
					)
					(number "H20"
						(effects
							(font
								(size 1.27 1.27)
							)
						)
					)
				)
				(pin passive line
					(at 0 -20.32 0)
					(length 5.08)
					(hide yes)
					(name "VSS"
						(effects
							(font
								(size 1.27 1.27)
							)
						)
					)
					(number "H3"
						(effects
							(font
								(size 1.27 1.27)
							)
						)
					)
				)
				(pin passive line
					(at 0 -20.32 0)
					(length 5.08)
					(hide yes)
					(name "VSS"
						(effects
							(font
								(size 1.27 1.27)
							)
						)
					)
					(number "J10"
						(effects
							(font
								(size 1.27 1.27)
							)
						)
					)
				)
				(pin passive line
					(at 0 -20.32 0)
					(length 5.08)
					(hide yes)
					(name "VSS"
						(effects
							(font
								(size 1.27 1.27)
							)
						)
					)
					(number "J12"
						(effects
							(font
								(size 1.27 1.27)
							)
						)
					)
				)
				(pin passive line
					(at 0 -20.32 0)
					(length 5.08)
					(hide yes)
					(name "VSS"
						(effects
							(font
								(size 1.27 1.27)
							)
						)
					)
					(number "J14"
						(effects
							(font
								(size 1.27 1.27)
							)
						)
					)
				)
				(pin passive line
					(at 0 -20.32 0)
					(length 5.08)
					(hide yes)
					(name "VSS"
						(effects
							(font
								(size 1.27 1.27)
							)
						)
					)
					(number "J16"
						(effects
							(font
								(size 1.27 1.27)
							)
						)
					)
				)
				(pin passive line
					(at 0 -20.32 0)
					(length 5.08)
					(hide yes)
					(name "VSS"
						(effects
							(font
								(size 1.27 1.27)
							)
						)
					)
					(number "J22"
						(effects
							(font
								(size 1.27 1.27)
							)
						)
					)
				)
				(pin passive line
					(at 0 -20.32 0)
					(length 5.08)
					(hide yes)
					(name "VSS"
						(effects
							(font
								(size 1.27 1.27)
							)
						)
					)
					(number "J8"
						(effects
							(font
								(size 1.27 1.27)
							)
						)
					)
				)
				(pin passive line
					(at 0 -20.32 0)
					(length 5.08)
					(hide yes)
					(name "VSS"
						(effects
							(font
								(size 1.27 1.27)
							)
						)
					)
					(number "K11"
						(effects
							(font
								(size 1.27 1.27)
							)
						)
					)
				)
				(pin passive line
					(at 0 -20.32 0)
					(length 5.08)
					(hide yes)
					(name "VSS"
						(effects
							(font
								(size 1.27 1.27)
							)
						)
					)
					(number "K13"
						(effects
							(font
								(size 1.27 1.27)
							)
						)
					)
				)
				(pin passive line
					(at 0 -20.32 0)
					(length 5.08)
					(hide yes)
					(name "VSS"
						(effects
							(font
								(size 1.27 1.27)
							)
						)
					)
					(number "K15"
						(effects
							(font
								(size 1.27 1.27)
							)
						)
					)
				)
				(pin passive line
					(at 0 -20.32 0)
					(length 5.08)
					(hide yes)
					(name "VSS"
						(effects
							(font
								(size 1.27 1.27)
							)
						)
					)
					(number "K17"
						(effects
							(font
								(size 1.27 1.27)
							)
						)
					)
				)
				(pin passive line
					(at 0 -20.32 0)
					(length 5.08)
					(hide yes)
					(name "VSS"
						(effects
							(font
								(size 1.27 1.27)
							)
						)
					)
					(number "K20"
						(effects
							(font
								(size 1.27 1.27)
							)
						)
					)
				)
				(pin passive line
					(at 0 -20.32 0)
					(length 5.08)
					(hide yes)
					(name "VSS"
						(effects
							(font
								(size 1.27 1.27)
							)
						)
					)
					(number "K9"
						(effects
							(font
								(size 1.27 1.27)
							)
						)
					)
				)
				(pin passive line
					(at 0 -20.32 0)
					(length 5.08)
					(hide yes)
					(name "VSS"
						(effects
							(font
								(size 1.27 1.27)
							)
						)
					)
					(number "L10"
						(effects
							(font
								(size 1.27 1.27)
							)
						)
					)
				)
				(pin passive line
					(at 0 -20.32 0)
					(length 5.08)
					(hide yes)
					(name "VSS"
						(effects
							(font
								(size 1.27 1.27)
							)
						)
					)
					(number "L12"
						(effects
							(font
								(size 1.27 1.27)
							)
						)
					)
				)
				(pin passive line
					(at 0 -20.32 0)
					(length 5.08)
					(hide yes)
					(name "VSS"
						(effects
							(font
								(size 1.27 1.27)
							)
						)
					)
					(number "L14"
						(effects
							(font
								(size 1.27 1.27)
							)
						)
					)
				)
				(pin passive line
					(at 0 -20.32 0)
					(length 5.08)
					(hide yes)
					(name "VSS"
						(effects
							(font
								(size 1.27 1.27)
							)
						)
					)
					(number "L16"
						(effects
							(font
								(size 1.27 1.27)
							)
						)
					)
				)
				(pin passive line
					(at 0 -20.32 0)
					(length 5.08)
					(hide yes)
					(name "VSS"
						(effects
							(font
								(size 1.27 1.27)
							)
						)
					)
					(number "L18"
						(effects
							(font
								(size 1.27 1.27)
							)
						)
					)
				)
				(pin passive line
					(at 0 -20.32 0)
					(length 5.08)
					(hide yes)
					(name "VSS"
						(effects
							(font
								(size 1.27 1.27)
							)
						)
					)
					(number "L22"
						(effects
							(font
								(size 1.27 1.27)
							)
						)
					)
				)
				(pin passive line
					(at 0 -20.32 0)
					(length 5.08)
					(hide yes)
					(name "VSS"
						(effects
							(font
								(size 1.27 1.27)
							)
						)
					)
					(number "L4"
						(effects
							(font
								(size 1.27 1.27)
							)
						)
					)
				)
				(pin passive line
					(at 0 -20.32 0)
					(length 5.08)
					(hide yes)
					(name "VSS"
						(effects
							(font
								(size 1.27 1.27)
							)
						)
					)
					(number "M1"
						(effects
							(font
								(size 1.27 1.27)
							)
						)
					)
				)
				(pin passive line
					(at 0 -20.32 0)
					(length 5.08)
					(hide yes)
					(name "VSS"
						(effects
							(font
								(size 1.27 1.27)
							)
						)
					)
					(number "M11"
						(effects
							(font
								(size 1.27 1.27)
							)
						)
					)
				)
				(pin passive line
					(at 0 -20.32 0)
					(length 5.08)
					(hide yes)
					(name "VSS"
						(effects
							(font
								(size 1.27 1.27)
							)
						)
					)
					(number "M13"
						(effects
							(font
								(size 1.27 1.27)
							)
						)
					)
				)
				(pin passive line
					(at 0 -20.32 0)
					(length 5.08)
					(hide yes)
					(name "VSS"
						(effects
							(font
								(size 1.27 1.27)
							)
						)
					)
					(number "M15"
						(effects
							(font
								(size 1.27 1.27)
							)
						)
					)
				)
				(pin passive line
					(at 0 -20.32 0)
					(length 5.08)
					(hide yes)
					(name "VSS"
						(effects
							(font
								(size 1.27 1.27)
							)
						)
					)
					(number "M17"
						(effects
							(font
								(size 1.27 1.27)
							)
						)
					)
				)
				(pin passive line
					(at 0 -20.32 0)
					(length 5.08)
					(hide yes)
					(name "VSS"
						(effects
							(font
								(size 1.27 1.27)
							)
						)
					)
					(number "M19"
						(effects
							(font
								(size 1.27 1.27)
							)
						)
					)
				)
				(pin passive line
					(at 0 -20.32 0)
					(length 5.08)
					(hide yes)
					(name "VSS"
						(effects
							(font
								(size 1.27 1.27)
							)
						)
					)
					(number "M20"
						(effects
							(font
								(size 1.27 1.27)
							)
						)
					)
				)
				(pin passive line
					(at 0 -20.32 0)
					(length 5.08)
					(hide yes)
					(name "VSS"
						(effects
							(font
								(size 1.27 1.27)
							)
						)
					)
					(number "M9"
						(effects
							(font
								(size 1.27 1.27)
							)
						)
					)
				)
				(pin passive line
					(at 0 -20.32 0)
					(length 5.08)
					(hide yes)
					(name "VSS"
						(effects
							(font
								(size 1.27 1.27)
							)
						)
					)
					(number "N10"
						(effects
							(font
								(size 1.27 1.27)
							)
						)
					)
				)
				(pin passive line
					(at 0 -20.32 0)
					(length 5.08)
					(hide yes)
					(name "VSS"
						(effects
							(font
								(size 1.27 1.27)
							)
						)
					)
					(number "N12"
						(effects
							(font
								(size 1.27 1.27)
							)
						)
					)
				)
				(pin passive line
					(at 0 -20.32 0)
					(length 5.08)
					(hide yes)
					(name "VSS"
						(effects
							(font
								(size 1.27 1.27)
							)
						)
					)
					(number "N14"
						(effects
							(font
								(size 1.27 1.27)
							)
						)
					)
				)
				(pin passive line
					(at 0 -20.32 0)
					(length 5.08)
					(hide yes)
					(name "VSS"
						(effects
							(font
								(size 1.27 1.27)
							)
						)
					)
					(number "N16"
						(effects
							(font
								(size 1.27 1.27)
							)
						)
					)
				)
				(pin passive line
					(at 0 -20.32 0)
					(length 5.08)
					(hide yes)
					(name "VSS"
						(effects
							(font
								(size 1.27 1.27)
							)
						)
					)
					(number "N18"
						(effects
							(font
								(size 1.27 1.27)
							)
						)
					)
				)
				(pin passive line
					(at 0 -20.32 0)
					(length 5.08)
					(hide yes)
					(name "VSS"
						(effects
							(font
								(size 1.27 1.27)
							)
						)
					)
					(number "N22"
						(effects
							(font
								(size 1.27 1.27)
							)
						)
					)
				)
				(pin passive line
					(at 0 -20.32 0)
					(length 5.08)
					(hide yes)
					(name "VSS"
						(effects
							(font
								(size 1.27 1.27)
							)
						)
					)
					(number "P11"
						(effects
							(font
								(size 1.27 1.27)
							)
						)
					)
				)
				(pin passive line
					(at 0 -20.32 0)
					(length 5.08)
					(hide yes)
					(name "VSS"
						(effects
							(font
								(size 1.27 1.27)
							)
						)
					)
					(number "P13"
						(effects
							(font
								(size 1.27 1.27)
							)
						)
					)
				)
				(pin passive line
					(at 0 -20.32 0)
					(length 5.08)
					(hide yes)
					(name "VSS"
						(effects
							(font
								(size 1.27 1.27)
							)
						)
					)
					(number "P15"
						(effects
							(font
								(size 1.27 1.27)
							)
						)
					)
				)
				(pin passive line
					(at 0 -20.32 0)
					(length 5.08)
					(hide yes)
					(name "VSS"
						(effects
							(font
								(size 1.27 1.27)
							)
						)
					)
					(number "P17"
						(effects
							(font
								(size 1.27 1.27)
							)
						)
					)
				)
				(pin passive line
					(at 0 -20.32 0)
					(length 5.08)
					(hide yes)
					(name "VSS"
						(effects
							(font
								(size 1.27 1.27)
							)
						)
					)
					(number "P20"
						(effects
							(font
								(size 1.27 1.27)
							)
						)
					)
				)
				(pin passive line
					(at 0 -20.32 0)
					(length 5.08)
					(hide yes)
					(name "VSS"
						(effects
							(font
								(size 1.27 1.27)
							)
						)
					)
					(number "P5"
						(effects
							(font
								(size 1.27 1.27)
							)
						)
					)
				)
				(pin passive line
					(at 0 -20.32 0)
					(length 5.08)
					(hide yes)
					(name "VSS"
						(effects
							(font
								(size 1.27 1.27)
							)
						)
					)
					(number "P9"
						(effects
							(font
								(size 1.27 1.27)
							)
						)
					)
				)
				(pin passive line
					(at 0 -20.32 0)
					(length 5.08)
					(hide yes)
					(name "VSS"
						(effects
							(font
								(size 1.27 1.27)
							)
						)
					)
					(number "R18"
						(effects
							(font
								(size 1.27 1.27)
							)
						)
					)
				)
				(pin passive line
					(at 0 -20.32 0)
					(length 5.08)
					(hide yes)
					(name "VSS"
						(effects
							(font
								(size 1.27 1.27)
							)
						)
					)
					(number "R2"
						(effects
							(font
								(size 1.27 1.27)
							)
						)
					)
				)
				(pin passive line
					(at 0 -20.32 0)
					(length 5.08)
					(hide yes)
					(name "VSS"
						(effects
							(font
								(size 1.27 1.27)
							)
						)
					)
					(number "R22"
						(effects
							(font
								(size 1.27 1.27)
							)
						)
					)
				)
				(pin passive line
					(at 0 -20.32 0)
					(length 5.08)
					(hide yes)
					(name "VSS"
						(effects
							(font
								(size 1.27 1.27)
							)
						)
					)
					(number "T18"
						(effects
							(font
								(size 1.27 1.27)
							)
						)
					)
				)
				(pin passive line
					(at 0 -20.32 0)
					(length 5.08)
					(hide yes)
					(name "VSS"
						(effects
							(font
								(size 1.27 1.27)
							)
						)
					)
					(number "T19"
						(effects
							(font
								(size 1.27 1.27)
							)
						)
					)
				)
				(pin passive line
					(at 0 -20.32 0)
					(length 5.08)
					(hide yes)
					(name "VSS"
						(effects
							(font
								(size 1.27 1.27)
							)
						)
					)
					(number "T20"
						(effects
							(font
								(size 1.27 1.27)
							)
						)
					)
				)
				(pin passive line
					(at 0 -20.32 0)
					(length 5.08)
					(hide yes)
					(name "VSS"
						(effects
							(font
								(size 1.27 1.27)
							)
						)
					)
					(number "T9"
						(effects
							(font
								(size 1.27 1.27)
							)
						)
					)
				)
				(pin passive line
					(at 0 -20.32 0)
					(length 5.08)
					(hide yes)
					(name "VSS"
						(effects
							(font
								(size 1.27 1.27)
							)
						)
					)
					(number "U16"
						(effects
							(font
								(size 1.27 1.27)
							)
						)
					)
				)
				(pin passive line
					(at 0 -20.32 0)
					(length 5.08)
					(hide yes)
					(name "VSS"
						(effects
							(font
								(size 1.27 1.27)
							)
						)
					)
					(number "U20"
						(effects
							(font
								(size 1.27 1.27)
							)
						)
					)
				)
				(pin passive line
					(at 0 -20.32 0)
					(length 5.08)
					(hide yes)
					(name "VSS"
						(effects
							(font
								(size 1.27 1.27)
							)
						)
					)
					(number "U21"
						(effects
							(font
								(size 1.27 1.27)
							)
						)
					)
				)
				(pin passive line
					(at 0 -20.32 0)
					(length 5.08)
					(hide yes)
					(name "VSS"
						(effects
							(font
								(size 1.27 1.27)
							)
						)
					)
					(number "U22"
						(effects
							(font
								(size 1.27 1.27)
							)
						)
					)
				)
				(pin passive line
					(at 0 -20.32 0)
					(length 5.08)
					(hide yes)
					(name "VSS"
						(effects
							(font
								(size 1.27 1.27)
							)
						)
					)
					(number "U6"
						(effects
							(font
								(size 1.27 1.27)
							)
						)
					)
				)
				(pin passive line
					(at 0 -20.32 0)
					(length 5.08)
					(hide yes)
					(name "VSS"
						(effects
							(font
								(size 1.27 1.27)
							)
						)
					)
					(number "V13"
						(effects
							(font
								(size 1.27 1.27)
							)
						)
					)
				)
				(pin passive line
					(at 0 -20.32 0)
					(length 5.08)
					(hide yes)
					(name "VSS"
						(effects
							(font
								(size 1.27 1.27)
							)
						)
					)
					(number "V3"
						(effects
							(font
								(size 1.27 1.27)
							)
						)
					)
				)
				(pin passive line
					(at 0 -20.32 0)
					(length 5.08)
					(hide yes)
					(name "VSS"
						(effects
							(font
								(size 1.27 1.27)
							)
						)
					)
					(number "W10"
						(effects
							(font
								(size 1.27 1.27)
							)
						)
					)
				)
				(pin passive line
					(at 0 -20.32 0)
					(length 5.08)
					(hide yes)
					(name "VSS"
						(effects
							(font
								(size 1.27 1.27)
							)
						)
					)
					(number "W20"
						(effects
							(font
								(size 1.27 1.27)
							)
						)
					)
				)
				(pin passive line
					(at 0 -20.32 0)
					(length 5.08)
					(hide yes)
					(name "VSS"
						(effects
							(font
								(size 1.27 1.27)
							)
						)
					)
					(number "Y17"
						(effects
							(font
								(size 1.27 1.27)
							)
						)
					)
				)
				(pin passive line
					(at 0 -20.32 0)
					(length 5.08)
					(hide yes)
					(name "VSS"
						(effects
							(font
								(size 1.27 1.27)
							)
						)
					)
					(number "Y7"
						(effects
							(font
								(size 1.27 1.27)
							)
						)
					)
				)
				(pin power_in line
					(at 33.02 0 180)
					(length 5.08)
					(name "VDDI0"
						(effects
							(font
								(size 1.27 1.27)
							)
						)
					)
					(number "AA19"
						(effects
							(font
								(size 1.27 1.27)
							)
						)
					)
				)
				(pin passive line
					(at 33.02 0 180)
					(length 5.08)
					(hide yes)
					(name "VDDI0"
						(effects
							(font
								(size 1.27 1.27)
							)
						)
					)
					(number "AB16"
						(effects
							(font
								(size 1.27 1.27)
							)
						)
					)
				)
				(pin passive line
					(at 33.02 0 180)
					(length 5.08)
					(hide yes)
					(name "VDDI0"
						(effects
							(font
								(size 1.27 1.27)
							)
						)
					)
					(number "T14"
						(effects
							(font
								(size 1.27 1.27)
							)
						)
					)
				)
				(pin passive line
					(at 33.02 0 180)
					(length 5.08)
					(hide yes)
					(name "VDDI0"
						(effects
							(font
								(size 1.27 1.27)
							)
						)
					)
					(number "V18"
						(effects
							(font
								(size 1.27 1.27)
							)
						)
					)
				)
				(pin passive line
					(at 33.02 0 180)
					(length 5.08)
					(hide yes)
					(name "VDDI0"
						(effects
							(font
								(size 1.27 1.27)
							)
						)
					)
					(number "W15"
						(effects
							(font
								(size 1.27 1.27)
							)
						)
					)
				)
				(pin passive line
					(at 33.02 0 180)
					(length 5.08)
					(hide yes)
					(name "VDDI0"
						(effects
							(font
								(size 1.27 1.27)
							)
						)
					)
					(number "Y12"
						(effects
							(font
								(size 1.27 1.27)
							)
						)
					)
				)
				(pin passive line
					(at 33.02 0 180)
					(length 5.08)
					(hide yes)
					(name "VDDI0"
						(effects
							(font
								(size 1.27 1.27)
							)
						)
					)
					(number "Y22"
						(effects
							(font
								(size 1.27 1.27)
							)
						)
					)
				)
				(pin power_in line
					(at 33.02 -2.54 180)
					(length 5.08)
					(name "VDDI1"
						(effects
							(font
								(size 1.27 1.27)
							)
						)
					)
					(number "A19"
						(effects
							(font
								(size 1.27 1.27)
							)
						)
					)
				)
				(pin passive line
					(at 33.02 -2.54 180)
					(length 5.08)
					(hide yes)
					(name "VDDI1"
						(effects
							(font
								(size 1.27 1.27)
							)
						)
					)
					(number "A9"
						(effects
							(font
								(size 1.27 1.27)
							)
						)
					)
				)
				(pin passive line
					(at 33.02 -2.54 180)
					(length 5.08)
					(hide yes)
					(name "VDDI1"
						(effects
							(font
								(size 1.27 1.27)
							)
						)
					)
					(number "B16"
						(effects
							(font
								(size 1.27 1.27)
							)
						)
					)
				)
				(pin passive line
					(at 33.02 -2.54 180)
					(length 5.08)
					(hide yes)
					(name "VDDI1"
						(effects
							(font
								(size 1.27 1.27)
							)
						)
					)
					(number "B6"
						(effects
							(font
								(size 1.27 1.27)
							)
						)
					)
				)
				(pin passive line
					(at 33.02 -2.54 180)
					(length 5.08)
					(hide yes)
					(name "VDDI1"
						(effects
							(font
								(size 1.27 1.27)
							)
						)
					)
					(number "C13"
						(effects
							(font
								(size 1.27 1.27)
							)
						)
					)
				)
				(pin passive line
					(at 33.02 -2.54 180)
					(length 5.08)
					(hide yes)
					(name "VDDI1"
						(effects
							(font
								(size 1.27 1.27)
							)
						)
					)
					(number "C21"
						(effects
							(font
								(size 1.27 1.27)
							)
						)
					)
				)
				(pin passive line
					(at 33.02 -2.54 180)
					(length 5.08)
					(hide yes)
					(name "VDDI1"
						(effects
							(font
								(size 1.27 1.27)
							)
						)
					)
					(number "D10"
						(effects
							(font
								(size 1.27 1.27)
							)
						)
					)
				)
				(pin passive line
					(at 33.02 -2.54 180)
					(length 5.08)
					(hide yes)
					(name "VDDI1"
						(effects
							(font
								(size 1.27 1.27)
							)
						)
					)
					(number "E17"
						(effects
							(font
								(size 1.27 1.27)
							)
						)
					)
				)
				(pin passive line
					(at 33.02 -2.54 180)
					(length 5.08)
					(hide yes)
					(name "VDDI1"
						(effects
							(font
								(size 1.27 1.27)
							)
						)
					)
					(number "F14"
						(effects
							(font
								(size 1.27 1.27)
							)
						)
					)
				)
				(pin passive line
					(at 33.02 -2.54 180)
					(length 5.08)
					(hide yes)
					(name "VDDI1"
						(effects
							(font
								(size 1.27 1.27)
							)
						)
					)
					(number "G11"
						(effects
							(font
								(size 1.27 1.27)
							)
						)
					)
				)
				(pin power_in line
					(at 33.02 -5.08 180)
					(length 5.08)
					(name "VDDI2"
						(effects
							(font
								(size 1.27 1.27)
							)
						)
					)
					(number "C3"
						(effects
							(font
								(size 1.27 1.27)
							)
						)
					)
				)
				(pin passive line
					(at 33.02 -5.08 180)
					(length 5.08)
					(hide yes)
					(name "VDDI2"
						(effects
							(font
								(size 1.27 1.27)
							)
						)
					)
					(number "F4"
						(effects
							(font
								(size 1.27 1.27)
							)
						)
					)
				)
				(pin passive line
					(at 33.02 -5.08 180)
					(length 5.08)
					(hide yes)
					(name "VDDI2"
						(effects
							(font
								(size 1.27 1.27)
							)
						)
					)
					(number "G1"
						(effects
							(font
								(size 1.27 1.27)
							)
						)
					)
				)
				(pin power_in line
					(at 33.02 -7.62 180)
					(length 5.08)
					(name "VDDI3"
						(effects
							(font
								(size 1.27 1.27)
							)
						)
					)
					(number "E7"
						(effects
							(font
								(size 1.27 1.27)
							)
						)
					)
				)
				(pin passive line
					(at 33.02 -7.62 180)
					(length 5.08)
					(hide yes)
					(name "VDDI3"
						(effects
							(font
								(size 1.27 1.27)
							)
						)
					)
					(number "J11"
						(effects
							(font
								(size 1.27 1.27)
							)
						)
					)
				)
				(pin power_in line
					(at 33.02 -10.16 180)
					(length 5.08)
					(name "VDDI4"
						(effects
							(font
								(size 1.27 1.27)
							)
						)
					)
					(number "J5"
						(effects
							(font
								(size 1.27 1.27)
							)
						)
					)
				)
				(pin passive line
					(at 33.02 -10.16 180)
					(length 5.08)
					(hide yes)
					(name "VDDI4"
						(effects
							(font
								(size 1.27 1.27)
							)
						)
					)
					(number "K2"
						(effects
							(font
								(size 1.27 1.27)
							)
						)
					)
				)
				(pin power_in line
					(at 33.02 -12.7 180)
					(length 5.08)
					(name "VDDI5"
						(effects
							(font
								(size 1.27 1.27)
							)
						)
					)
					(number "M6"
						(effects
							(font
								(size 1.27 1.27)
							)
						)
					)
				)
				(pin passive line
					(at 33.02 -12.7 180)
					(length 5.08)
					(hide yes)
					(name "VDDI5"
						(effects
							(font
								(size 1.27 1.27)
							)
						)
					)
					(number "M8"
						(effects
							(font
								(size 1.27 1.27)
							)
						)
					)
				)
				(pin power_in line
					(at 33.02 -15.24 180)
					(length 5.08)
					(name "VDDI6"
						(effects
							(font
								(size 1.27 1.27)
							)
						)
					)
					(number "AA9"
						(effects
							(font
								(size 1.27 1.27)
							)
						)
					)
				)
				(pin passive line
					(at 33.02 -15.24 180)
					(length 5.08)
					(hide yes)
					(name "VDDI6"
						(effects
							(font
								(size 1.27 1.27)
							)
						)
					)
					(number "AB6"
						(effects
							(font
								(size 1.27 1.27)
							)
						)
					)
				)
				(pin passive line
					(at 33.02 -15.24 180)
					(length 5.08)
					(hide yes)
					(name "VDDI6"
						(effects
							(font
								(size 1.27 1.27)
							)
						)
					)
					(number "N3"
						(effects
							(font
								(size 1.27 1.27)
							)
						)
					)
				)
				(pin passive line
					(at 33.02 -15.24 180)
					(length 5.08)
					(hide yes)
					(name "VDDI6"
						(effects
							(font
								(size 1.27 1.27)
							)
						)
					)
					(number "R7"
						(effects
							(font
								(size 1.27 1.27)
							)
						)
					)
				)
				(pin passive line
					(at 33.02 -15.24 180)
					(length 5.08)
					(hide yes)
					(name "VDDI6"
						(effects
							(font
								(size 1.27 1.27)
							)
						)
					)
					(number "T4"
						(effects
							(font
								(size 1.27 1.27)
							)
						)
					)
				)
				(pin passive line
					(at 33.02 -15.24 180)
					(length 5.08)
					(hide yes)
					(name "VDDI6"
						(effects
							(font
								(size 1.27 1.27)
							)
						)
					)
					(number "U1"
						(effects
							(font
								(size 1.27 1.27)
							)
						)
					)
				)
				(pin passive line
					(at 33.02 -15.24 180)
					(length 5.08)
					(hide yes)
					(name "VDDI6"
						(effects
							(font
								(size 1.27 1.27)
							)
						)
					)
					(number "U11"
						(effects
							(font
								(size 1.27 1.27)
							)
						)
					)
				)
				(pin passive line
					(at 33.02 -15.24 180)
					(length 5.08)
					(hide yes)
					(name "VDDI6"
						(effects
							(font
								(size 1.27 1.27)
							)
						)
					)
					(number "V8"
						(effects
							(font
								(size 1.27 1.27)
							)
						)
					)
				)
				(pin passive line
					(at 33.02 -15.24 180)
					(length 5.08)
					(hide yes)
					(name "VDDI6"
						(effects
							(font
								(size 1.27 1.27)
							)
						)
					)
					(number "W5"
						(effects
							(font
								(size 1.27 1.27)
							)
						)
					)
				)
				(pin passive line
					(at 33.02 -15.24 180)
					(length 5.08)
					(hide yes)
					(name "VDDI6"
						(effects
							(font
								(size 1.27 1.27)
							)
						)
					)
					(number "Y2"
						(effects
							(font
								(size 1.27 1.27)
							)
						)
					)
				)
				(pin power_in line
					(at 33.02 -17.78 180)
					(length 5.08)
					(name "XCVR_VREF"
						(effects
							(font
								(size 1.27 1.27)
							)
						)
					)
					(number "H18"
						(effects
							(font
								(size 1.27 1.27)
							)
						)
					)
				)
				(pin passive line
					(at 33.02 -17.78 180)
					(length 5.08)
					(hide yes)
					(name "XCVR_VREF"
						(effects
							(font
								(size 1.27 1.27)
							)
						)
					)
					(number "H19"
						(effects
							(font
								(size 1.27 1.27)
							)
						)
					)
				)
				(pin power_in line
					(at 33.02 -20.32 180)
					(length 5.08)
					(name "VDD_XCVR_CLK"
						(effects
							(font
								(size 1.27 1.27)
							)
						)
					)
					(number "K18"
						(effects
							(font
								(size 1.27 1.27)
							)
						)
					)
				)
				(pin passive line
					(at 33.02 -20.32 180)
					(length 5.08)
					(hide yes)
					(name "VDD_XCVR_CLK"
						(effects
							(font
								(size 1.27 1.27)
							)
						)
					)
					(number "P18"
						(effects
							(font
								(size 1.27 1.27)
							)
						)
					)
				)
			)
		)
	(symbol "antmicroFerriteBeadsandChips:FB_120Z_1.2A_TDK-MPZ_0402"
			(pin_numbers
				(hide yes)
			)
			(pin_names
				(hide yes)
			)
			(exclude_from_sim no)
			(in_bom yes)
			(on_board yes)
			(property "Reference" "FB"
				(at 13.97 0 0)
				(effects
					(font
						(size 1.27 1.27)
						(thickness 0.15)
					)
					(justify left bottom)
				)
			)
			(property "Value" "FB_120Z_1.2A_TDK-MPZ_0402"
				(at 13.97 -2.54 0)
				(effects
					(font
						(size 1.27 1.27)
						(thickness 0.15)
					)
					(justify left bottom)
					(hide yes)
				)
			)
			(property "Footprint" "antmicro-footprints:FB_0402_1005Metric"
				(at 13.97 -7.62 0)
				(effects
					(font
						(size 1.27 1.27)
						(thickness 0.15)
					)
					(justify left bottom)
					(hide yes)
				)
			)
			(property "Datasheet" "https://product.tdk.com/en/search/emc/emc/beads/info?part_no=MPZ1005S121CT000"
				(at 13.97 -10.16 0)
				(effects
					(font
						(size 1.27 1.27)
						(thickness 0.15)
					)
					(justify left bottom)
					(hide yes)
				)
			)
			(property "Description" "Ferrite Bead, 0402 [1005 Metric], 120 ohm, 1.2A, MPZ, 0.06 ohm, ± 25%, DC Power line"
				(at 0 0 0)
				(effects
					(font
						(size 1.27 1.27)
					)
					(hide yes)
				)
			)
			(property "Val" "120Z/1.2A"
				(at 13.97 -5.08 0)
				(effects
					(font
						(size 1.27 1.27)
					)
					(justify left bottom)
				)
			)
			(property "MPN" "MPZ1005S121CT000"
				(at 13.97 -12.7 0)
				(effects
					(font
						(size 1.27 1.27)
						(thickness 0.15)
					)
					(justify left bottom)
					(hide yes)
				)
			)
			(property "Manufacturer" "TDK"
				(at 13.97 -15.24 0)
				(effects
					(font
						(size 1.27 1.27)
						(thickness 0.15)
					)
					(justify left bottom)
					(hide yes)
				)
			)
			(property "Current" ""
				(at 20.32 -22.86 0)
				(effects
					(font
						(size 1.27 1.27)
						(thickness 0.15)
					)
					(justify left bottom)
					(hide yes)
				)
			)
			(property "Author" "Antmicro"
				(at 13.97 -17.78 0)
				(effects
					(font
						(size 1.27 1.27)
						(thickness 0.15)
					)
					(justify left bottom)
					(hide yes)
				)
			)
			(property "License" "Apache-2.0"
				(at 13.97 -20.32 0)
				(effects
					(font
						(size 1.27 1.27)
						(thickness 0.15)
					)
					(justify left bottom)
					(hide yes)
				)
			)
			(property "ki_keywords" "0402, SMT, FERRITE BEAD, PASSIVE"
				(at 0 0 0)
				(effects
					(font
						(size 1.27 1.27)
					)
					(hide yes)
				)
			)
			(symbol "FB_120Z_1.2A_TDK-MPZ_0402_0_1"
				(polyline
					(pts
						(xy 1.651 0) (xy 1.2446 0)
					)
					(stroke
						(width 0)
						(type default)
					)
					(fill
						(type none)
					)
				)
				(polyline
					(pts
						(xy 2.2606 -1.8288) (xy 1.0414 -1.1176) (xy 2.7432 1.8288) (xy 3.9624 1.1176) (xy 2.2606 -1.8288)
					)
					(stroke
						(width 0)
						(type default)
					)
					(fill
						(type none)
					)
				)
				(polyline
					(pts
						(xy 3.81 0) (xy 3.3274 0)
					)
					(stroke
						(width 0)
						(type default)
					)
					(fill
						(type none)
					)
				)
			)
			(symbol "FB_120Z_1.2A_TDK-MPZ_0402_1_1"
				(pin passive line
					(at 0 0 0)
					(length 1.27)
					(name "~"
						(effects
							(font
								(size 1.27 1.27)
							)
						)
					)
					(number "1"
						(effects
							(font
								(size 1.27 1.27)
							)
						)
					)
				)
				(pin passive line
					(at 5.08 0 180)
					(length 1.27)
					(name "~"
						(effects
							(font
								(size 1.27 1.27)
							)
						)
					)
					(number "2"
						(effects
							(font
								(size 1.27 1.27)
							)
						)
					)
				)
			)
		)
	(symbol "antmicroFerriteBeadsandChips:FB_470Z_1A_Murata-BLM18PG_0603"
			(pin_numbers
				(hide yes)
			)
			(pin_names
				(hide yes)
			)
			(exclude_from_sim no)
			(in_bom yes)
			(on_board yes)
			(property "Reference" "FB"
				(at 13.97 0 0)
				(effects
					(font
						(size 1.27 1.27)
						(thickness 0.15)
					)
					(justify left bottom)
				)
			)
			(property "Value" "FB_470Z_1A_Murata-BLM18PG_0603"
				(at 13.97 -2.54 0)
				(effects
					(font
						(size 1.27 1.27)
						(thickness 0.15)
					)
					(justify left bottom)
					(hide yes)
				)
			)
			(property "Footprint" "antmicro-footprints:FB_0603_1608Metric"
				(at 13.97 -7.62 0)
				(effects
					(font
						(size 1.27 1.27)
						(thickness 0.15)
					)
					(justify left bottom)
					(hide yes)
				)
			)
			(property "Datasheet" "https://www.murata.com/en-us/products/productdata/8796738650142/ENFA0003.pdf"
				(at 13.97 -10.16 0)
				(effects
					(font
						(size 1.27 1.27)
						(thickness 0.15)
					)
					(justify left bottom)
					(hide yes)
				)
			)
			(property "Description" "Ferrite Bead, 0603 [1608 Metric], 470 ohm, 1 A, BLM18P, 0.2 ohm, ± 25%, DC power line"
				(at 0 0 0)
				(effects
					(font
						(size 1.27 1.27)
					)
					(hide yes)
				)
			)
			(property "Val" "470Z/1A"
				(at 13.97 -5.08 0)
				(effects
					(font
						(size 1.27 1.27)
					)
					(justify left bottom)
				)
			)
			(property "MPN" "BLM18PG471SN1D"
				(at 13.97 -12.7 0)
				(effects
					(font
						(size 1.27 1.27)
						(thickness 0.15)
					)
					(justify left bottom)
					(hide yes)
				)
			)
			(property "Manufacturer" "Murata"
				(at 13.97 -15.24 0)
				(effects
					(font
						(size 1.27 1.27)
						(thickness 0.15)
					)
					(justify left bottom)
					(hide yes)
				)
			)
			(property "Current" ""
				(at 20.32 -22.86 0)
				(effects
					(font
						(size 1.27 1.27)
						(thickness 0.15)
					)
					(justify left bottom)
					(hide yes)
				)
			)
			(property "Author" "Antmicro"
				(at 13.97 -17.78 0)
				(effects
					(font
						(size 1.27 1.27)
						(thickness 0.15)
					)
					(justify left bottom)
					(hide yes)
				)
			)
			(property "License" "Apache-2.0"
				(at 13.97 -20.32 0)
				(effects
					(font
						(size 1.27 1.27)
						(thickness 0.15)
					)
					(justify left bottom)
					(hide yes)
				)
			)
			(property "ki_keywords" "0603, SMT, FERRITE BEAD, PASSIVE"
				(at 0 0 0)
				(effects
					(font
						(size 1.27 1.27)
					)
					(hide yes)
				)
			)
			(symbol "FB_470Z_1A_Murata-BLM18PG_0603_0_1"
				(polyline
					(pts
						(xy 1.651 0) (xy 1.2446 0)
					)
					(stroke
						(width 0)
						(type default)
					)
					(fill
						(type none)
					)
				)
				(polyline
					(pts
						(xy 2.2606 -1.8288) (xy 1.0414 -1.1176) (xy 2.7432 1.8288) (xy 3.9624 1.1176) (xy 2.2606 -1.8288)
					)
					(stroke
						(width 0)
						(type default)
					)
					(fill
						(type none)
					)
				)
				(polyline
					(pts
						(xy 3.81 0) (xy 3.3274 0)
					)
					(stroke
						(width 0)
						(type default)
					)
					(fill
						(type none)
					)
				)
			)
			(symbol "FB_470Z_1A_Murata-BLM18PG_0603_1_1"
				(pin passive line
					(at 0 0 0)
					(length 1.27)
					(name "~"
						(effects
							(font
								(size 1.27 1.27)
							)
						)
					)
					(number "1"
						(effects
							(font
								(size 1.27 1.27)
							)
						)
					)
				)
				(pin passive line
					(at 5.08 0 180)
					(length 1.27)
					(name "~"
						(effects
							(font
								(size 1.27 1.27)
							)
						)
					)
					(number "2"
						(effects
							(font
								(size 1.27 1.27)
							)
						)
					)
				)
			)
		)
	(symbol "antmicroFixedInductors:L_1u5_2.8A_0806"
			(pin_numbers
				(hide yes)
			)
			(pin_names
				(hide yes)
			)
			(exclude_from_sim no)
			(in_bom yes)
			(on_board yes)
			(property "Reference" "L"
				(at 13.97 0 0)
				(effects
					(font
						(size 1.27 1.27)
						(thickness 0.15)
					)
					(justify left bottom)
				)
			)
			(property "Value" "L_1u5_2.8A_0806"
				(at 13.97 -2.54 0)
				(effects
					(font
						(size 1.27 1.27)
						(thickness 0.15)
					)
					(justify left bottom)
					(hide yes)
				)
			)
			(property "Footprint" "antmicro-footprints:L_0806_2016Metric"
				(at 13.97 -7.62 0)
				(effects
					(font
						(size 1.27 1.27)
						(thickness 0.15)
					)
					(justify left bottom)
					(hide yes)
				)
			)
			(property "Datasheet" "https://abracon.com/datasheets/AOTA-B201610S.pdf"
				(at 13.97 -10.16 0)
				(effects
					(font
						(size 1.27 1.27)
						(thickness 0.15)
					)
					(justify left bottom)
					(hide yes)
				)
			)
			(property "Description" "Power Inductor (SMT), 1.5 µH, 0.074 ohm, 2.8 A, AOTA-B201610S"
				(at 0 0 0)
				(effects
					(font
						(size 1.27 1.27)
					)
					(hide yes)
				)
			)
			(property "Val" "1.5u/2.8A"
				(at 13.97 -5.08 0)
				(effects
					(font
						(size 1.27 1.27)
						(thickness 0.15)
					)
					(justify left bottom)
				)
			)
			(property "Manufacturer" "Abracon"
				(at 13.97 -12.7 0)
				(effects
					(font
						(size 1.27 1.27)
						(thickness 0.15)
					)
					(justify left bottom)
					(hide yes)
				)
			)
			(property "MPN" "AOTA-B201610S1R5MT"
				(at 13.97 -15.24 0)
				(effects
					(font
						(size 1.27 1.27)
						(thickness 0.15)
					)
					(justify left bottom)
					(hide yes)
				)
			)
			(property "ISat" "3.5 A"
				(at 13.97 -16.51 0)
				(effects
					(font
						(size 1.27 1.27)
					)
					(justify left)
					(hide yes)
				)
			)
			(property "IMax" "2.8 A"
				(at 13.97 -20.32 0)
				(effects
					(font
						(size 1.27 1.27)
						(thickness 0.15)
					)
					(justify left bottom)
					(hide yes)
				)
			)
			(property "Size" "2.0x1.6"
				(at 13.97 -22.86 0)
				(effects
					(font
						(size 1.27 1.27)
						(thickness 0.15)
					)
					(justify left bottom)
					(hide yes)
				)
			)
			(property "Author" "Antmicro"
				(at 13.97 -25.4 0)
				(effects
					(font
						(size 1.27 1.27)
						(thickness 0.15)
					)
					(justify left bottom)
					(hide yes)
				)
			)
			(property "License" "Apache-2.0"
				(at 13.97 -27.94 0)
				(effects
					(font
						(size 1.27 1.27)
						(thickness 0.15)
					)
					(justify left bottom)
					(hide yes)
				)
			)
			(property "ki_keywords" "SMT, INDUCTOR, PASSIVE"
				(at 0 0 0)
				(effects
					(font
						(size 1.27 1.27)
					)
					(hide yes)
				)
			)
			(symbol "L_1u5_2.8A_0806_0_1"
				(arc
					(start 0.508 0)
					(mid 1.016 0.5058)
					(end 1.524 0)
					(stroke
						(width 0)
						(type default)
					)
					(fill
						(type none)
					)
				)
				(arc
					(start 1.524 0)
					(mid 2.032 0.5058)
					(end 2.54 0)
					(stroke
						(width 0)
						(type default)
					)
					(fill
						(type none)
					)
				)
				(arc
					(start 2.54 0)
					(mid 3.048 0.5058)
					(end 3.556 0)
					(stroke
						(width 0)
						(type default)
					)
					(fill
						(type none)
					)
				)
				(arc
					(start 3.556 0)
					(mid 4.064 0.5058)
					(end 4.572 0)
					(stroke
						(width 0)
						(type default)
					)
					(fill
						(type none)
					)
				)
			)
			(symbol "L_1u5_2.8A_0806_1_1"
				(pin passive line
					(at 0 0 0)
					(length 0.508)
					(name "~"
						(effects
							(font
								(size 1.27 1.27)
							)
						)
					)
					(number "1"
						(effects
							(font
								(size 1.27 1.27)
							)
						)
					)
				)
				(pin passive line
					(at 5.08 0 180)
					(length 0.508)
					(name "~"
						(effects
							(font
								(size 1.27 1.27)
							)
						)
					)
					(number "2"
						(effects
							(font
								(size 1.27 1.27)
							)
						)
					)
				)
			)
		)
	(symbol "antmicroFixedInductors:L_1u5_7.5A_Coilcraft-XEL4020"
			(pin_numbers
				(hide yes)
			)
			(pin_names
				(hide yes)
			)
			(exclude_from_sim no)
			(in_bom yes)
			(on_board yes)
			(property "Reference" "L"
				(at 13.97 0 0)
				(effects
					(font
						(size 1.27 1.27)
						(thickness 0.15)
					)
					(justify left bottom)
				)
			)
			(property "Value" "L_1u5_7.5A_Coilcraft-XEL4020"
				(at 13.97 -2.54 0)
				(effects
					(font
						(size 1.27 1.27)
						(thickness 0.15)
					)
					(justify left bottom)
					(hide yes)
				)
			)
			(property "Footprint" "antmicro-footprints:L_Coilcraft-XEL4020"
				(at 13.97 -7.62 0)
				(effects
					(font
						(size 1.27 1.27)
						(thickness 0.15)
					)
					(justify left bottom)
					(hide yes)
				)
			)
			(property "Datasheet" "https://www.coilcraft.com/getmedia/3c7caaa2-c1ed-4ff8-84e5-0b1b14a30417/xel4020.pdf"
				(at 13.97 -10.16 0)
				(effects
					(font
						(size 1.27 1.27)
						(thickness 0.15)
					)
					(justify left bottom)
					(hide yes)
				)
			)
			(property "Description" "Power Inductor (SMT), 1.5 µH, 7.5 A, Shielded, 7.4 A, XEL4020-152MEC"
				(at 0 0 0)
				(effects
					(font
						(size 1.27 1.27)
					)
					(hide yes)
				)
			)
			(property "Val" "1u5/7.5A"
				(at 13.97 -5.08 0)
				(effects
					(font
						(size 1.27 1.27)
						(thickness 0.15)
					)
					(justify left bottom)
				)
			)
			(property "Manufacturer" "Coilcraft"
				(at 13.97 -12.7 0)
				(effects
					(font
						(size 1.27 1.27)
						(thickness 0.15)
					)
					(justify left bottom)
					(hide yes)
				)
			)
			(property "MPN" "XEL4020-152MEC "
				(at 13.97 -15.24 0)
				(effects
					(font
						(size 1.27 1.27)
						(thickness 0.15)
					)
					(justify left bottom)
					(hide yes)
				)
			)
			(property "ISat" "7.4 A"
				(at 13.97 -16.51 0)
				(effects
					(font
						(size 1.27 1.27)
					)
					(justify left)
					(hide yes)
				)
			)
			(property "IMax" "7.5 A"
				(at 13.97 -20.32 0)
				(effects
					(font
						(size 1.27 1.27)
						(thickness 0.15)
					)
					(justify left bottom)
					(hide yes)
				)
			)
			(property "Size" "4x4"
				(at 13.97 -22.86 0)
				(effects
					(font
						(size 1.27 1.27)
						(thickness 0.15)
					)
					(justify left bottom)
					(hide yes)
				)
			)
			(property "Author" "Antmicro"
				(at 13.97 -25.4 0)
				(effects
					(font
						(size 1.27 1.27)
						(thickness 0.15)
					)
					(justify left bottom)
					(hide yes)
				)
			)
			(property "License" "Apache-2.0"
				(at 13.97 -27.94 0)
				(effects
					(font
						(size 1.27 1.27)
						(thickness 0.15)
					)
					(justify left bottom)
					(hide yes)
				)
			)
			(property "ki_keywords" "SMT, INDUCTOR, PASSIVE"
				(at 0 0 0)
				(effects
					(font
						(size 1.27 1.27)
					)
					(hide yes)
				)
			)
			(symbol "L_1u5_7.5A_Coilcraft-XEL4020_0_1"
				(arc
					(start 0.508 0)
					(mid 1.016 0.5058)
					(end 1.524 0)
					(stroke
						(width 0)
						(type default)
					)
					(fill
						(type none)
					)
				)
				(arc
					(start 1.524 0)
					(mid 2.032 0.5058)
					(end 2.54 0)
					(stroke
						(width 0)
						(type default)
					)
					(fill
						(type none)
					)
				)
				(arc
					(start 2.54 0)
					(mid 3.048 0.5058)
					(end 3.556 0)
					(stroke
						(width 0)
						(type default)
					)
					(fill
						(type none)
					)
				)
				(arc
					(start 3.556 0)
					(mid 4.064 0.5058)
					(end 4.572 0)
					(stroke
						(width 0)
						(type default)
					)
					(fill
						(type none)
					)
				)
			)
			(symbol "L_1u5_7.5A_Coilcraft-XEL4020_1_1"
				(pin passive line
					(at 0 0 0)
					(length 0.508)
					(name "~"
						(effects
							(font
								(size 1.27 1.27)
							)
						)
					)
					(number "1"
						(effects
							(font
								(size 1.27 1.27)
							)
						)
					)
				)
				(pin passive line
					(at 5.08 0 180)
					(length 0.508)
					(name "~"
						(effects
							(font
								(size 1.27 1.27)
							)
						)
					)
					(number "2"
						(effects
							(font
								(size 1.27 1.27)
							)
						)
					)
				)
			)
		)
	(symbol "antmicroFixedInductors:L_1u_3.2A_0805"
			(pin_numbers
				(hide yes)
			)
			(pin_names
				(hide yes)
			)
			(exclude_from_sim no)
			(in_bom yes)
			(on_board yes)
			(property "Reference" "L"
				(at 13.97 0 0)
				(effects
					(font
						(size 1.27 1.27)
						(thickness 0.15)
					)
					(justify left bottom)
				)
			)
			(property "Value" "L_1u_3.2A_0805"
				(at 13.97 -2.54 0)
				(effects
					(font
						(size 1.27 1.27)
						(thickness 0.15)
					)
					(justify left bottom)
					(hide yes)
				)
			)
			(property "Footprint" "antmicro-footprints:L_0805_2012Metric"
				(at 13.97 -7.62 0)
				(effects
					(font
						(size 1.27 1.27)
						(thickness 0.15)
					)
					(justify left bottom)
					(hide yes)
				)
			)
			(property "Datasheet" "https://abracon.com/datasheets/AOTA-B201208S.pdf"
				(at 13.97 -10.16 0)
				(effects
					(font
						(size 1.27 1.27)
						(thickness 0.15)
					)
					(justify left bottom)
					(hide yes)
				)
			)
			(property "Description" "Power Inductor (SMT), 1 µH, 0.05 ohm, 3.2 A, AOTA-B201208S"
				(at 0 0 0)
				(effects
					(font
						(size 1.27 1.27)
					)
					(hide yes)
				)
			)
			(property "Val" "1u/3.2A"
				(at 13.97 -5.08 0)
				(effects
					(font
						(size 1.27 1.27)
						(thickness 0.15)
					)
					(justify left bottom)
				)
			)
			(property "Manufacturer" "Abracon"
				(at 13.97 -12.7 0)
				(effects
					(font
						(size 1.27 1.27)
						(thickness 0.15)
					)
					(justify left bottom)
					(hide yes)
				)
			)
			(property "MPN" "AOTA-B201208S1R0MT "
				(at 13.97 -15.24 0)
				(effects
					(font
						(size 1.27 1.27)
						(thickness 0.15)
					)
					(justify left bottom)
					(hide yes)
				)
			)
			(property "ISat" "3.5 A"
				(at 13.97 -16.51 0)
				(effects
					(font
						(size 1.27 1.27)
					)
					(justify left)
					(hide yes)
				)
			)
			(property "IMax" "3.2 A"
				(at 13.97 -20.32 0)
				(effects
					(font
						(size 1.27 1.27)
						(thickness 0.15)
					)
					(justify left bottom)
					(hide yes)
				)
			)
			(property "Size" "2x1.2"
				(at 13.97 -22.86 0)
				(effects
					(font
						(size 1.27 1.27)
						(thickness 0.15)
					)
					(justify left bottom)
					(hide yes)
				)
			)
			(property "Author" "Antmicro"
				(at 13.97 -25.4 0)
				(effects
					(font
						(size 1.27 1.27)
						(thickness 0.15)
					)
					(justify left bottom)
					(hide yes)
				)
			)
			(property "License" "Apache-2.0"
				(at 13.97 -27.94 0)
				(effects
					(font
						(size 1.27 1.27)
						(thickness 0.15)
					)
					(justify left bottom)
					(hide yes)
				)
			)
			(property "ki_keywords" "INDUCTOR, PASSIVE"
				(at 0 0 0)
				(effects
					(font
						(size 1.27 1.27)
					)
					(hide yes)
				)
			)
			(symbol "L_1u_3.2A_0805_0_1"
				(arc
					(start 0.508 0)
					(mid 1.016 0.5058)
					(end 1.524 0)
					(stroke
						(width 0)
						(type default)
					)
					(fill
						(type none)
					)
				)
				(arc
					(start 1.524 0)
					(mid 2.032 0.5058)
					(end 2.54 0)
					(stroke
						(width 0)
						(type default)
					)
					(fill
						(type none)
					)
				)
				(arc
					(start 2.54 0)
					(mid 3.048 0.5058)
					(end 3.556 0)
					(stroke
						(width 0)
						(type default)
					)
					(fill
						(type none)
					)
				)
				(arc
					(start 3.556 0)
					(mid 4.064 0.5058)
					(end 4.572 0)
					(stroke
						(width 0)
						(type default)
					)
					(fill
						(type none)
					)
				)
			)
			(symbol "L_1u_3.2A_0805_1_1"
				(pin passive line
					(at 0 0 0)
					(length 0.508)
					(name "~"
						(effects
							(font
								(size 1.27 1.27)
							)
						)
					)
					(number "1"
						(effects
							(font
								(size 1.27 1.27)
							)
						)
					)
				)
				(pin passive line
					(at 5.08 0 180)
					(length 0.508)
					(name "~"
						(effects
							(font
								(size 1.27 1.27)
							)
						)
					)
					(number "2"
						(effects
							(font
								(size 1.27 1.27)
							)
						)
					)
				)
			)
		)
	(symbol "antmicroFixedInductors:L_2u2_1.2A_0603"
			(pin_numbers
				(hide yes)
			)
			(pin_names
				(hide yes)
			)
			(exclude_from_sim no)
			(in_bom yes)
			(on_board yes)
			(property "Reference" "L"
				(at 13.97 0 0)
				(effects
					(font
						(size 1.27 1.27)
						(thickness 0.15)
					)
					(justify left bottom)
				)
			)
			(property "Value" "L_2u2_1.2A_0603"
				(at 13.97 -2.54 0)
				(effects
					(font
						(size 1.27 1.27)
						(thickness 0.15)
					)
					(justify left bottom)
					(hide yes)
				)
			)
			(property "Footprint" "antmicro-footprints:L_0603_1608Metric"
				(at 13.97 -7.62 0)
				(effects
					(font
						(size 1.27 1.27)
						(thickness 0.15)
					)
					(justify left bottom)
					(hide yes)
				)
			)
			(property "Datasheet" "https://www.mouser.com/datasheet/2/3/AOTA_B160808S-3224144.pdf"
				(at 13.97 -10.16 0)
				(effects
					(font
						(size 1.27 1.27)
						(thickness 0.15)
					)
					(justify left bottom)
					(hide yes)
				)
			)
			(property "Description" "Wirewound Inductor, 2.2 µH, 240 mOhm, 40 MHz, 1.2 A, 0603 [1608 Metric]"
				(at 0 0 0)
				(effects
					(font
						(size 1.27 1.27)
					)
					(hide yes)
				)
			)
			(property "Val" "2u2/1.2A"
				(at 13.97 -5.08 0)
				(effects
					(font
						(size 1.27 1.27)
						(thickness 0.15)
					)
					(justify left bottom)
				)
			)
			(property "Manufacturer" "Abracon"
				(at 13.97 -12.7 0)
				(effects
					(font
						(size 1.27 1.27)
						(thickness 0.15)
					)
					(justify left bottom)
					(hide yes)
				)
			)
			(property "MPN" "AOTA-B160808S2R2MT "
				(at 13.97 -15.24 0)
				(effects
					(font
						(size 1.27 1.27)
						(thickness 0.15)
					)
					(justify left bottom)
					(hide yes)
				)
			)
			(property "ISat" "1.3 A"
				(at 13.97 -16.51 0)
				(effects
					(font
						(size 1.27 1.27)
					)
					(justify left)
					(hide yes)
				)
			)
			(property "IMax" "1.2 A"
				(at 13.97 -20.32 0)
				(effects
					(font
						(size 1.27 1.27)
						(thickness 0.15)
					)
					(justify left bottom)
					(hide yes)
				)
			)
			(property "Size" "1.6 x 0.8 x 0.8"
				(at 13.97 -22.86 0)
				(effects
					(font
						(size 1.27 1.27)
						(thickness 0.15)
					)
					(justify left bottom)
					(hide yes)
				)
			)
			(property "Author" "Antmicro"
				(at 13.97 -25.4 0)
				(effects
					(font
						(size 1.27 1.27)
						(thickness 0.15)
					)
					(justify left bottom)
					(hide yes)
				)
			)
			(property "License" "Apache-2.0"
				(at 13.97 -27.94 0)
				(effects
					(font
						(size 1.27 1.27)
						(thickness 0.15)
					)
					(justify left bottom)
					(hide yes)
				)
			)
			(property "ki_keywords" "SMT, INDUCTOR, PASSIVE"
				(at 0 0 0)
				(effects
					(font
						(size 1.27 1.27)
					)
					(hide yes)
				)
			)
			(symbol "L_2u2_1.2A_0603_0_1"
				(arc
					(start 0.508 0)
					(mid 1.016 0.5058)
					(end 1.524 0)
					(stroke
						(width 0)
						(type default)
					)
					(fill
						(type none)
					)
				)
				(arc
					(start 1.524 0)
					(mid 2.032 0.5058)
					(end 2.54 0)
					(stroke
						(width 0)
						(type default)
					)
					(fill
						(type none)
					)
				)
				(arc
					(start 2.54 0)
					(mid 3.048 0.5058)
					(end 3.556 0)
					(stroke
						(width 0)
						(type default)
					)
					(fill
						(type none)
					)
				)
				(arc
					(start 3.556 0)
					(mid 4.064 0.5058)
					(end 4.572 0)
					(stroke
						(width 0)
						(type default)
					)
					(fill
						(type none)
					)
				)
			)
			(symbol "L_2u2_1.2A_0603_1_1"
				(pin passive line
					(at 0 0 0)
					(length 0.508)
					(name "~"
						(effects
							(font
								(size 1.27 1.27)
							)
						)
					)
					(number "1"
						(effects
							(font
								(size 1.27 1.27)
							)
						)
					)
				)
				(pin passive line
					(at 5.08 0 180)
					(length 0.508)
					(name "~"
						(effects
							(font
								(size 1.27 1.27)
							)
						)
					)
					(number "2"
						(effects
							(font
								(size 1.27 1.27)
							)
						)
					)
				)
			)
		)
	(symbol "antmicroGenericPinHeaders:PinHeader_2x5_P1.27mm_SMD"
			(exclude_from_sim no)
			(in_bom yes)
			(on_board yes)
			(property "Reference" "J"
				(at 25.4 -5.08 0)
				(effects
					(font
						(size 1.27 1.27)
						(thickness 0.15)
					)
					(justify left bottom)
				)
			)
			(property "Value" "PinHeader_2x5_P1.27mm_SMD"
				(at 25.4 -7.62 0)
				(effects
					(font
						(size 1.27 1.27)
						(thickness 0.15)
					)
					(justify left bottom)
				)
			)
			(property "Footprint" "antmicro-footprints:PinHeader_2x5_P1.27mm_SMD"
				(at 25.4 -10.16 0)
				(effects
					(font
						(size 1.27 1.27)
						(thickness 0.15)
					)
					(justify left bottom)
					(hide yes)
				)
			)
			(property "Datasheet" "https://eu.mouser.com/datasheet/2/527/ftsh_th-2854322.pdf"
				(at 25.4 -12.7 0)
				(effects
					(font
						(size 1.27 1.27)
						(thickness 0.15)
					)
					(justify left bottom)
					(hide yes)
				)
			)
			(property "Description" "Pin Header, Board-to-Board, Wire-to-Board, 1.27 mm, 2 Rows, 10 Contacts, Surface Mount, FTSH"
				(at 0 0 0)
				(effects
					(font
						(size 1.27 1.27)
					)
					(hide yes)
				)
			)
			(property "MPN" "FTSH-105-01-F-DV"
				(at 25.4 -15.24 0)
				(effects
					(font
						(size 1.27 1.27)
						(thickness 0.15)
					)
					(justify left bottom)
					(hide yes)
				)
			)
			(property "Manufacturer" "Samtec"
				(at 25.4 -17.78 0)
				(effects
					(font
						(size 1.27 1.27)
						(thickness 0.15)
					)
					(justify left bottom)
					(hide yes)
				)
			)
			(property "Author" "Antmicro"
				(at 25.4 -20.32 0)
				(effects
					(font
						(size 1.27 1.27)
						(thickness 0.15)
					)
					(justify left bottom)
					(hide yes)
				)
			)
			(property "License" "Apache-2.0"
				(at 25.4 -22.86 0)
				(effects
					(font
						(size 1.27 1.27)
						(thickness 0.15)
					)
					(justify left bottom)
					(hide yes)
				)
			)
			(property "ki_keywords" "PINSTRIP, HEADER "
				(at 0 0 0)
				(effects
					(font
						(size 1.27 1.27)
					)
					(hide yes)
				)
			)
			(symbol "PinHeader_2x5_P1.27mm_SMD_1_1"
				(rectangle
					(start 2.54 1.27)
					(end 7.62 -11.43)
					(stroke
						(width 0.254)
						(type default)
					)
					(fill
						(type background)
					)
				)
				(rectangle
					(start 3.556 0.254)
					(end 4.064 -0.254)
					(stroke
						(width 0.254)
						(type default)
					)
					(fill
						(type outline)
					)
				)
				(rectangle
					(start 3.556 -2.286)
					(end 4.064 -2.794)
					(stroke
						(width 0.254)
						(type default)
					)
					(fill
						(type outline)
					)
				)
				(rectangle
					(start 3.556 -4.826)
					(end 4.064 -5.334)
					(stroke
						(width 0.254)
						(type default)
					)
					(fill
						(type outline)
					)
				)
				(rectangle
					(start 3.556 -7.366)
					(end 4.064 -7.874)
					(stroke
						(width 0.254)
						(type default)
					)
					(fill
						(type outline)
					)
				)
				(rectangle
					(start 3.556 -9.906)
					(end 4.064 -10.414)
					(stroke
						(width 0.254)
						(type default)
					)
					(fill
						(type outline)
					)
				)
				(rectangle
					(start 6.096 0.254)
					(end 6.604 -0.254)
					(stroke
						(width 0.254)
						(type default)
					)
					(fill
						(type outline)
					)
				)
				(rectangle
					(start 6.096 -2.286)
					(end 6.604 -2.794)
					(stroke
						(width 0.254)
						(type default)
					)
					(fill
						(type outline)
					)
				)
				(rectangle
					(start 6.096 -4.826)
					(end 6.604 -5.334)
					(stroke
						(width 0.254)
						(type default)
					)
					(fill
						(type outline)
					)
				)
				(rectangle
					(start 6.096 -7.366)
					(end 6.604 -7.874)
					(stroke
						(width 0.254)
						(type default)
					)
					(fill
						(type outline)
					)
				)
				(rectangle
					(start 6.096 -9.906)
					(end 6.604 -10.414)
					(stroke
						(width 0.254)
						(type default)
					)
					(fill
						(type outline)
					)
				)
				(pin passive line
					(at 0 0 0)
					(length 2.54)
					(name "~"
						(effects
							(font
								(size 1.27 1.27)
							)
						)
					)
					(number "1"
						(effects
							(font
								(size 1.27 1.27)
							)
						)
					)
				)
				(pin passive line
					(at 0 -2.54 0)
					(length 2.54)
					(name "~"
						(effects
							(font
								(size 1.27 1.27)
							)
						)
					)
					(number "3"
						(effects
							(font
								(size 1.27 1.27)
							)
						)
					)
				)
				(pin passive line
					(at 0 -5.08 0)
					(length 2.54)
					(name "~"
						(effects
							(font
								(size 1.27 1.27)
							)
						)
					)
					(number "5"
						(effects
							(font
								(size 1.27 1.27)
							)
						)
					)
				)
				(pin passive line
					(at 0 -7.62 0)
					(length 2.54)
					(name "~"
						(effects
							(font
								(size 1.27 1.27)
							)
						)
					)
					(number "7"
						(effects
							(font
								(size 1.27 1.27)
							)
						)
					)
				)
				(pin passive line
					(at 0 -10.16 0)
					(length 2.54)
					(name "~"
						(effects
							(font
								(size 1.27 1.27)
							)
						)
					)
					(number "9"
						(effects
							(font
								(size 1.27 1.27)
							)
						)
					)
				)
				(pin passive line
					(at 10.16 0 180)
					(length 2.54)
					(name "~"
						(effects
							(font
								(size 1.27 1.27)
							)
						)
					)
					(number "2"
						(effects
							(font
								(size 1.27 1.27)
							)
						)
					)
				)
				(pin passive line
					(at 10.16 -2.54 180)
					(length 2.54)
					(name "~"
						(effects
							(font
								(size 1.27 1.27)
							)
						)
					)
					(number "4"
						(effects
							(font
								(size 1.27 1.27)
							)
						)
					)
				)
				(pin passive line
					(at 10.16 -5.08 180)
					(length 2.54)
					(name "~"
						(effects
							(font
								(size 1.27 1.27)
							)
						)
					)
					(number "6"
						(effects
							(font
								(size 1.27 1.27)
							)
						)
					)
				)
				(pin passive line
					(at 10.16 -7.62 180)
					(length 2.54)
					(name "~"
						(effects
							(font
								(size 1.27 1.27)
							)
						)
					)
					(number "8"
						(effects
							(font
								(size 1.27 1.27)
							)
						)
					)
				)
				(pin passive line
					(at 10.16 -10.16 180)
					(length 2.54)
					(name "~"
						(effects
							(font
								(size 1.27 1.27)
							)
						)
					)
					(number "10"
						(effects
							(font
								(size 1.27 1.27)
							)
						)
					)
				)
			)
		)
	(symbol "antmicroInterfaceAnalogSwitchesSpecialPurpose:PI3USB102GZLEX"
			(exclude_from_sim no)
			(in_bom yes)
			(on_board yes)
			(property "Reference" "U"
				(at 35.56 -5.08 0)
				(effects
					(font
						(size 1.27 1.27)
						(thickness 0.15)
					)
					(justify left bottom)
				)
			)
			(property "Value" "PI3USB102GZLEX"
				(at 35.56 -7.62 0)
				(effects
					(font
						(size 1.27 1.27)
						(thickness 0.15)
					)
					(justify left bottom)
					(hide yes)
				)
			)
			(property "Footprint" "antmicro-footprints:UQFN-10_1.4x1.8x0.5mm_P0.4mm"
				(at 35.56 -10.16 0)
				(effects
					(font
						(size 1.27 1.27)
						(thickness 0.15)
					)
					(justify left bottom)
					(hide yes)
				)
			)
			(property "Datasheet" "https://www.diodes.com/assets/Datasheets/PI3USB102G.pdf"
				(at 35.56 -12.7 0)
				(effects
					(font
						(size 1.27 1.27)
						(thickness 0.15)
					)
					(justify left bottom)
					(hide yes)
				)
			)
			(property "Description" "USB Switch IC 1 Channel 10-TQFN (1.3x1.6)"
				(at 0 0 0)
				(effects
					(font
						(size 1.27 1.27)
					)
					(hide yes)
				)
			)
			(property "MPN" "PI3USB102GZLEX"
				(at 35.56 -15.24 0)
				(effects
					(font
						(size 1.27 1.27)
						(thickness 0.15)
					)
					(justify left bottom)
				)
			)
			(property "Manufacturer" "Diodes Incorporated"
				(at 35.56 -17.78 0)
				(effects
					(font
						(size 1.27 1.27)
						(thickness 0.15)
					)
					(justify left bottom)
					(hide yes)
				)
			)
			(property "Author" "Antmicro"
				(at 35.56 -20.32 0)
				(effects
					(font
						(size 1.27 1.27)
						(thickness 0.15)
					)
					(justify left bottom)
					(hide yes)
				)
			)
			(property "License" "Apache-2.0"
				(at 35.56 -22.86 0)
				(effects
					(font
						(size 1.27 1.27)
						(thickness 0.15)
					)
					(justify left bottom)
					(hide yes)
				)
			)
			(property "ki_keywords" "IC"
				(at 0 0 0)
				(effects
					(font
						(size 1.27 1.27)
					)
					(hide yes)
				)
			)
			(property "ki_fp_filters" "MSOP*3x3mm*P0.5mm*"
				(at 0 0 0)
				(effects
					(font
						(size 1.27 1.27)
					)
					(hide yes)
				)
			)
			(symbol "PI3USB102GZLEX_0_1"
				(polyline
					(pts
						(xy 2.54 -3.81) (xy 6.35 -3.81) (xy 6.35 -8.89) (xy 2.54 -8.89)
					)
					(stroke
						(width 0)
						(type default)
					)
					(fill
						(type none)
					)
				)
				(polyline
					(pts
						(xy 6.35 -6.35) (xy 7.62 -6.35) (xy 7.62 -2.54) (xy 8.89 -2.54) (xy 11.43 -1.27)
					)
					(stroke
						(width 0)
						(type default)
					)
					(fill
						(type none)
					)
				)
				(polyline
					(pts
						(xy 7.62 -6.35) (xy 7.62 -10.16) (xy 8.89 -10.16) (xy 11.43 -8.89)
					)
					(stroke
						(width 0)
						(type default)
					)
					(fill
						(type none)
					)
				)
				(polyline
					(pts
						(xy 12.7 -2.54) (xy 10.795 -2.54) (xy 10.795 -1.27)
					)
					(stroke
						(width 0)
						(type default)
					)
					(fill
						(type none)
					)
				)
				(polyline
					(pts
						(xy 12.7 -10.16) (xy 10.795 -10.16)
					)
					(stroke
						(width 0)
						(type default)
					)
					(fill
						(type none)
					)
				)
				(polyline
					(pts
						(xy 17.78 0) (xy 12.7 0) (xy 12.7 -5.08) (xy 17.78 -5.08)
					)
					(stroke
						(width 0)
						(type default)
					)
					(fill
						(type none)
					)
				)
				(polyline
					(pts
						(xy 17.78 -7.62) (xy 12.7 -7.62) (xy 12.7 -12.7) (xy 17.78 -12.7)
					)
					(stroke
						(width 0)
						(type default)
					)
					(fill
						(type none)
					)
				)
			)
			(symbol "PI3USB102GZLEX_1_1"
				(rectangle
					(start 2.54 1.27)
					(end 17.78 -16.51)
					(stroke
						(width 0.254)
						(type default)
					)
					(fill
						(type background)
					)
				)
				(polyline
					(pts
						(xy 9.906 -1.524) (xy 9.906 -10.414)
					)
					(stroke
						(width 0.125)
						(type dash)
					)
					(fill
						(type none)
					)
				)
				(pin power_in line
					(at 0 0 0)
					(length 2.54)
					(name "V_{DD}"
						(effects
							(font
								(size 1.27 1.27)
							)
						)
					)
					(number "9"
						(effects
							(font
								(size 1.27 1.27)
							)
						)
					)
				)
				(pin bidirectional line
					(at 0 -5.08 0)
					(length 2.54)
					(name "D+"
						(effects
							(font
								(size 1.27 1.27)
							)
						)
					)
					(number "1"
						(effects
							(font
								(size 1.27 1.27)
							)
						)
					)
				)
				(pin bidirectional line
					(at 0 -7.62 0)
					(length 2.54)
					(name "D-"
						(effects
							(font
								(size 1.27 1.27)
							)
						)
					)
					(number "2"
						(effects
							(font
								(size 1.27 1.27)
							)
						)
					)
				)
				(pin input line
					(at 0 -11.43 0)
					(length 2.54)
					(name "~{OE}"
						(effects
							(font
								(size 1.27 1.27)
							)
						)
					)
					(number "8"
						(effects
							(font
								(size 1.27 1.27)
							)
						)
					)
				)
				(pin input line
					(at 0 -13.97 0)
					(length 2.54)
					(name "SEL"
						(effects
							(font
								(size 1.27 1.27)
							)
						)
					)
					(number "10"
						(effects
							(font
								(size 1.27 1.27)
							)
						)
					)
				)
				(pin bidirectional line
					(at 20.32 -1.27 180)
					(length 2.54)
					(name "D1+"
						(effects
							(font
								(size 1.27 1.27)
							)
						)
					)
					(number "5"
						(effects
							(font
								(size 1.27 1.27)
							)
						)
					)
				)
				(pin bidirectional line
					(at 20.32 -3.81 180)
					(length 2.54)
					(name "D1-"
						(effects
							(font
								(size 1.27 1.27)
							)
						)
					)
					(number "4"
						(effects
							(font
								(size 1.27 1.27)
							)
						)
					)
				)
				(pin bidirectional line
					(at 20.32 -8.89 180)
					(length 2.54)
					(name "D2+"
						(effects
							(font
								(size 1.27 1.27)
							)
						)
					)
					(number "7"
						(effects
							(font
								(size 1.27 1.27)
							)
						)
					)
				)
				(pin bidirectional line
					(at 20.32 -11.43 180)
					(length 2.54)
					(name "D2-"
						(effects
							(font
								(size 1.27 1.27)
							)
						)
					)
					(number "6"
						(effects
							(font
								(size 1.27 1.27)
							)
						)
					)
				)
				(pin power_in line
					(at 20.32 -15.24 180)
					(length 2.54)
					(name "GND"
						(effects
							(font
								(size 1.27 1.27)
							)
						)
					)
					(number "3"
						(effects
							(font
								(size 1.27 1.27)
							)
						)
					)
				)
			)
		)
	(symbol "antmicroInterfaceControllers:DP83867ISRGZR"
			(exclude_from_sim no)
			(in_bom yes)
			(on_board yes)
			(property "Reference" "U"
				(at 64.77 -2.54 0)
				(effects
					(font
						(size 1.27 1.27)
						(thickness 0.15)
					)
					(justify left bottom)
				)
			)
			(property "Value" "DP83867ISRGZR"
				(at 64.77 -7.62 0)
				(effects
					(font
						(size 1.27 1.27)
						(thickness 0.15)
					)
					(justify left bottom)
					(hide yes)
				)
			)
			(property "Footprint" "antmicro-footprints:VQFN-48_7x7mm_P0.5mm_EP4.1x4.1mm"
				(at 64.77 -10.16 0)
				(effects
					(font
						(size 1.27 1.27)
						(thickness 0.15)
					)
					(justify left bottom)
					(hide yes)
				)
			)
			(property "Datasheet" "https://www.ti.com/lit/ds/symlink/dp83867is.pdf?HQS=dis-dk-null-digikeymode-dsf-pf-null-wwe&ts=1704962980288&ref_url=https%253A%252F%252Fwww.ti.com%252Fgeneral%252Fdocs%252Fsuppproductinfo.tsp%253FdistId%253D10%2526gotoUrl%253Dhttps%253A%252F%252Fwww.ti.com%252Flit%252Fgpn%252Fdp83867is"
				(at 64.77 -12.7 0)
				(effects
					(font
						(size 1.27 1.27)
						(thickness 0.15)
					)
					(justify left bottom)
					(hide yes)
				)
			)
			(property "Description" "Robust, High Immunity, Small Form Factor 10/100/1000 Ethernet, Physical Layer Transceiver, SGMII/RGMII"
				(at 0 0 0)
				(effects
					(font
						(size 1.27 1.27)
					)
					(hide yes)
				)
			)
			(property "MPN" "DP83867ISRGZR"
				(at 64.77 -5.08 0)
				(effects
					(font
						(size 1.27 1.27)
						(thickness 0.15)
					)
					(justify left bottom)
				)
			)
			(property "Manufacturer" "Texas Instruments"
				(at 64.77 -15.24 0)
				(effects
					(font
						(size 1.27 1.27)
					)
					(justify left bottom)
					(hide yes)
				)
			)
			(property "Author" "Antmicro"
				(at 64.77 -17.78 0)
				(effects
					(font
						(size 1.27 1.27)
						(thickness 0.15)
					)
					(justify left bottom)
					(hide yes)
				)
			)
			(property "License" "Apache-2.0"
				(at 64.77 -20.32 0)
				(effects
					(font
						(size 1.27 1.27)
						(thickness 0.15)
					)
					(justify left bottom)
					(hide yes)
				)
			)
			(property "ki_keywords" "SMT, ETHERNET, IC, TRANSCEIVER"
				(at 0 0 0)
				(effects
					(font
						(size 1.27 1.27)
					)
					(hide yes)
				)
			)
			(property "ki_fp_filters" "RGZ0048B RGZ0048B_NV"
				(at 0 0 0)
				(effects
					(font
						(size 1.27 1.27)
					)
					(hide yes)
				)
			)
			(symbol "DP83867ISRGZR_1_1"
				(rectangle
					(start 2.54 2.54)
					(end 31.75 -71.12)
					(stroke
						(width 0.254)
						(type default)
					)
					(fill
						(type background)
					)
				)
				(pin power_in line
					(at 0 0 0)
					(length 2.54)
					(name "VDDIO"
						(effects
							(font
								(size 1.27 1.27)
							)
						)
					)
					(number "19"
						(effects
							(font
								(size 1.27 1.27)
							)
						)
					)
				)
				(pin passive line
					(at 0 0 0)
					(length 2.54)
					(hide yes)
					(name "VDDIO"
						(effects
							(font
								(size 1.27 1.27)
							)
						)
					)
					(number "30"
						(effects
							(font
								(size 1.27 1.27)
							)
						)
					)
				)
				(pin passive line
					(at 0 0 0)
					(length 2.54)
					(hide yes)
					(name "VDDIO"
						(effects
							(font
								(size 1.27 1.27)
							)
						)
					)
					(number "41"
						(effects
							(font
								(size 1.27 1.27)
							)
						)
					)
				)
				(pin power_in line
					(at 0 -3.81 0)
					(length 2.54)
					(name "VDDA2P5"
						(effects
							(font
								(size 1.27 1.27)
							)
						)
					)
					(number "3"
						(effects
							(font
								(size 1.27 1.27)
							)
						)
					)
				)
				(pin passive line
					(at 0 -3.81 0)
					(length 2.54)
					(hide yes)
					(name "VDDA2P5"
						(effects
							(font
								(size 1.27 1.27)
							)
						)
					)
					(number "9"
						(effects
							(font
								(size 1.27 1.27)
							)
						)
					)
				)
				(pin power_in line
					(at 0 -6.35 0)
					(length 2.54)
					(name "VDDA1P8"
						(effects
							(font
								(size 1.27 1.27)
							)
						)
					)
					(number "13"
						(effects
							(font
								(size 1.27 1.27)
							)
						)
					)
				)
				(pin passive line
					(at 0 -6.35 0)
					(length 2.54)
					(hide yes)
					(name "VDDA1P8"
						(effects
							(font
								(size 1.27 1.27)
							)
						)
					)
					(number "48"
						(effects
							(font
								(size 1.27 1.27)
							)
						)
					)
				)
				(pin power_in line
					(at 0 -8.89 0)
					(length 2.54)
					(name "VDD1P0"
						(effects
							(font
								(size 1.27 1.27)
							)
						)
					)
					(number "24"
						(effects
							(font
								(size 1.27 1.27)
							)
						)
					)
				)
				(pin passive line
					(at 0 -8.89 0)
					(length 2.54)
					(hide yes)
					(name "VDD1P0"
						(effects
							(font
								(size 1.27 1.27)
							)
						)
					)
					(number "31"
						(effects
							(font
								(size 1.27 1.27)
							)
						)
					)
				)
				(pin passive line
					(at 0 -8.89 0)
					(length 2.54)
					(hide yes)
					(name "VDD1P0"
						(effects
							(font
								(size 1.27 1.27)
							)
						)
					)
					(number "42"
						(effects
							(font
								(size 1.27 1.27)
							)
						)
					)
				)
				(pin passive line
					(at 0 -8.89 0)
					(length 2.54)
					(hide yes)
					(name "VDD1P0"
						(effects
							(font
								(size 1.27 1.27)
							)
						)
					)
					(number "6"
						(effects
							(font
								(size 1.27 1.27)
							)
						)
					)
				)
				(pin input line
					(at 0 -12.7 0)
					(length 2.54)
					(name "GTX_CLK"
						(effects
							(font
								(size 1.27 1.27)
							)
						)
					)
					(number "29"
						(effects
							(font
								(size 1.27 1.27)
							)
						)
					)
				)
				(pin input line
					(at 0 -15.24 0)
					(length 2.54)
					(name "TX_CTRL"
						(effects
							(font
								(size 1.27 1.27)
							)
						)
					)
					(number "37"
						(effects
							(font
								(size 1.27 1.27)
							)
						)
					)
				)
				(pin input line
					(at 0 -19.05 0)
					(length 2.54)
					(name "TX_D0/SGMII_SIN"
						(effects
							(font
								(size 1.27 1.27)
							)
						)
					)
					(number "28"
						(effects
							(font
								(size 1.27 1.27)
							)
						)
					)
				)
				(pin input line
					(at 0 -21.59 0)
					(length 2.54)
					(name "TX_D1/SGMII_SIP"
						(effects
							(font
								(size 1.27 1.27)
							)
						)
					)
					(number "27"
						(effects
							(font
								(size 1.27 1.27)
							)
						)
					)
				)
				(pin input line
					(at 0 -24.13 0)
					(length 2.54)
					(name "TX_D2"
						(effects
							(font
								(size 1.27 1.27)
							)
						)
					)
					(number "26"
						(effects
							(font
								(size 1.27 1.27)
							)
						)
					)
				)
				(pin input line
					(at 0 -26.67 0)
					(length 2.54)
					(name "TX_D3"
						(effects
							(font
								(size 1.27 1.27)
							)
						)
					)
					(number "25"
						(effects
							(font
								(size 1.27 1.27)
							)
						)
					)
				)
				(pin output line
					(at 0 -30.48 0)
					(length 2.54)
					(name "RX_CTRL"
						(effects
							(font
								(size 1.27 1.27)
							)
						)
					)
					(number "38"
						(effects
							(font
								(size 1.27 1.27)
							)
						)
					)
				)
				(pin output line
					(at 0 -33.02 0)
					(length 2.54)
					(name "RX_CLK"
						(effects
							(font
								(size 1.27 1.27)
							)
						)
					)
					(number "32"
						(effects
							(font
								(size 1.27 1.27)
							)
						)
					)
				)
				(pin output line
					(at 0 -36.83 0)
					(length 2.54)
					(name "RX_D0/SGMII_COP"
						(effects
							(font
								(size 1.27 1.27)
							)
						)
					)
					(number "33"
						(effects
							(font
								(size 1.27 1.27)
							)
						)
					)
				)
				(pin output line
					(at 0 -39.37 0)
					(length 2.54)
					(name "RX_D1/SGMII_CON"
						(effects
							(font
								(size 1.27 1.27)
							)
						)
					)
					(number "34"
						(effects
							(font
								(size 1.27 1.27)
							)
						)
					)
				)
				(pin output line
					(at 0 -41.91 0)
					(length 2.54)
					(name "RX_D2/SGMII_SOP"
						(effects
							(font
								(size 1.27 1.27)
							)
						)
					)
					(number "35"
						(effects
							(font
								(size 1.27 1.27)
							)
						)
					)
				)
				(pin output line
					(at 0 -44.45 0)
					(length 2.54)
					(name "RX_D3/SGMII_SON"
						(effects
							(font
								(size 1.27 1.27)
							)
						)
					)
					(number "36"
						(effects
							(font
								(size 1.27 1.27)
							)
						)
					)
				)
				(pin output line
					(at 0 -48.26 0)
					(length 2.54)
					(name "GPIO_0"
						(effects
							(font
								(size 1.27 1.27)
							)
						)
					)
					(number "39"
						(effects
							(font
								(size 1.27 1.27)
							)
						)
					)
				)
				(pin output line
					(at 0 -50.8 0)
					(length 2.54)
					(name "GPIO_1"
						(effects
							(font
								(size 1.27 1.27)
							)
						)
					)
					(number "40"
						(effects
							(font
								(size 1.27 1.27)
							)
						)
					)
				)
				(pin bidirectional line
					(at 0 -54.61 0)
					(length 2.54)
					(name "~{INT}/~{PWDN}"
						(effects
							(font
								(size 1.27 1.27)
							)
						)
					)
					(number "44"
						(effects
							(font
								(size 1.27 1.27)
							)
						)
					)
				)
				(pin input line
					(at 0 -58.42 0)
					(length 2.54)
					(name "~{RESET}"
						(effects
							(font
								(size 1.27 1.27)
							)
						)
					)
					(number "43"
						(effects
							(font
								(size 1.27 1.27)
							)
						)
					)
				)
				(pin input line
					(at 0 -62.23 0)
					(length 2.54)
					(name "X_I"
						(effects
							(font
								(size 1.27 1.27)
							)
						)
					)
					(number "15"
						(effects
							(font
								(size 1.27 1.27)
							)
						)
					)
				)
				(pin output line
					(at 0 -64.77 0)
					(length 2.54)
					(name "X_O"
						(effects
							(font
								(size 1.27 1.27)
							)
						)
					)
					(number "14"
						(effects
							(font
								(size 1.27 1.27)
							)
						)
					)
				)
				(pin output line
					(at 0 -68.58 0)
					(length 2.54)
					(name "CLK_OUT"
						(effects
							(font
								(size 1.27 1.27)
							)
						)
					)
					(number "18"
						(effects
							(font
								(size 1.27 1.27)
							)
						)
					)
				)
				(pin bidirectional line
					(at 34.29 0 180)
					(length 2.54)
					(name "TD_P_A"
						(effects
							(font
								(size 1.27 1.27)
							)
						)
					)
					(number "1"
						(effects
							(font
								(size 1.27 1.27)
							)
						)
					)
				)
				(pin bidirectional line
					(at 34.29 -2.54 180)
					(length 2.54)
					(name "TD_M_A"
						(effects
							(font
								(size 1.27 1.27)
							)
						)
					)
					(number "2"
						(effects
							(font
								(size 1.27 1.27)
							)
						)
					)
				)
				(pin bidirectional line
					(at 34.29 -6.35 180)
					(length 2.54)
					(name "TD_P_B"
						(effects
							(font
								(size 1.27 1.27)
							)
						)
					)
					(number "4"
						(effects
							(font
								(size 1.27 1.27)
							)
						)
					)
				)
				(pin bidirectional line
					(at 34.29 -8.89 180)
					(length 2.54)
					(name "TD_M_B"
						(effects
							(font
								(size 1.27 1.27)
							)
						)
					)
					(number "5"
						(effects
							(font
								(size 1.27 1.27)
							)
						)
					)
				)
				(pin bidirectional line
					(at 34.29 -12.7 180)
					(length 2.54)
					(name "TD_P_C"
						(effects
							(font
								(size 1.27 1.27)
							)
						)
					)
					(number "7"
						(effects
							(font
								(size 1.27 1.27)
							)
						)
					)
				)
				(pin bidirectional line
					(at 34.29 -15.24 180)
					(length 2.54)
					(name "TD_M_C"
						(effects
							(font
								(size 1.27 1.27)
							)
						)
					)
					(number "8"
						(effects
							(font
								(size 1.27 1.27)
							)
						)
					)
				)
				(pin bidirectional line
					(at 34.29 -19.05 180)
					(length 2.54)
					(name "TD_P_D"
						(effects
							(font
								(size 1.27 1.27)
							)
						)
					)
					(number "10"
						(effects
							(font
								(size 1.27 1.27)
							)
						)
					)
				)
				(pin bidirectional line
					(at 34.29 -21.59 180)
					(length 2.54)
					(name "TD_M_D"
						(effects
							(font
								(size 1.27 1.27)
							)
						)
					)
					(number "11"
						(effects
							(font
								(size 1.27 1.27)
							)
						)
					)
				)
				(pin passive line
					(at 34.29 -26.67 180)
					(length 2.54)
					(name "RBIAS"
						(effects
							(font
								(size 1.27 1.27)
							)
						)
					)
					(number "12"
						(effects
							(font
								(size 1.27 1.27)
							)
						)
					)
				)
				(pin input line
					(at 34.29 -31.75 180)
					(length 2.54)
					(name "JTAG_TDI"
						(effects
							(font
								(size 1.27 1.27)
							)
						)
					)
					(number "23"
						(effects
							(font
								(size 1.27 1.27)
							)
						)
					)
				)
				(pin output line
					(at 34.29 -34.29 180)
					(length 2.54)
					(name "JTAG_TDO"
						(effects
							(font
								(size 1.27 1.27)
							)
						)
					)
					(number "21"
						(effects
							(font
								(size 1.27 1.27)
							)
						)
					)
				)
				(pin input line
					(at 34.29 -36.83 180)
					(length 2.54)
					(name "JTAG_CLK"
						(effects
							(font
								(size 1.27 1.27)
							)
						)
					)
					(number "20"
						(effects
							(font
								(size 1.27 1.27)
							)
						)
					)
				)
				(pin input line
					(at 34.29 -39.37 180)
					(length 2.54)
					(name "JTAG_TMS"
						(effects
							(font
								(size 1.27 1.27)
							)
						)
					)
					(number "22"
						(effects
							(font
								(size 1.27 1.27)
							)
						)
					)
				)
				(pin bidirectional line
					(at 34.29 -44.45 180)
					(length 2.54)
					(name "LED_0"
						(effects
							(font
								(size 1.27 1.27)
							)
						)
					)
					(number "47"
						(effects
							(font
								(size 1.27 1.27)
							)
						)
					)
				)
				(pin bidirectional line
					(at 34.29 -46.99 180)
					(length 2.54)
					(name "LED_1"
						(effects
							(font
								(size 1.27 1.27)
							)
						)
					)
					(number "46"
						(effects
							(font
								(size 1.27 1.27)
							)
						)
					)
				)
				(pin bidirectional line
					(at 34.29 -49.53 180)
					(length 2.54)
					(name "LED_2"
						(effects
							(font
								(size 1.27 1.27)
							)
						)
					)
					(number "45"
						(effects
							(font
								(size 1.27 1.27)
							)
						)
					)
				)
				(pin input line
					(at 34.29 -54.61 180)
					(length 2.54)
					(name "MDC"
						(effects
							(font
								(size 1.27 1.27)
							)
						)
					)
					(number "16"
						(effects
							(font
								(size 1.27 1.27)
							)
						)
					)
				)
				(pin bidirectional line
					(at 34.29 -57.15 180)
					(length 2.54)
					(name "MDIO"
						(effects
							(font
								(size 1.27 1.27)
							)
						)
					)
					(number "17"
						(effects
							(font
								(size 1.27 1.27)
							)
						)
					)
				)
				(pin power_in line
					(at 34.29 -68.58 180)
					(length 2.54)
					(name "GND"
						(effects
							(font
								(size 1.27 1.27)
							)
						)
					)
					(number "49"
						(effects
							(font
								(size 1.27 1.27)
							)
						)
					)
				)
			)
		)
	(symbol "antmicroInterfaceControllers:USB2422-I_MJ"
			(exclude_from_sim no)
			(in_bom yes)
			(on_board yes)
			(property "Reference" "U"
				(at 48.26 -2.54 0)
				(effects
					(font
						(size 1.27 1.27)
						(thickness 0.15)
					)
					(justify left bottom)
				)
			)
			(property "Value" "USB2422-I_MJ"
				(at 48.26 -5.08 0)
				(effects
					(font
						(size 1.27 1.27)
						(thickness 0.15)
					)
					(justify left bottom)
					(hide yes)
				)
			)
			(property "Footprint" "antmicro-footprints:QFN-24-1EP_4x4mm_P0.5mm_EP2.6x2.6mm"
				(at 48.26 -7.62 0)
				(effects
					(font
						(size 1.27 1.27)
						(thickness 0.15)
					)
					(justify left bottom)
					(hide yes)
				)
			)
			(property "Datasheet" "https://ww1.microchip.com/downloads/aemDocuments/documents/OTH/ProductDocuments/DataSheets/00001726B.pdf"
				(at 48.26 -10.16 0)
				(effects
					(font
						(size 1.27 1.27)
						(thickness 0.15)
					)
					(justify left bottom)
					(hide yes)
				)
			)
			(property "Description" "USB Interface, USB Hub Controller, USB 2.0, 3 V, 3.6 V, SQFN, 24 Pins"
				(at 0 0 0)
				(effects
					(font
						(size 1.27 1.27)
					)
					(hide yes)
				)
			)
			(property "Author" "Antmicro"
				(at 48.26 -12.7 0)
				(effects
					(font
						(size 1.27 1.27)
						(thickness 0.15)
					)
					(justify left bottom)
					(hide yes)
				)
			)
			(property "License" "Apache-2.0"
				(at 48.26 -15.24 0)
				(effects
					(font
						(size 1.27 1.27)
						(thickness 0.15)
					)
					(justify left bottom)
					(hide yes)
				)
			)
			(property "MPN" "USB2422-I/MJ"
				(at 48.26 -17.78 0)
				(effects
					(font
						(size 1.27 1.27)
						(thickness 0.15)
					)
					(justify left bottom)
				)
			)
			(property "Manufacturer" "Microchip Technology"
				(at 48.26 -20.32 0)
				(effects
					(font
						(size 1.27 1.27)
						(thickness 0.15)
					)
					(justify left bottom)
					(hide yes)
				)
			)
			(property "ki_keywords" "SMT, TRANSCEIVER, IC, HUB, CONTROLLER, USB"
				(at 0 0 0)
				(effects
					(font
						(size 1.27 1.27)
					)
					(hide yes)
				)
			)
			(symbol "USB2422-I_MJ_1_1"
				(rectangle
					(start 2.54 2.54)
					(end 30.48 -38.1)
					(stroke
						(width 0.254)
						(type default)
					)
					(fill
						(type background)
					)
				)
				(polyline
					(pts
						(xy 17.78 -12.7) (xy 17.78 -26.67) (xy 30.48 -26.67)
					)
					(stroke
						(width 0.254)
						(type default)
					)
					(fill
						(type background)
					)
				)
				(polyline
					(pts
						(xy 30.48 -12.7) (xy 17.78 -12.7) (xy 17.78 2.54)
					)
					(stroke
						(width 0.254)
						(type default)
					)
					(fill
						(type background)
					)
				)
				(text "PORT 1"
					(at 18.415 -12.065 0)
					(effects
						(font
							(size 1.27 1.27)
							(thickness 0.15)
						)
						(justify left bottom)
					)
				)
				(text "PORT 2"
					(at 18.415 -26.035 0)
					(effects
						(font
							(size 1.27 1.27)
							(thickness 0.15)
						)
						(justify left bottom)
					)
				)
				(pin power_in line
					(at 0 0 0)
					(length 2.54)
					(name "3V3"
						(effects
							(font
								(size 1.27 1.27)
							)
						)
					)
					(number "1"
						(effects
							(font
								(size 1.27 1.27)
							)
						)
					)
				)
				(pin passive line
					(at 0 0 0)
					(length 2.54)
					(hide yes)
					(name "3V3"
						(effects
							(font
								(size 1.27 1.27)
							)
						)
					)
					(number "18"
						(effects
							(font
								(size 1.27 1.27)
							)
						)
					)
				)
				(pin passive line
					(at 0 0 0)
					(length 2.54)
					(hide yes)
					(name "3V3"
						(effects
							(font
								(size 1.27 1.27)
							)
						)
					)
					(number "9"
						(effects
							(font
								(size 1.27 1.27)
							)
						)
					)
				)
				(pin input line
					(at 0 -2.54 0)
					(length 2.54)
					(name "~{RESET}"
						(effects
							(font
								(size 1.27 1.27)
							)
						)
					)
					(number "15"
						(effects
							(font
								(size 1.27 1.27)
							)
						)
					)
				)
				(pin input line
					(at 0 -6.35 0)
					(length 2.54)
					(name "VBUS_{DET}"
						(effects
							(font
								(size 1.27 1.27)
							)
						)
					)
					(number "16"
						(effects
							(font
								(size 1.27 1.27)
							)
						)
					)
				)
				(pin bidirectional line
					(at 0 -10.16 0)
					(length 2.54)
					(name "UP_D+"
						(effects
							(font
								(size 1.27 1.27)
							)
						)
					)
					(number "20"
						(effects
							(font
								(size 1.27 1.27)
							)
						)
					)
				)
				(pin bidirectional line
					(at 0 -12.7 0)
					(length 2.54)
					(name "UP_D-"
						(effects
							(font
								(size 1.27 1.27)
							)
						)
					)
					(number "19"
						(effects
							(font
								(size 1.27 1.27)
							)
						)
					)
				)
				(pin no_connect line
					(at 0 -16.51 0)
					(length 2.54)
					(hide yes)
					(name "NC"
						(effects
							(font
								(size 1.27 1.27)
							)
						)
					)
					(number "6"
						(effects
							(font
								(size 1.27 1.27)
							)
						)
					)
				)
				(pin input line
					(at 0 -20.32 0)
					(length 2.54)
					(name "XTAL_{IN}"
						(effects
							(font
								(size 1.27 1.27)
							)
						)
					)
					(number "22"
						(effects
							(font
								(size 1.27 1.27)
							)
						)
					)
					(alternate "CLKIN" input line)
				)
				(pin input line
					(at 0 -22.86 0)
					(length 2.54)
					(name "XTAL_{OUT}"
						(effects
							(font
								(size 1.27 1.27)
							)
						)
					)
					(number "21"
						(effects
							(font
								(size 1.27 1.27)
							)
						)
					)
				)
				(pin input line
					(at 0 -26.67 0)
					(length 2.54)
					(name "SMBDATA"
						(effects
							(font
								(size 1.27 1.27)
							)
						)
					)
					(number "13"
						(effects
							(font
								(size 1.27 1.27)
							)
						)
					)
					(alternate "NON_REM1" input line)
				)
				(pin input line
					(at 0 -29.21 0)
					(length 2.54)
					(name "SMBCLK"
						(effects
							(font
								(size 1.27 1.27)
							)
						)
					)
					(number "14"
						(effects
							(font
								(size 1.27 1.27)
							)
						)
					)
					(alternate "CFG_SEL" output line)
				)
				(pin input line
					(at 0 -31.75 0)
					(length 2.54)
					(name "SUSP_IND"
						(effects
							(font
								(size 1.27 1.27)
							)
						)
					)
					(number "17"
						(effects
							(font
								(size 1.27 1.27)
							)
						)
					)
					(alternate "LOCAL_PWR" input line)
					(alternate "NON_REM0" input line)
				)
				(pin power_in line
					(at 0 -35.56 0)
					(length 2.54)
					(name "GND"
						(effects
							(font
								(size 1.27 1.27)
							)
						)
					)
					(number "25"
						(effects
							(font
								(size 1.27 1.27)
							)
						)
					)
				)
				(pin output line
					(at 33.02 0 180)
					(length 2.54)
					(name "PWR_{PRT1}"
						(effects
							(font
								(size 1.27 1.27)
							)
						)
					)
					(number "7"
						(effects
							(font
								(size 1.27 1.27)
							)
						)
					)
					(alternate "BC_EN1" passive line)
				)
				(pin input line
					(at 33.02 -2.54 180)
					(length 2.54)
					(name "OSC_{N1}"
						(effects
							(font
								(size 1.27 1.27)
							)
						)
					)
					(number "8"
						(effects
							(font
								(size 1.27 1.27)
							)
						)
					)
				)
				(pin bidirectional line
					(at 33.02 -6.35 180)
					(length 2.54)
					(name "DN1_D+"
						(effects
							(font
								(size 1.27 1.27)
							)
						)
					)
					(number "3"
						(effects
							(font
								(size 1.27 1.27)
							)
						)
					)
				)
				(pin bidirectional line
					(at 33.02 -8.89 180)
					(length 2.54)
					(name "DN1_D-"
						(effects
							(font
								(size 1.27 1.27)
							)
						)
					)
					(number "2"
						(effects
							(font
								(size 1.27 1.27)
							)
						)
					)
				)
				(pin output line
					(at 33.02 -13.97 180)
					(length 2.54)
					(name "PWR_{PRT2}"
						(effects
							(font
								(size 1.27 1.27)
							)
						)
					)
					(number "11"
						(effects
							(font
								(size 1.27 1.27)
							)
						)
					)
				)
				(pin input line
					(at 33.02 -16.51 180)
					(length 2.54)
					(name "OSC_{N2}"
						(effects
							(font
								(size 1.27 1.27)
							)
						)
					)
					(number "12"
						(effects
							(font
								(size 1.27 1.27)
							)
						)
					)
				)
				(pin bidirectional line
					(at 33.02 -20.32 180)
					(length 2.54)
					(name "DN2_D+"
						(effects
							(font
								(size 1.27 1.27)
							)
						)
					)
					(number "5"
						(effects
							(font
								(size 1.27 1.27)
							)
						)
					)
				)
				(pin bidirectional line
					(at 33.02 -22.86 180)
					(length 2.54)
					(name "DN2_D-"
						(effects
							(font
								(size 1.27 1.27)
							)
						)
					)
					(number "4"
						(effects
							(font
								(size 1.27 1.27)
							)
						)
					)
				)
				(pin passive line
					(at 33.02 -29.21 180)
					(length 2.54)
					(name "CRFILT"
						(effects
							(font
								(size 1.27 1.27)
							)
						)
					)
					(number "10"
						(effects
							(font
								(size 1.27 1.27)
							)
						)
					)
				)
				(pin passive line
					(at 33.02 -31.75 180)
					(length 2.54)
					(name "PLLFILT"
						(effects
							(font
								(size 1.27 1.27)
							)
						)
					)
					(number "23"
						(effects
							(font
								(size 1.27 1.27)
							)
						)
					)
				)
				(pin passive line
					(at 33.02 -34.29 180)
					(length 2.54)
					(name "R_{BIAS}"
						(effects
							(font
								(size 1.27 1.27)
							)
						)
					)
					(number "24"
						(effects
							(font
								(size 1.27 1.27)
							)
						)
					)
				)
			)
		)
	(symbol "antmicroInterfaceControllers:USB3315-CP-TR"
			(exclude_from_sim no)
			(in_bom yes)
			(on_board yes)
			(property "Reference" "U"
				(at 45.72 -2.54 0)
				(effects
					(font
						(size 1.27 1.27)
						(thickness 0.15)
					)
					(justify left bottom)
				)
			)
			(property "Value" "USB3315-CP-TR"
				(at 45.72 -7.62 0)
				(effects
					(font
						(size 1.27 1.27)
						(thickness 0.15)
					)
					(justify left bottom)
					(hide yes)
				)
			)
			(property "Footprint" "antmicro-footprints:QFN-24-1EP_4x4mm_P0.5_EP2.5x2.5mm"
				(at 45.72 -10.16 0)
				(effects
					(font
						(size 1.27 1.27)
						(thickness 0.15)
					)
					(justify left bottom)
					(hide yes)
				)
			)
			(property "Datasheet" "https://ww1.microchip.com/downloads/aemDocuments/documents/OTH/ProductDocuments/DataSheets/00002364A.pdf"
				(at 45.72 -12.7 0)
				(effects
					(font
						(size 1.27 1.27)
						(thickness 0.15)
					)
					(justify left bottom)
					(hide yes)
				)
			)
			(property "Description" "USB Interface, USB PHY Transceiver, USB 2.0, 3 V, 5.5 V, QFN, 24 Pins"
				(at 0 0 0)
				(effects
					(font
						(size 1.27 1.27)
					)
					(hide yes)
				)
			)
			(property "MPN" "USB3315-CP-TR"
				(at 45.72 -5.08 0)
				(effects
					(font
						(size 1.27 1.27)
						(thickness 0.15)
					)
					(justify left bottom)
				)
			)
			(property "Manufacturer" "Microchip Technology"
				(at 45.72 -15.24 0)
				(effects
					(font
						(size 1.27 1.27)
						(thickness 0.15)
					)
					(justify left bottom)
					(hide yes)
				)
			)
			(property "Author" "Antmicro"
				(at 45.72 -17.78 0)
				(effects
					(font
						(size 1.27 1.27)
						(thickness 0.15)
					)
					(justify left bottom)
					(hide yes)
				)
			)
			(property "License" "Apache-2.0"
				(at 45.72 -20.32 0)
				(effects
					(font
						(size 1.27 1.27)
						(thickness 0.15)
					)
					(justify left bottom)
					(hide yes)
				)
			)
			(property "ki_keywords" "SMT, TRANSCEIVER, IC, USB, INTERFACE"
				(at 0 0 0)
				(effects
					(font
						(size 1.27 1.27)
					)
					(hide yes)
				)
			)
			(symbol "USB3315-CP-TR_1_1"
				(rectangle
					(start 2.54 2.54)
					(end 17.78 -38.1)
					(stroke
						(width 0.254)
						(type default)
					)
					(fill
						(type background)
					)
				)
				(pin power_in line
					(at 0 0 0)
					(length 2.54)
					(name "VBAT"
						(effects
							(font
								(size 1.27 1.27)
							)
						)
					)
					(number "3"
						(effects
							(font
								(size 1.27 1.27)
							)
						)
					)
				)
				(pin power_in line
					(at 0 -2.54 0)
					(length 2.54)
					(name "VDDIO"
						(effects
							(font
								(size 1.27 1.27)
							)
						)
					)
					(number "17"
						(effects
							(font
								(size 1.27 1.27)
							)
						)
					)
				)
				(pin bidirectional line
					(at 0 -6.35 0)
					(length 2.54)
					(name "D_P"
						(effects
							(font
								(size 1.27 1.27)
							)
						)
					)
					(number "6"
						(effects
							(font
								(size 1.27 1.27)
							)
						)
					)
				)
				(pin bidirectional line
					(at 0 -8.89 0)
					(length 2.54)
					(name "D_N"
						(effects
							(font
								(size 1.27 1.27)
							)
						)
					)
					(number "5"
						(effects
							(font
								(size 1.27 1.27)
							)
						)
					)
				)
				(pin bidirectional line
					(at 0 -11.43 0)
					(length 2.54)
					(name "VBUS"
						(effects
							(font
								(size 1.27 1.27)
							)
						)
					)
					(number "2"
						(effects
							(font
								(size 1.27 1.27)
							)
						)
					)
				)
				(pin input line
					(at 0 -13.97 0)
					(length 2.54)
					(name "ID"
						(effects
							(font
								(size 1.27 1.27)
							)
						)
					)
					(number "1"
						(effects
							(font
								(size 1.27 1.27)
							)
						)
					)
				)
				(pin output line
					(at 0 -16.51 0)
					(length 2.54)
					(name "CPEN"
						(effects
							(font
								(size 1.27 1.27)
							)
						)
					)
					(number "7"
						(effects
							(font
								(size 1.27 1.27)
							)
						)
					)
				)
				(pin input line
					(at 0 -21.59 0)
					(length 2.54)
					(name "REFCLK"
						(effects
							(font
								(size 1.27 1.27)
							)
						)
					)
					(number "23"
						(effects
							(font
								(size 1.27 1.27)
							)
						)
					)
				)
				(pin input line
					(at 0 -24.13 0)
					(length 2.54)
					(name "RESETB"
						(effects
							(font
								(size 1.27 1.27)
							)
						)
					)
					(number "22"
						(effects
							(font
								(size 1.27 1.27)
							)
						)
					)
				)
				(pin passive line
					(at 0 -30.48 0)
					(length 2.54)
					(name "RBIAS"
						(effects
							(font
								(size 1.27 1.27)
							)
						)
					)
					(number "24"
						(effects
							(font
								(size 1.27 1.27)
							)
						)
					)
				)
				(pin power_in line
					(at 0 -35.56 0)
					(length 2.54)
					(name "GND"
						(effects
							(font
								(size 1.27 1.27)
							)
						)
					)
					(number "25"
						(effects
							(font
								(size 1.27 1.27)
							)
						)
					)
				)
				(pin power_out line
					(at 20.32 0 180)
					(length 2.54)
					(name "VDD33"
						(effects
							(font
								(size 1.27 1.27)
							)
						)
					)
					(number "4"
						(effects
							(font
								(size 1.27 1.27)
							)
						)
					)
				)
				(pin power_out line
					(at 20.32 -2.54 180)
					(length 2.54)
					(name "VDD18"
						(effects
							(font
								(size 1.27 1.27)
							)
						)
					)
					(number "21"
						(effects
							(font
								(size 1.27 1.27)
							)
						)
					)
				)
				(pin bidirectional line
					(at 20.32 -6.35 180)
					(length 2.54)
					(name "DATA0"
						(effects
							(font
								(size 1.27 1.27)
							)
						)
					)
					(number "16"
						(effects
							(font
								(size 1.27 1.27)
							)
						)
					)
				)
				(pin bidirectional line
					(at 20.32 -8.89 180)
					(length 2.54)
					(name "DATA1"
						(effects
							(font
								(size 1.27 1.27)
							)
						)
					)
					(number "15"
						(effects
							(font
								(size 1.27 1.27)
							)
						)
					)
				)
				(pin bidirectional line
					(at 20.32 -11.43 180)
					(length 2.54)
					(name "DATA2"
						(effects
							(font
								(size 1.27 1.27)
							)
						)
					)
					(number "14"
						(effects
							(font
								(size 1.27 1.27)
							)
						)
					)
				)
				(pin bidirectional line
					(at 20.32 -13.97 180)
					(length 2.54)
					(name "DATA3"
						(effects
							(font
								(size 1.27 1.27)
							)
						)
					)
					(number "13"
						(effects
							(font
								(size 1.27 1.27)
							)
						)
					)
				)
				(pin bidirectional line
					(at 20.32 -16.51 180)
					(length 2.54)
					(name "DATA4"
						(effects
							(font
								(size 1.27 1.27)
							)
						)
					)
					(number "11"
						(effects
							(font
								(size 1.27 1.27)
							)
						)
					)
				)
				(pin bidirectional line
					(at 20.32 -19.05 180)
					(length 2.54)
					(name "DATA5"
						(effects
							(font
								(size 1.27 1.27)
							)
						)
					)
					(number "10"
						(effects
							(font
								(size 1.27 1.27)
							)
						)
					)
				)
				(pin bidirectional line
					(at 20.32 -21.59 180)
					(length 2.54)
					(name "DATA6"
						(effects
							(font
								(size 1.27 1.27)
							)
						)
					)
					(number "9"
						(effects
							(font
								(size 1.27 1.27)
							)
						)
					)
				)
				(pin bidirectional line
					(at 20.32 -24.13 180)
					(length 2.54)
					(name "DATA7"
						(effects
							(font
								(size 1.27 1.27)
							)
						)
					)
					(number "8"
						(effects
							(font
								(size 1.27 1.27)
							)
						)
					)
				)
				(pin output line
					(at 20.32 -27.94 180)
					(length 2.54)
					(name "CLKOUT"
						(effects
							(font
								(size 1.27 1.27)
							)
						)
					)
					(number "12"
						(effects
							(font
								(size 1.27 1.27)
							)
						)
					)
				)
				(pin input line
					(at 20.32 -30.48 180)
					(length 2.54)
					(name "STP"
						(effects
							(font
								(size 1.27 1.27)
							)
						)
					)
					(number "20"
						(effects
							(font
								(size 1.27 1.27)
							)
						)
					)
				)
				(pin output line
					(at 20.32 -33.02 180)
					(length 2.54)
					(name "NXT"
						(effects
							(font
								(size 1.27 1.27)
							)
						)
					)
					(number "18"
						(effects
							(font
								(size 1.27 1.27)
							)
						)
					)
				)
				(pin output line
					(at 20.32 -35.56 180)
					(length 2.54)
					(name "DIR"
						(effects
							(font
								(size 1.27 1.27)
							)
						)
					)
					(number "19"
						(effects
							(font
								(size 1.27 1.27)
							)
						)
					)
				)
			)
		)
	(symbol "antmicroInterfaceDriversReceiversTransceivers:PI3HDX511DZLE"
			(exclude_from_sim no)
			(in_bom yes)
			(on_board yes)
			(property "Reference" "U"
				(at 50.8 0 0)
				(effects
					(font
						(size 1.27 1.27)
						(thickness 0.15)
					)
					(justify left bottom)
				)
			)
			(property "Value" "PI3HDX511DZLE"
				(at 50.8 -5.08 0)
				(effects
					(font
						(size 1.27 1.27)
						(thickness 0.15)
					)
					(justify left bottom)
					(hide yes)
				)
			)
			(property "Footprint" "antmicro-footprints:TQFN-30-1EP_2.5x4.5mm_P0.4mm_Layout5x10"
				(at 50.8 -7.62 0)
				(effects
					(font
						(size 1.27 1.27)
						(thickness 0.15)
					)
					(justify left bottom)
					(hide yes)
				)
			)
			(property "Datasheet" "https://eu.mouser.com/datasheet/2/115/diodes_inc_diod-s-a0004145302-1-1749206.pdf"
				(at 50.8 -10.16 0)
				(effects
					(font
						(size 1.27 1.27)
						(thickness 0.15)
					)
					(justify left bottom)
					(hide yes)
				)
			)
			(property "Description" "Video ICs Active HDMI TQFN-30"
				(at 0 0 0)
				(effects
					(font
						(size 1.27 1.27)
					)
					(hide yes)
				)
			)
			(property "MPN" "PI3HDX511DZLE"
				(at 50.8 -2.54 0)
				(effects
					(font
						(size 1.27 1.27)
						(thickness 0.15)
					)
					(justify left bottom)
				)
			)
			(property "Manufacturer" "Diodes Incorporated"
				(at 50.8 -12.7 0)
				(effects
					(font
						(size 1.27 1.27)
						(thickness 0.15)
					)
					(justify left bottom)
					(hide yes)
				)
			)
			(property "Author" "Antmicro"
				(at 50.8 -15.24 0)
				(effects
					(font
						(size 1.27 1.27)
						(thickness 0.15)
					)
					(justify left bottom)
					(hide yes)
				)
			)
			(property "License" "Apache-2.0"
				(at 50.8 -17.78 0)
				(effects
					(font
						(size 1.27 1.27)
						(thickness 0.15)
					)
					(justify left bottom)
					(hide yes)
				)
			)
			(property "ki_keywords" "SMT, IC, HDMI"
				(at 0 0 0)
				(effects
					(font
						(size 1.27 1.27)
					)
					(hide yes)
				)
			)
			(symbol "PI3HDX511DZLE_1_1"
				(rectangle
					(start 2.54 2.54)
					(end 25.4 -44.45)
					(stroke
						(width 0.254)
						(type default)
					)
					(fill
						(type background)
					)
				)
				(pin power_in line
					(at 0 0 0)
					(length 2.54)
					(name "VDD"
						(effects
							(font
								(size 1.27 1.27)
							)
						)
					)
					(number "20"
						(effects
							(font
								(size 1.27 1.27)
							)
						)
					)
				)
				(pin passive line
					(at 0 0 0)
					(length 2.54)
					(hide yes)
					(name "VDD"
						(effects
							(font
								(size 1.27 1.27)
							)
						)
					)
					(number "30"
						(effects
							(font
								(size 1.27 1.27)
							)
						)
					)
				)
				(pin power_in line
					(at 0 -2.54 0)
					(length 2.54)
					(name "CEXT"
						(effects
							(font
								(size 1.27 1.27)
							)
						)
					)
					(number "1"
						(effects
							(font
								(size 1.27 1.27)
							)
						)
					)
				)
				(pin input line
					(at 0 -5.08 0)
					(length 2.54)
					(name "OEB"
						(effects
							(font
								(size 1.27 1.27)
							)
						)
					)
					(number "29"
						(effects
							(font
								(size 1.27 1.27)
							)
						)
					)
				)
				(pin input line
					(at 0 -8.89 0)
					(length 2.54)
					(name "IN_D2_P"
						(effects
							(font
								(size 1.27 1.27)
							)
						)
					)
					(number "3"
						(effects
							(font
								(size 1.27 1.27)
							)
						)
					)
				)
				(pin input line
					(at 0 -11.43 0)
					(length 2.54)
					(name "IN_D2_N"
						(effects
							(font
								(size 1.27 1.27)
							)
						)
					)
					(number "2"
						(effects
							(font
								(size 1.27 1.27)
							)
						)
					)
				)
				(pin input line
					(at 0 -13.97 0)
					(length 2.54)
					(name "IN_D1_P"
						(effects
							(font
								(size 1.27 1.27)
							)
						)
					)
					(number "5"
						(effects
							(font
								(size 1.27 1.27)
							)
						)
					)
				)
				(pin input line
					(at 0 -16.51 0)
					(length 2.54)
					(name "IN_D1_N"
						(effects
							(font
								(size 1.27 1.27)
							)
						)
					)
					(number "4"
						(effects
							(font
								(size 1.27 1.27)
							)
						)
					)
				)
				(pin input line
					(at 0 -19.05 0)
					(length 2.54)
					(name "IN_D0_P"
						(effects
							(font
								(size 1.27 1.27)
							)
						)
					)
					(number "7"
						(effects
							(font
								(size 1.27 1.27)
							)
						)
					)
				)
				(pin input line
					(at 0 -21.59 0)
					(length 2.54)
					(name "IN_D0_N"
						(effects
							(font
								(size 1.27 1.27)
							)
						)
					)
					(number "6"
						(effects
							(font
								(size 1.27 1.27)
							)
						)
					)
				)
				(pin input line
					(at 0 -24.13 0)
					(length 2.54)
					(name "IN_CLK_P"
						(effects
							(font
								(size 1.27 1.27)
							)
						)
					)
					(number "9"
						(effects
							(font
								(size 1.27 1.27)
							)
						)
					)
				)
				(pin input line
					(at 0 -26.67 0)
					(length 2.54)
					(name "IN_CLK_N"
						(effects
							(font
								(size 1.27 1.27)
							)
						)
					)
					(number "8"
						(effects
							(font
								(size 1.27 1.27)
							)
						)
					)
				)
				(pin output line
					(at 0 -30.48 0)
					(length 2.54)
					(name "HPD_SRC"
						(effects
							(font
								(size 1.27 1.27)
							)
						)
					)
					(number "10"
						(effects
							(font
								(size 1.27 1.27)
							)
						)
					)
				)
				(pin bidirectional line
					(at 0 -33.02 0)
					(length 2.54)
					(name "SDA_SRC"
						(effects
							(font
								(size 1.27 1.27)
							)
						)
					)
					(number "11"
						(effects
							(font
								(size 1.27 1.27)
							)
						)
					)
				)
				(pin bidirectional line
					(at 0 -35.56 0)
					(length 2.54)
					(name "SCL_SRC"
						(effects
							(font
								(size 1.27 1.27)
							)
						)
					)
					(number "12"
						(effects
							(font
								(size 1.27 1.27)
							)
						)
					)
				)
				(pin power_in line
					(at 0 -39.37 0)
					(length 2.54)
					(name "EP"
						(effects
							(font
								(size 1.27 1.27)
							)
						)
					)
					(number "31"
						(effects
							(font
								(size 1.27 1.27)
							)
						)
					)
				)
				(pin passive line
					(at 0 -41.91 0)
					(length 2.54)
					(hide yes)
					(name "GND"
						(effects
							(font
								(size 1.27 1.27)
							)
						)
					)
					(number "13"
						(effects
							(font
								(size 1.27 1.27)
							)
						)
					)
				)
				(pin power_in line
					(at 0 -41.91 0)
					(length 2.54)
					(name "GND"
						(effects
							(font
								(size 1.27 1.27)
							)
						)
					)
					(number "28"
						(effects
							(font
								(size 1.27 1.27)
							)
						)
					)
				)
				(pin input line
					(at 27.94 0 180)
					(length 2.54)
					(name "OC_S0"
						(effects
							(font
								(size 1.27 1.27)
							)
						)
					)
					(number "14"
						(effects
							(font
								(size 1.27 1.27)
							)
						)
					)
				)
				(pin input line
					(at 27.94 -2.54 180)
					(length 2.54)
					(name "EQ_S0"
						(effects
							(font
								(size 1.27 1.27)
							)
						)
					)
					(number "15"
						(effects
							(font
								(size 1.27 1.27)
							)
						)
					)
				)
				(pin output line
					(at 27.94 -8.89 180)
					(length 2.54)
					(name "OUT_D2_P"
						(effects
							(font
								(size 1.27 1.27)
							)
						)
					)
					(number "23"
						(effects
							(font
								(size 1.27 1.27)
							)
						)
					)
				)
				(pin output line
					(at 27.94 -11.43 180)
					(length 2.54)
					(name "OUT_D2_N"
						(effects
							(font
								(size 1.27 1.27)
							)
						)
					)
					(number "24"
						(effects
							(font
								(size 1.27 1.27)
							)
						)
					)
				)
				(pin output line
					(at 27.94 -13.97 180)
					(length 2.54)
					(name "OUT_D1_P"
						(effects
							(font
								(size 1.27 1.27)
							)
						)
					)
					(number "21"
						(effects
							(font
								(size 1.27 1.27)
							)
						)
					)
				)
				(pin output line
					(at 27.94 -16.51 180)
					(length 2.54)
					(name "OUT_D1_N"
						(effects
							(font
								(size 1.27 1.27)
							)
						)
					)
					(number "22"
						(effects
							(font
								(size 1.27 1.27)
							)
						)
					)
				)
				(pin output line
					(at 27.94 -19.05 180)
					(length 2.54)
					(name "OUT_D0_P"
						(effects
							(font
								(size 1.27 1.27)
							)
						)
					)
					(number "18"
						(effects
							(font
								(size 1.27 1.27)
							)
						)
					)
				)
				(pin output line
					(at 27.94 -21.59 180)
					(length 2.54)
					(name "OUT_D0_N"
						(effects
							(font
								(size 1.27 1.27)
							)
						)
					)
					(number "19"
						(effects
							(font
								(size 1.27 1.27)
							)
						)
					)
				)
				(pin output line
					(at 27.94 -24.13 180)
					(length 2.54)
					(name "OUT_CLK_P"
						(effects
							(font
								(size 1.27 1.27)
							)
						)
					)
					(number "16"
						(effects
							(font
								(size 1.27 1.27)
							)
						)
					)
				)
				(pin output line
					(at 27.94 -26.67 180)
					(length 2.54)
					(name "OUT_CLK_N"
						(effects
							(font
								(size 1.27 1.27)
							)
						)
					)
					(number "17"
						(effects
							(font
								(size 1.27 1.27)
							)
						)
					)
				)
				(pin input line
					(at 27.94 -30.48 180)
					(length 2.54)
					(name "HPD_SINK"
						(effects
							(font
								(size 1.27 1.27)
							)
						)
					)
					(number "27"
						(effects
							(font
								(size 1.27 1.27)
							)
						)
					)
				)
				(pin bidirectional line
					(at 27.94 -33.02 180)
					(length 2.54)
					(name "SDA_SINK"
						(effects
							(font
								(size 1.27 1.27)
							)
						)
					)
					(number "26"
						(effects
							(font
								(size 1.27 1.27)
							)
						)
					)
				)
				(pin bidirectional line
					(at 27.94 -35.56 180)
					(length 2.54)
					(name "SCL_SINK"
						(effects
							(font
								(size 1.27 1.27)
							)
						)
					)
					(number "25"
						(effects
							(font
								(size 1.27 1.27)
							)
						)
					)
				)
			)
		)
	(symbol "antmicroLEDIndicationDiscrete:LED_G_0603_LTST-C190GKT"
			(pin_numbers
				(hide yes)
			)
			(pin_names
				(hide yes)
			)
			(exclude_from_sim no)
			(in_bom yes)
			(on_board yes)
			(property "Reference" "D"
				(at 22.86 -2.54 0)
				(effects
					(font
						(size 1.27 1.27)
						(thickness 0.15)
					)
					(justify left bottom)
				)
			)
			(property "Value" "LED_G_0603_LTST-C190GKT"
				(at 22.86 -7.62 0)
				(effects
					(font
						(size 1.27 1.27)
						(thickness 0.15)
					)
					(justify left bottom)
					(hide yes)
				)
			)
			(property "Footprint" "antmicro-footprints:LED_0603_1608Metric_G"
				(at 22.86 -10.16 0)
				(effects
					(font
						(size 1.27 1.27)
						(thickness 0.15)
					)
					(justify left bottom)
					(hide yes)
				)
			)
			(property "Datasheet" "https://media.digikey.com/pdf/Data%20Sheets/Lite-On%20PDFs/LTST-C190GKT.pdf"
				(at 22.86 -12.7 0)
				(effects
					(font
						(size 1.27 1.27)
						(thickness 0.15)
					)
					(justify left bottom)
					(hide yes)
				)
			)
			(property "Description" "LED, Green, SMD, 0603, 20 mA, 2.1 V, 569 nm"
				(at 0 0 0)
				(effects
					(font
						(size 1.27 1.27)
					)
					(hide yes)
				)
			)
			(property "MPN" "LTST-C190GKT"
				(at 22.86 -15.24 0)
				(effects
					(font
						(size 1.27 1.27)
						(thickness 0.15)
					)
					(justify left bottom)
					(hide yes)
				)
			)
			(property "Manufacturer" "Lite-On"
				(at 22.86 -17.78 0)
				(effects
					(font
						(size 1.27 1.27)
						(thickness 0.15)
					)
					(justify left bottom)
					(hide yes)
				)
			)
			(property "Color" "Green"
				(at 22.86 -5.08 0)
				(effects
					(font
						(size 1.27 1.27)
					)
					(justify left bottom)
				)
			)
			(property "Author" "Antmicro"
				(at 22.86 -20.32 0)
				(effects
					(font
						(size 1.27 1.27)
						(thickness 0.15)
					)
					(justify left bottom)
					(hide yes)
				)
			)
			(property "License" "Apache-2.0"
				(at 22.86 -22.86 0)
				(effects
					(font
						(size 1.27 1.27)
						(thickness 0.15)
					)
					(justify left bottom)
					(hide yes)
				)
			)
			(property "ki_keywords" "SMT, DIODE, SEMICONDUCTOR, LED"
				(at 0 0 0)
				(effects
					(font
						(size 1.27 1.27)
					)
					(hide yes)
				)
			)
			(symbol "LED_G_0603_LTST-C190GKT_0_1"
				(polyline
					(pts
						(xy 1.905 0) (xy 0.635 0)
					)
					(stroke
						(width 0)
						(type default)
					)
					(fill
						(type none)
					)
				)
				(polyline
					(pts
						(xy 4.445 0) (xy 3.175 0)
					)
					(stroke
						(width 0)
						(type default)
					)
					(fill
						(type none)
					)
				)
			)
			(symbol "LED_G_0603_LTST-C190GKT_1_1"
				(polyline
					(pts
						(xy 1.143 2.286) (xy 1.143 1.778) (xy 1.143 2.286) (xy 1.651 2.286) (xy 1.143 2.286) (xy 2.159 1.27)
					)
					(stroke
						(width 0.254)
						(type default)
					)
					(fill
						(type none)
					)
				)
				(polyline
					(pts
						(xy 1.778 1.016) (xy 1.778 -1.016)
					)
					(stroke
						(width 0.254)
						(type default)
					)
					(fill
						(type none)
					)
				)
				(polyline
					(pts
						(xy 2.159 2.54) (xy 2.159 2.032) (xy 2.159 2.54) (xy 2.667 2.54) (xy 2.159 2.54) (xy 3.048 1.651)
					)
					(stroke
						(width 0.254)
						(type default)
					)
					(fill
						(type none)
					)
				)
				(polyline
					(pts
						(xy 3.302 1.016) (xy 3.302 -1.016) (xy 1.778 0) (xy 3.302 1.016)
					)
					(stroke
						(width 0.254)
						(type default)
					)
					(fill
						(type outline)
					)
				)
				(pin passive line
					(at 0 0 0)
					(length 0.635)
					(name "C"
						(effects
							(font
								(size 1.27 1.27)
							)
						)
					)
					(number "1"
						(effects
							(font
								(size 1.27 1.27)
							)
						)
					)
				)
				(pin passive line
					(at 5.08 0 180)
					(length 0.635)
					(name "A"
						(effects
							(font
								(size 1.27 1.27)
							)
						)
					)
					(number "2"
						(effects
							(font
								(size 1.27 1.27)
							)
						)
					)
				)
			)
		)
	(symbol "antmicroLEDIndicationDiscrete:LED_RGB_1204_LTST-S310F2KT_Horizontal"
			(exclude_from_sim no)
			(in_bom yes)
			(on_board yes)
			(property "Reference" "D"
				(at 27.94 -2.54 0)
				(effects
					(font
						(size 1.27 1.27)
						(thickness 0.15)
					)
					(justify left bottom)
				)
			)
			(property "Value" "LED_RGB_1204_LTST-S310F2KT_Horizontal"
				(at 27.94 -7.62 0)
				(effects
					(font
						(size 1.27 1.27)
						(thickness 0.15)
					)
					(justify left bottom)
					(hide yes)
				)
			)
			(property "Footprint" "antmicro-footprints:LED_1204_3210Metric_RGB_Horizontal"
				(at 27.94 -10.16 0)
				(effects
					(font
						(size 1.27 1.27)
						(thickness 0.15)
					)
					(justify left bottom)
					(hide yes)
				)
			)
			(property "Datasheet" "https://optoelectronics.liteon.com/upload/download/DS22-2003-047/LTST-S310F2KT.PDF"
				(at 27.94 -12.7 0)
				(effects
					(font
						(size 1.27 1.27)
						(thickness 0.15)
					)
					(justify left bottom)
					(hide yes)
				)
			)
			(property "Description" "LED, RGB, SMD, 1204, R 30 mA, G 20 mA, B 20 mA, R 2 V, G 3.5 V, B 3.5 V, Common Anode, Side Look"
				(at 0 0 0)
				(effects
					(font
						(size 1.27 1.27)
					)
					(hide yes)
				)
			)
			(property "MPN" "LTST-S310F2KT"
				(at 27.94 -15.24 0)
				(effects
					(font
						(size 1.27 1.27)
						(thickness 0.15)
					)
					(justify left bottom)
					(hide yes)
				)
			)
			(property "Manufacturer" "Lite-On"
				(at 27.94 -17.78 0)
				(effects
					(font
						(size 1.27 1.27)
						(thickness 0.15)
					)
					(justify left bottom)
					(hide yes)
				)
			)
			(property "Color" "R, G, B"
				(at 27.94 -5.08 0)
				(effects
					(font
						(size 1.27 1.27)
					)
					(justify left bottom)
				)
			)
			(property "Author" "Antmicro"
				(at 27.94 -20.32 0)
				(effects
					(font
						(size 1.27 1.27)
						(thickness 0.15)
					)
					(justify left bottom)
					(hide yes)
				)
			)
			(property "License" "Apache-2.0"
				(at 27.94 -22.86 0)
				(effects
					(font
						(size 1.27 1.27)
						(thickness 0.15)
					)
					(justify left bottom)
					(hide yes)
				)
			)
			(property "ki_keywords" "SMT, DIODE, SEMICONDUCTOR, LED"
				(at 0 0 0)
				(effects
					(font
						(size 1.27 1.27)
					)
					(hide yes)
				)
			)
			(symbol "LED_RGB_1204_LTST-S310F2KT_Horizontal_1_1"
				(rectangle
					(start 2.54 3.81)
					(end 16.51 -11.43)
					(stroke
						(width 0.254)
						(type default)
					)
					(fill
						(type background)
					)
				)
				(polyline
					(pts
						(xy 6.35 0) (xy 8.89 0)
					)
					(stroke
						(width 0.254)
						(type default)
					)
					(fill
						(type none)
					)
				)
				(polyline
					(pts
						(xy 6.35 -3.81) (xy 8.89 -3.81)
					)
					(stroke
						(width 0.254)
						(type default)
					)
					(fill
						(type none)
					)
				)
				(polyline
					(pts
						(xy 6.35 -7.62) (xy 8.89 -7.62)
					)
					(stroke
						(width 0.254)
						(type default)
					)
					(fill
						(type none)
					)
				)
				(polyline
					(pts
						(xy 8.128 2.286) (xy 8.128 1.778) (xy 8.128 2.286) (xy 8.636 2.286) (xy 8.128 2.286) (xy 9.144 1.27)
					)
					(stroke
						(width 0.254)
						(type default)
					)
					(fill
						(type none)
					)
				)
				(polyline
					(pts
						(xy 8.128 -1.524) (xy 8.128 -2.032) (xy 8.128 -1.524) (xy 8.636 -1.524) (xy 8.128 -1.524) (xy 9.144 -2.54)
					)
					(stroke
						(width 0.254)
						(type default)
					)
					(fill
						(type none)
					)
				)
				(polyline
					(pts
						(xy 8.128 -5.334) (xy 8.128 -5.842) (xy 8.128 -5.334) (xy 8.636 -5.334) (xy 8.128 -5.334) (xy 9.144 -6.35)
					)
					(stroke
						(width 0.254)
						(type default)
					)
					(fill
						(type none)
					)
				)
				(polyline
					(pts
						(xy 8.763 1.016) (xy 8.763 -1.016)
					)
					(stroke
						(width 0.254)
						(type default)
					)
					(fill
						(type none)
					)
				)
				(polyline
					(pts
						(xy 8.763 -2.794) (xy 8.763 -4.826)
					)
					(stroke
						(width 0.254)
						(type default)
					)
					(fill
						(type none)
					)
				)
				(polyline
					(pts
						(xy 8.763 -6.604) (xy 8.763 -8.636)
					)
					(stroke
						(width 0.254)
						(type default)
					)
					(fill
						(type none)
					)
				)
				(polyline
					(pts
						(xy 9.144 2.54) (xy 9.144 2.032) (xy 9.144 2.54) (xy 9.652 2.54) (xy 9.144 2.54) (xy 10.033 1.651)
					)
					(stroke
						(width 0.254)
						(type default)
					)
					(fill
						(type none)
					)
				)
				(polyline
					(pts
						(xy 9.144 -1.27) (xy 9.144 -1.778) (xy 9.144 -1.27) (xy 9.652 -1.27) (xy 9.144 -1.27) (xy 10.033 -2.159)
					)
					(stroke
						(width 0.254)
						(type default)
					)
					(fill
						(type none)
					)
				)
				(polyline
					(pts
						(xy 9.144 -5.08) (xy 9.144 -5.588) (xy 9.144 -5.08) (xy 9.652 -5.08) (xy 9.144 -5.08) (xy 10.033 -5.969)
					)
					(stroke
						(width 0.254)
						(type default)
					)
					(fill
						(type none)
					)
				)
				(polyline
					(pts
						(xy 10.16 -3.81) (xy 12.7 -3.81) (xy 12.7 0) (xy 10.16 0)
					)
					(stroke
						(width 0.254)
						(type default)
					)
					(fill
						(type none)
					)
				)
				(polyline
					(pts
						(xy 10.287 1.016) (xy 10.287 -1.016) (xy 8.763 0) (xy 10.287 1.016)
					)
					(stroke
						(width 0.254)
						(type default)
					)
					(fill
						(type outline)
					)
				)
				(polyline
					(pts
						(xy 10.287 -2.794) (xy 10.287 -4.826) (xy 8.763 -3.81) (xy 10.287 -2.794)
					)
					(stroke
						(width 0.254)
						(type default)
					)
					(fill
						(type outline)
					)
				)
				(polyline
					(pts
						(xy 10.287 -6.604) (xy 10.287 -8.636) (xy 8.763 -7.62) (xy 10.287 -6.604)
					)
					(stroke
						(width 0.254)
						(type default)
					)
					(fill
						(type outline)
					)
				)
				(polyline
					(pts
						(xy 12.7 -3.81) (xy 13.97 -3.81)
					)
					(stroke
						(width 0.254)
						(type default)
					)
					(fill
						(type none)
					)
				)
				(polyline
					(pts
						(xy 12.7 -3.81) (xy 12.7 -7.62) (xy 10.16 -7.62)
					)
					(stroke
						(width 0.254)
						(type default)
					)
					(fill
						(type none)
					)
				)
				(pin passive line
					(at 0 0 0)
					(length 2.54)
					(name "C_{R}"
						(effects
							(font
								(size 1.27 1.27)
							)
						)
					)
					(number "1"
						(effects
							(font
								(size 1.27 1.27)
							)
						)
					)
				)
				(pin passive line
					(at 0 -3.81 0)
					(length 2.54)
					(name "C_{G}"
						(effects
							(font
								(size 1.27 1.27)
							)
						)
					)
					(number "2"
						(effects
							(font
								(size 1.27 1.27)
							)
						)
					)
				)
				(pin passive line
					(at 0 -7.62 0)
					(length 2.54)
					(name "C_{B}"
						(effects
							(font
								(size 1.27 1.27)
							)
						)
					)
					(number "3"
						(effects
							(font
								(size 1.27 1.27)
							)
						)
					)
				)
				(pin passive line
					(at 19.05 -3.81 180)
					(length 2.54)
					(name "A"
						(effects
							(font
								(size 1.27 1.27)
							)
						)
					)
					(number "4"
						(effects
							(font
								(size 1.27 1.27)
							)
						)
					)
				)
			)
		)
	(symbol "antmicroLogicTranslatorsLevelShifters:74LVC1T45GM"
			(exclude_from_sim no)
			(in_bom yes)
			(on_board yes)
			(property "Reference" "U"
				(at 30.48 -5.08 0)
				(effects
					(font
						(size 1.27 1.27)
						(thickness 0.15)
					)
					(justify left bottom)
				)
			)
			(property "Value" "74LVC1T45GM"
				(at 30.48 -7.62 0)
				(effects
					(font
						(size 1.27 1.27)
						(thickness 0.15)
					)
					(justify left bottom)
					(hide yes)
				)
			)
			(property "Footprint" "antmicro-footprints:SOT-886"
				(at 30.48 -10.16 0)
				(effects
					(font
						(size 1.27 1.27)
						(thickness 0.15)
					)
					(justify left bottom)
					(hide yes)
				)
			)
			(property "Datasheet" "http://www.ti.com/general/docs/suppproductinfo.tsp?distId=10&gotoUrl=http%3A%2F%2Fwww.ti.com%2Flit%2Fgpn%2Fsn74lvc1t45"
				(at 30.48 -12.7 0)
				(effects
					(font
						(size 1.27 1.27)
						(thickness 0.15)
					)
					(justify left bottom)
					(hide yes)
				)
			)
			(property "Description" "Transceiver, Translating, 74LVC1T45, 74LVC Family, 1.2V to 5.5V Supply, XSON-6"
				(at 0 0 0)
				(effects
					(font
						(size 1.27 1.27)
					)
					(hide yes)
				)
			)
			(property "MPN" "74LVC1T45GM-Q100X"
				(at 30.48 -15.24 0)
				(effects
					(font
						(size 1.27 1.27)
						(thickness 0.15)
					)
					(justify left bottom)
				)
			)
			(property "Manufacturer" "Nexperia"
				(at 30.48 -17.78 0)
				(effects
					(font
						(size 1.27 1.27)
						(thickness 0.15)
					)
					(justify left bottom)
					(hide yes)
				)
			)
			(property "Author" "Antmicro"
				(at 30.48 -20.32 0)
				(effects
					(font
						(size 1.27 1.27)
						(thickness 0.15)
					)
					(justify left bottom)
					(hide yes)
				)
			)
			(property "License" "Apache-2.0"
				(at 30.48 -22.86 0)
				(effects
					(font
						(size 1.27 1.27)
						(thickness 0.15)
					)
					(justify left bottom)
					(hide yes)
				)
			)
			(property "ki_keywords" "SMT, LOGIC, IC"
				(at 0 0 0)
				(effects
					(font
						(size 1.27 1.27)
					)
					(hide yes)
				)
			)
			(symbol "74LVC1T45GM_1_1"
				(rectangle
					(start 2.54 1.27)
					(end 13.97 -6.35)
					(stroke
						(width 0.254)
						(type default)
					)
					(fill
						(type background)
					)
				)
				(polyline
					(pts
						(xy 5.08 -2.54) (xy 6.35 -2.54)
					)
					(stroke
						(width 0.254)
						(type default)
					)
					(fill
						(type background)
					)
				)
				(polyline
					(pts
						(xy 6.35 -2.54) (xy 6.35 -1.905) (xy 7.62 -1.905)
					)
					(stroke
						(width 0.254)
						(type default)
					)
					(fill
						(type background)
					)
				)
				(polyline
					(pts
						(xy 6.35 -2.54) (xy 6.35 -3.175) (xy 7.747 -3.175)
					)
					(stroke
						(width 0.254)
						(type default)
					)
					(fill
						(type background)
					)
				)
				(polyline
					(pts
						(xy 7.62 -1.27) (xy 7.62 -2.54) (xy 8.89 -1.905) (xy 7.62 -1.27)
					)
					(stroke
						(width 0.254)
						(type default)
					)
					(fill
						(type background)
					)
				)
				(polyline
					(pts
						(xy 8.89 -2.54) (xy 8.89 -3.81) (xy 7.62 -3.175) (xy 8.89 -2.54)
					)
					(stroke
						(width 0.254)
						(type default)
					)
					(fill
						(type background)
					)
				)
				(polyline
					(pts
						(xy 10.16 -2.54) (xy 10.16 -1.905) (xy 8.89 -1.905)
					)
					(stroke
						(width 0.254)
						(type default)
					)
					(fill
						(type background)
					)
				)
				(polyline
					(pts
						(xy 10.16 -2.54) (xy 10.16 -3.175) (xy 8.89 -3.175)
					)
					(stroke
						(width 0.254)
						(type default)
					)
					(fill
						(type background)
					)
				)
				(polyline
					(pts
						(xy 11.43 -2.54) (xy 10.16 -2.54)
					)
					(stroke
						(width 0.254)
						(type default)
					)
					(fill
						(type background)
					)
				)
				(pin power_in line
					(at 0 0 0)
					(length 2.54)
					(name "VCCA"
						(effects
							(font
								(size 1.27 1.27)
							)
						)
					)
					(number "1"
						(effects
							(font
								(size 1.27 1.27)
							)
						)
					)
				)
				(pin bidirectional line
					(at 0 -2.54 0)
					(length 2.54)
					(name "A"
						(effects
							(font
								(size 1.27 1.27)
							)
						)
					)
					(number "3"
						(effects
							(font
								(size 1.27 1.27)
							)
						)
					)
				)
				(pin input line
					(at 0 -5.08 0)
					(length 2.54)
					(name "DIR"
						(effects
							(font
								(size 1.27 1.27)
							)
						)
					)
					(number "5"
						(effects
							(font
								(size 1.27 1.27)
							)
						)
					)
				)
				(pin power_in line
					(at 16.51 0 180)
					(length 2.54)
					(name "VCCB"
						(effects
							(font
								(size 1.27 1.27)
							)
						)
					)
					(number "6"
						(effects
							(font
								(size 1.27 1.27)
							)
						)
					)
				)
				(pin bidirectional line
					(at 16.51 -2.54 180)
					(length 2.54)
					(name "B"
						(effects
							(font
								(size 1.27 1.27)
							)
						)
					)
					(number "4"
						(effects
							(font
								(size 1.27 1.27)
							)
						)
					)
				)
				(pin power_in line
					(at 16.51 -5.08 180)
					(length 2.54)
					(name "GND"
						(effects
							(font
								(size 1.27 1.27)
							)
						)
					)
					(number "2"
						(effects
							(font
								(size 1.27 1.27)
							)
						)
					)
				)
			)
		)
	(symbol "antmicroLogicTranslatorsLevelShifters:NTS0102_XSON"
			(exclude_from_sim no)
			(in_bom yes)
			(on_board yes)
			(property "Reference" "U"
				(at 35.56 -2.54 0)
				(effects
					(font
						(size 1.27 1.27)
						(thickness 0.15)
					)
					(justify left bottom)
				)
			)
			(property "Value" "NTS0102_XSON"
				(at 35.56 -7.62 0)
				(effects
					(font
						(size 1.27 1.27)
						(thickness 0.15)
					)
					(justify left bottom)
					(hide yes)
				)
			)
			(property "Footprint" "antmicro-footprints:XSON-8_1x1.95mm_P0.5mm"
				(at 35.56 -10.16 0)
				(effects
					(font
						(size 1.27 1.27)
						(thickness 0.15)
					)
					(justify left bottom)
					(hide yes)
				)
			)
			(property "Datasheet" "http://www.farnell.com/datasheets/1760723.pdf"
				(at 35.56 -12.7 0)
				(effects
					(font
						(size 1.27 1.27)
						(thickness 0.15)
					)
					(justify left bottom)
					(hide yes)
				)
			)
			(property "Description" "Transceiver, 1.65 V to 3.6 V, XSON-8"
				(at 0 0 0)
				(effects
					(font
						(size 1.27 1.27)
					)
					(hide yes)
				)
			)
			(property "MPN" "NTS0102GT"
				(at 35.56 -5.08 0)
				(effects
					(font
						(size 1.27 1.27)
						(thickness 0.15)
					)
					(justify left bottom)
				)
			)
			(property "Manufacturer" "NXP"
				(at 35.56 -15.24 0)
				(effects
					(font
						(size 1.27 1.27)
						(thickness 0.15)
					)
					(justify left bottom)
					(hide yes)
				)
			)
			(property "Author" "Antmicro"
				(at 35.56 -17.78 0)
				(effects
					(font
						(size 1.27 1.27)
						(thickness 0.15)
					)
					(justify left bottom)
					(hide yes)
				)
			)
			(property "License" "Apache-2.0"
				(at 35.56 -20.32 0)
				(effects
					(font
						(size 1.27 1.27)
						(thickness 0.15)
					)
					(justify left bottom)
					(hide yes)
				)
			)
			(property "ki_keywords" "SMT, LEVEL-SHIFTER, IC, LOGIC"
				(at 0 0 0)
				(effects
					(font
						(size 1.27 1.27)
					)
					(hide yes)
				)
			)
			(symbol "NTS0102_XSON_1_1"
				(rectangle
					(start 2.54 2.54)
					(end 17.78 -10.16)
					(stroke
						(width 0.254)
						(type default)
					)
					(fill
						(type background)
					)
				)
				(pin power_in line
					(at 0 0 0)
					(length 2.54)
					(name "VCC_{A}"
						(effects
							(font
								(size 1.27 1.27)
							)
						)
					)
					(number "3"
						(effects
							(font
								(size 1.27 1.27)
							)
						)
					)
				)
				(pin bidirectional line
					(at 0 -2.54 0)
					(length 2.54)
					(name "A_{1}"
						(effects
							(font
								(size 1.27 1.27)
							)
						)
					)
					(number "5"
						(effects
							(font
								(size 1.27 1.27)
							)
						)
					)
				)
				(pin bidirectional line
					(at 0 -5.08 0)
					(length 2.54)
					(name "A_{2}"
						(effects
							(font
								(size 1.27 1.27)
							)
						)
					)
					(number "4"
						(effects
							(font
								(size 1.27 1.27)
							)
						)
					)
				)
				(pin input line
					(at 0 -7.62 0)
					(length 2.54)
					(name "OE"
						(effects
							(font
								(size 1.27 1.27)
							)
						)
					)
					(number "6"
						(effects
							(font
								(size 1.27 1.27)
							)
						)
					)
				)
				(pin power_in line
					(at 20.32 0 180)
					(length 2.54)
					(name "VCC_{B}"
						(effects
							(font
								(size 1.27 1.27)
							)
						)
					)
					(number "7"
						(effects
							(font
								(size 1.27 1.27)
							)
						)
					)
				)
				(pin bidirectional line
					(at 20.32 -2.54 180)
					(length 2.54)
					(name "B_{1}"
						(effects
							(font
								(size 1.27 1.27)
							)
						)
					)
					(number "8"
						(effects
							(font
								(size 1.27 1.27)
							)
						)
					)
				)
				(pin bidirectional line
					(at 20.32 -5.08 180)
					(length 2.54)
					(name "B_{2}"
						(effects
							(font
								(size 1.27 1.27)
							)
						)
					)
					(number "1"
						(effects
							(font
								(size 1.27 1.27)
							)
						)
					)
				)
				(pin power_in line
					(at 20.32 -7.62 180)
					(length 2.54)
					(name "GND"
						(effects
							(font
								(size 1.27 1.27)
							)
						)
					)
					(number "2"
						(effects
							(font
								(size 1.27 1.27)
							)
						)
					)
				)
			)
		)
	(symbol "antmicroMemory:MT25QL01GBBB1EW9-0SIT"
			(exclude_from_sim no)
			(in_bom yes)
			(on_board yes)
			(property "Reference" "U"
				(at 43.18 -2.54 0)
				(effects
					(font
						(size 1.27 1.27)
						(thickness 0.15)
					)
					(justify left bottom)
				)
			)
			(property "Value" "MT25QL01GBBB1EW9-0SIT"
				(at 43.18 -7.62 0)
				(effects
					(font
						(size 1.27 1.27)
						(thickness 0.15)
					)
					(justify left bottom)
					(hide yes)
				)
			)
			(property "Footprint" "antmicro-footprints:W-PDFN-8-1EP_8x6mm_P1.27mm_EP4.3x3.4mm"
				(at 43.18 -10.16 0)
				(effects
					(font
						(size 1.27 1.27)
						(thickness 0.15)
					)
					(justify left bottom)
					(hide yes)
				)
			)
			(property "Datasheet" "https://www.mouser.com/datasheet/2/671/mict_s_a0002234966_1-2290738.pdf"
				(at 43.18 -12.7 0)
				(effects
					(font
						(size 1.27 1.27)
						(thickness 0.15)
					)
					(justify left bottom)
					(hide yes)
				)
			)
			(property "Description" "NOR Flash Serial-SPI 3.3V 1G-bit 1G/512M/256M x 1/2-bit/4-bit 6ns 16-Pin SOP-II T/R"
				(at 0 0 0)
				(effects
					(font
						(size 1.27 1.27)
					)
					(hide yes)
				)
			)
			(property "MPN" "MT25QL01GBBB1EW9-0SIT"
				(at 43.18 -5.08 0)
				(effects
					(font
						(size 1.27 1.27)
						(thickness 0.15)
					)
					(justify left bottom)
				)
			)
			(property "Manufacturer" "Micron Technology"
				(at 43.18 -15.24 0)
				(effects
					(font
						(size 1.27 1.27)
						(thickness 0.15)
					)
					(justify left bottom)
					(hide yes)
				)
			)
			(property "Author" "Antmicro"
				(at 43.18 -17.78 0)
				(effects
					(font
						(size 1.27 1.27)
						(thickness 0.15)
					)
					(justify left bottom)
					(hide yes)
				)
			)
			(property "License" "Apache-2.0"
				(at 43.18 -20.32 0)
				(effects
					(font
						(size 1.27 1.27)
						(thickness 0.15)
					)
					(justify left bottom)
					(hide yes)
				)
			)
			(property "ki_keywords" "IC, MEMORY, SPI, FLASH"
				(at 0 0 0)
				(effects
					(font
						(size 1.27 1.27)
					)
					(hide yes)
				)
			)
			(symbol "MT25QL01GBBB1EW9-0SIT_1_1"
				(rectangle
					(start 2.54 2.54)
					(end 20.32 -10.16)
					(stroke
						(width 0.254)
						(type default)
					)
					(fill
						(type background)
					)
				)
				(pin power_in line
					(at 0 0 0)
					(length 2.54)
					(name "VCC"
						(effects
							(font
								(size 1.27 1.27)
							)
						)
					)
					(number "8"
						(effects
							(font
								(size 1.27 1.27)
							)
						)
					)
				)
				(pin input line
					(at 0 -2.54 0)
					(length 2.54)
					(name "C"
						(effects
							(font
								(size 1.27 1.27)
							)
						)
					)
					(number "6"
						(effects
							(font
								(size 1.27 1.27)
							)
						)
					)
				)
				(pin input line
					(at 0 -5.08 0)
					(length 2.54)
					(name "S#"
						(effects
							(font
								(size 1.27 1.27)
							)
						)
					)
					(number "1"
						(effects
							(font
								(size 1.27 1.27)
							)
						)
					)
				)
				(pin power_in line
					(at 0 -7.62 0)
					(length 2.54)
					(name "GND"
						(effects
							(font
								(size 1.27 1.27)
							)
						)
					)
					(number "4"
						(effects
							(font
								(size 1.27 1.27)
							)
						)
					)
				)
				(pin bidirectional line
					(at 22.86 0 180)
					(length 2.54)
					(name "DQ0"
						(effects
							(font
								(size 1.27 1.27)
							)
						)
					)
					(number "5"
						(effects
							(font
								(size 1.27 1.27)
							)
						)
					)
				)
				(pin bidirectional line
					(at 22.86 -2.54 180)
					(length 2.54)
					(name "DQ1"
						(effects
							(font
								(size 1.27 1.27)
							)
						)
					)
					(number "2"
						(effects
							(font
								(size 1.27 1.27)
							)
						)
					)
				)
				(pin bidirectional line
					(at 22.86 -5.08 180)
					(length 2.54)
					(name "W#/DQ2"
						(effects
							(font
								(size 1.27 1.27)
							)
						)
					)
					(number "3"
						(effects
							(font
								(size 1.27 1.27)
							)
						)
					)
				)
				(pin bidirectional line
					(at 22.86 -7.62 180)
					(length 2.54)
					(name "HOLD#/DQ3"
						(effects
							(font
								(size 1.27 1.27)
							)
						)
					)
					(number "7"
						(effects
							(font
								(size 1.27 1.27)
							)
						)
					)
				)
			)
		)
	(symbol "antmicroMemory:MT53D512M32D2_WFBGA"
			(exclude_from_sim no)
			(in_bom yes)
			(on_board yes)
			(property "Reference" "U"
				(at 48.26 -2.54 0)
				(effects
					(font
						(size 1.27 1.27)
						(thickness 0.15)
					)
					(justify left bottom)
				)
			)
			(property "Value" "MT53D512M32D2_WFBGA"
				(at 48.26 -10.16 0)
				(effects
					(font
						(size 1.27 1.27)
						(thickness 0.15)
					)
					(justify left bottom)
					(hide yes)
				)
			)
			(property "Footprint" "antmicro-footprints:BGA-200_10.0x14.5mm_Layout12x22_P0.80x0.65mm"
				(at 48.26 -12.7 0)
				(effects
					(font
						(size 1.27 1.27)
						(thickness 0.15)
					)
					(justify left bottom)
					(hide yes)
				)
			)
			(property "Datasheet" "https://eu.mouser.com/datasheet/2/671/200b_z11m_non_auto_lpddr4_lpddr4x-3077547.pdf"
				(at 48.26 -15.24 0)
				(effects
					(font
						(size 1.27 1.27)
						(thickness 0.15)
					)
					(justify left bottom)
					(hide yes)
				)
			)
			(property "Description" "LPDDR4 DRAM, 1GX32"
				(at 0 0 0)
				(effects
					(font
						(size 1.27 1.27)
					)
					(hide yes)
				)
			)
			(property "MPN" "MT53D512M32D2DS-053 WT:D TR"
				(at 48.26 -5.08 0)
				(effects
					(font
						(size 1.27 1.27)
						(thickness 0.15)
					)
					(justify left bottom)
				)
			)
			(property "Manufacturer" "Micron Technology"
				(at 48.26 -17.78 0)
				(effects
					(font
						(size 1.27 1.27)
						(thickness 0.15)
					)
					(justify left bottom)
					(hide yes)
				)
			)
			(property "Author" "Antmicro"
				(at 48.26 -22.86 0)
				(effects
					(font
						(size 1.27 1.27)
						(thickness 0.15)
					)
					(justify left bottom)
					(hide yes)
				)
			)
			(property "License" "Apache-2.0"
				(at 48.26 -25.4 0)
				(effects
					(font
						(size 1.27 1.27)
						(thickness 0.15)
					)
					(justify left bottom)
					(hide yes)
				)
			)
			(property "ki_locked" ""
				(at 0 0 0)
				(effects
					(font
						(size 1.27 1.27)
					)
				)
			)
			(property "ki_keywords" "IC, MEMORY, DDR"
				(at 0 0 0)
				(effects
					(font
						(size 1.27 1.27)
					)
					(hide yes)
				)
			)
			(property "ki_fp_filters" "WFBGA200_10X14p5_DS_MRN WFBGA200_10X14p5_DS_MRN-M WFBGA200_10X14p5_DS_MRN-L"
				(at 0 0 0)
				(effects
					(font
						(size 1.27 1.27)
					)
					(hide yes)
				)
			)
			(symbol "MT53D512M32D2_WFBGA_1_1"
				(rectangle
					(start 5.08 2.54)
					(end 29.21 -63.5)
					(stroke
						(width 0.254)
						(type default)
					)
					(fill
						(type background)
					)
				)
				(pin power_in line
					(at 0 0 0)
					(length 5.08)
					(name "VDD2"
						(effects
							(font
								(size 1.27 1.27)
							)
						)
					)
					(number "A4"
						(effects
							(font
								(size 1.27 1.27)
							)
						)
					)
				)
				(pin passive line
					(at 0 0 0)
					(length 5.08)
					(hide yes)
					(name "VDD2"
						(effects
							(font
								(size 1.27 1.27)
							)
						)
					)
					(number "A9"
						(effects
							(font
								(size 1.27 1.27)
							)
						)
					)
				)
				(pin passive line
					(at 0 0 0)
					(length 5.08)
					(hide yes)
					(name "VDD2"
						(effects
							(font
								(size 1.27 1.27)
							)
						)
					)
					(number "F5"
						(effects
							(font
								(size 1.27 1.27)
							)
						)
					)
				)
				(pin passive line
					(at 0 0 0)
					(length 5.08)
					(hide yes)
					(name "VDD2"
						(effects
							(font
								(size 1.27 1.27)
							)
						)
					)
					(number "F8"
						(effects
							(font
								(size 1.27 1.27)
							)
						)
					)
				)
				(pin passive line
					(at 0 0 0)
					(length 5.08)
					(hide yes)
					(name "VDD2"
						(effects
							(font
								(size 1.27 1.27)
							)
						)
					)
					(number "H1"
						(effects
							(font
								(size 1.27 1.27)
							)
						)
					)
				)
				(pin passive line
					(at 0 0 0)
					(length 5.08)
					(hide yes)
					(name "VDD2"
						(effects
							(font
								(size 1.27 1.27)
							)
						)
					)
					(number "H5"
						(effects
							(font
								(size 1.27 1.27)
							)
						)
					)
				)
				(pin passive line
					(at 0 0 0)
					(length 5.08)
					(hide yes)
					(name "VDD2"
						(effects
							(font
								(size 1.27 1.27)
							)
						)
					)
					(number "H8"
						(effects
							(font
								(size 1.27 1.27)
							)
						)
					)
				)
				(pin passive line
					(at 0 0 0)
					(length 5.08)
					(hide yes)
					(name "VDD2"
						(effects
							(font
								(size 1.27 1.27)
							)
						)
					)
					(number "K1"
						(effects
							(font
								(size 1.27 1.27)
							)
						)
					)
				)
				(pin passive line
					(at 0 0 0)
					(length 5.08)
					(hide yes)
					(name "VDD2"
						(effects
							(font
								(size 1.27 1.27)
							)
						)
					)
					(number "K3"
						(effects
							(font
								(size 1.27 1.27)
							)
						)
					)
				)
				(pin passive line
					(at 0 0 0)
					(length 5.08)
					(hide yes)
					(name "VDD2"
						(effects
							(font
								(size 1.27 1.27)
							)
						)
					)
					(number "N1"
						(effects
							(font
								(size 1.27 1.27)
							)
						)
					)
				)
				(pin passive line
					(at 0 0 0)
					(length 5.08)
					(hide yes)
					(name "VDD2"
						(effects
							(font
								(size 1.27 1.27)
							)
						)
					)
					(number "N3"
						(effects
							(font
								(size 1.27 1.27)
							)
						)
					)
				)
				(pin passive line
					(at 0 0 0)
					(length 5.08)
					(hide yes)
					(name "VDD2"
						(effects
							(font
								(size 1.27 1.27)
							)
						)
					)
					(number "R1"
						(effects
							(font
								(size 1.27 1.27)
							)
						)
					)
				)
				(pin passive line
					(at 0 0 0)
					(length 5.08)
					(hide yes)
					(name "VDD2"
						(effects
							(font
								(size 1.27 1.27)
							)
						)
					)
					(number "R5"
						(effects
							(font
								(size 1.27 1.27)
							)
						)
					)
				)
				(pin passive line
					(at 0 0 0)
					(length 5.08)
					(hide yes)
					(name "VDD2"
						(effects
							(font
								(size 1.27 1.27)
							)
						)
					)
					(number "R8"
						(effects
							(font
								(size 1.27 1.27)
							)
						)
					)
				)
				(pin power_in line
					(at 0 -2.54 0)
					(length 5.08)
					(name "VDD1"
						(effects
							(font
								(size 1.27 1.27)
							)
						)
					)
					(number "F1"
						(effects
							(font
								(size 1.27 1.27)
							)
						)
					)
				)
				(pin passive line
					(at 0 -2.54 0)
					(length 5.08)
					(hide yes)
					(name "VDD1"
						(effects
							(font
								(size 1.27 1.27)
							)
						)
					)
					(number "G4"
						(effects
							(font
								(size 1.27 1.27)
							)
						)
					)
				)
				(pin passive line
					(at 0 -2.54 0)
					(length 5.08)
					(hide yes)
					(name "VDD1"
						(effects
							(font
								(size 1.27 1.27)
							)
						)
					)
					(number "G9"
						(effects
							(font
								(size 1.27 1.27)
							)
						)
					)
				)
				(pin passive line
					(at 0 -2.54 0)
					(length 5.08)
					(hide yes)
					(name "VDD1"
						(effects
							(font
								(size 1.27 1.27)
							)
						)
					)
					(number "T4"
						(effects
							(font
								(size 1.27 1.27)
							)
						)
					)
				)
				(pin passive line
					(at 0 -2.54 0)
					(length 5.08)
					(hide yes)
					(name "VDD1"
						(effects
							(font
								(size 1.27 1.27)
							)
						)
					)
					(number "T9"
						(effects
							(font
								(size 1.27 1.27)
							)
						)
					)
				)
				(pin passive line
					(at 0 -2.54 0)
					(length 5.08)
					(hide yes)
					(name "VDD1"
						(effects
							(font
								(size 1.27 1.27)
							)
						)
					)
					(number "U1"
						(effects
							(font
								(size 1.27 1.27)
							)
						)
					)
				)
				(pin power_in line
					(at 0 -5.08 0)
					(length 5.08)
					(name "VDDQ"
						(effects
							(font
								(size 1.27 1.27)
							)
						)
					)
					(number "B3"
						(effects
							(font
								(size 1.27 1.27)
							)
						)
					)
				)
				(pin passive line
					(at 0 -5.08 0)
					(length 5.08)
					(hide yes)
					(name "VDDQ"
						(effects
							(font
								(size 1.27 1.27)
							)
						)
					)
					(number "B5"
						(effects
							(font
								(size 1.27 1.27)
							)
						)
					)
				)
				(pin passive line
					(at 0 -5.08 0)
					(length 5.08)
					(hide yes)
					(name "VDDQ"
						(effects
							(font
								(size 1.27 1.27)
							)
						)
					)
					(number "B8"
						(effects
							(font
								(size 1.27 1.27)
							)
						)
					)
				)
				(pin passive line
					(at 0 -5.08 0)
					(length 5.08)
					(hide yes)
					(name "VDDQ"
						(effects
							(font
								(size 1.27 1.27)
							)
						)
					)
					(number "D1"
						(effects
							(font
								(size 1.27 1.27)
							)
						)
					)
				)
				(pin passive line
					(at 0 -5.08 0)
					(length 5.08)
					(hide yes)
					(name "VDDQ"
						(effects
							(font
								(size 1.27 1.27)
							)
						)
					)
					(number "D5"
						(effects
							(font
								(size 1.27 1.27)
							)
						)
					)
				)
				(pin passive line
					(at 0 -5.08 0)
					(length 5.08)
					(hide yes)
					(name "VDDQ"
						(effects
							(font
								(size 1.27 1.27)
							)
						)
					)
					(number "D8"
						(effects
							(font
								(size 1.27 1.27)
							)
						)
					)
				)
				(pin passive line
					(at 0 -5.08 0)
					(length 5.08)
					(hide yes)
					(name "VDDQ"
						(effects
							(font
								(size 1.27 1.27)
							)
						)
					)
					(number "F3"
						(effects
							(font
								(size 1.27 1.27)
							)
						)
					)
				)
				(pin input line
					(at 0 -7.62 0)
					(length 5.08)
					(name "CA5_A"
						(effects
							(font
								(size 1.27 1.27)
							)
						)
					)
					(number "J11"
						(effects
							(font
								(size 1.27 1.27)
							)
						)
					)
				)
				(pin input line
					(at 0 -10.16 0)
					(length 5.08)
					(name "CA4_A"
						(effects
							(font
								(size 1.27 1.27)
							)
						)
					)
					(number "H11"
						(effects
							(font
								(size 1.27 1.27)
							)
						)
					)
				)
				(pin input line
					(at 0 -12.7 0)
					(length 5.08)
					(name "CA3_A"
						(effects
							(font
								(size 1.27 1.27)
							)
						)
					)
					(number "H10"
						(effects
							(font
								(size 1.27 1.27)
							)
						)
					)
				)
				(pin input line
					(at 0 -15.24 0)
					(length 5.08)
					(name "CA2_A"
						(effects
							(font
								(size 1.27 1.27)
							)
						)
					)
					(number "H9"
						(effects
							(font
								(size 1.27 1.27)
							)
						)
					)
				)
				(pin input line
					(at 0 -17.78 0)
					(length 5.08)
					(name "CA1_A"
						(effects
							(font
								(size 1.27 1.27)
							)
						)
					)
					(number "J2"
						(effects
							(font
								(size 1.27 1.27)
							)
						)
					)
				)
				(pin input line
					(at 0 -20.32 0)
					(length 5.08)
					(name "CA0_A"
						(effects
							(font
								(size 1.27 1.27)
							)
						)
					)
					(number "H2"
						(effects
							(font
								(size 1.27 1.27)
							)
						)
					)
				)
				(pin input line
					(at 0 -22.86 0)
					(length 5.08)
					(name "CS0_A"
						(effects
							(font
								(size 1.27 1.27)
							)
						)
					)
					(number "H4"
						(effects
							(font
								(size 1.27 1.27)
							)
						)
					)
				)
				(pin input line
					(at 0 -25.4 0)
					(length 5.08)
					(name "ODT_CA_A"
						(effects
							(font
								(size 1.27 1.27)
							)
						)
					)
					(number "G2"
						(effects
							(font
								(size 1.27 1.27)
							)
						)
					)
				)
				(pin input line
					(at 0 -27.94 0)
					(length 5.08)
					(name "CKE0_A"
						(effects
							(font
								(size 1.27 1.27)
							)
						)
					)
					(number "J4"
						(effects
							(font
								(size 1.27 1.27)
							)
						)
					)
				)
				(pin input line
					(at 0 -30.48 0)
					(length 5.08)
					(name "CK_c_A"
						(effects
							(font
								(size 1.27 1.27)
							)
						)
					)
					(number "J9"
						(effects
							(font
								(size 1.27 1.27)
							)
						)
					)
				)
				(pin input line
					(at 0 -33.02 0)
					(length 5.08)
					(name "CK_t_A"
						(effects
							(font
								(size 1.27 1.27)
							)
						)
					)
					(number "J8"
						(effects
							(font
								(size 1.27 1.27)
							)
						)
					)
				)
				(pin input line
					(at 0 -35.56 0)
					(length 5.08)
					(name "RESET_n"
						(effects
							(font
								(size 1.27 1.27)
							)
						)
					)
					(number "T11"
						(effects
							(font
								(size 1.27 1.27)
							)
						)
					)
				)
				(pin no_connect line
					(at 0 -53.34 0)
					(length 5.08)
					(name "DNU"
						(effects
							(font
								(size 1.27 1.27)
							)
						)
					)
					(number "A2"
						(effects
							(font
								(size 1.27 1.27)
							)
						)
					)
				)
				(pin no_connect line
					(at 0 -55.88 0)
					(length 5.08)
					(name "DNU"
						(effects
							(font
								(size 1.27 1.27)
							)
						)
					)
					(number "B1"
						(effects
							(font
								(size 1.27 1.27)
							)
						)
					)
				)
				(pin no_connect line
					(at 0 -58.42 0)
					(length 5.08)
					(name "DNU"
						(effects
							(font
								(size 1.27 1.27)
							)
						)
					)
					(number "A1"
						(effects
							(font
								(size 1.27 1.27)
							)
						)
					)
				)
				(pin power_out line
					(at 0 -60.96 0)
					(length 5.08)
					(name "VSS"
						(effects
							(font
								(size 1.27 1.27)
							)
						)
					)
					(number "A3"
						(effects
							(font
								(size 1.27 1.27)
							)
						)
					)
				)
				(pin passive line
					(at 0 -60.96 0)
					(length 5.08)
					(hide yes)
					(name "VSS"
						(effects
							(font
								(size 1.27 1.27)
							)
						)
					)
					(number "C1"
						(effects
							(font
								(size 1.27 1.27)
							)
						)
					)
				)
				(pin passive line
					(at 0 -60.96 0)
					(length 5.08)
					(hide yes)
					(name "VSS"
						(effects
							(font
								(size 1.27 1.27)
							)
						)
					)
					(number "C5"
						(effects
							(font
								(size 1.27 1.27)
							)
						)
					)
				)
				(pin passive line
					(at 0 -60.96 0)
					(length 5.08)
					(hide yes)
					(name "VSS"
						(effects
							(font
								(size 1.27 1.27)
							)
						)
					)
					(number "C8"
						(effects
							(font
								(size 1.27 1.27)
							)
						)
					)
				)
				(pin passive line
					(at 0 -60.96 0)
					(length 5.08)
					(hide yes)
					(name "VSS"
						(effects
							(font
								(size 1.27 1.27)
							)
						)
					)
					(number "D2"
						(effects
							(font
								(size 1.27 1.27)
							)
						)
					)
				)
				(pin passive line
					(at 0 -60.96 0)
					(length 5.08)
					(hide yes)
					(name "VSS"
						(effects
							(font
								(size 1.27 1.27)
							)
						)
					)
					(number "D4"
						(effects
							(font
								(size 1.27 1.27)
							)
						)
					)
				)
				(pin passive line
					(at 0 -60.96 0)
					(length 5.08)
					(hide yes)
					(name "VSS"
						(effects
							(font
								(size 1.27 1.27)
							)
						)
					)
					(number "D9"
						(effects
							(font
								(size 1.27 1.27)
							)
						)
					)
				)
				(pin passive line
					(at 0 -60.96 0)
					(length 5.08)
					(hide yes)
					(name "VSS"
						(effects
							(font
								(size 1.27 1.27)
							)
						)
					)
					(number "E1"
						(effects
							(font
								(size 1.27 1.27)
							)
						)
					)
				)
				(pin passive line
					(at 0 -60.96 0)
					(length 5.08)
					(hide yes)
					(name "VSS"
						(effects
							(font
								(size 1.27 1.27)
							)
						)
					)
					(number "E5"
						(effects
							(font
								(size 1.27 1.27)
							)
						)
					)
				)
				(pin passive line
					(at 0 -60.96 0)
					(length 5.08)
					(hide yes)
					(name "VSS"
						(effects
							(font
								(size 1.27 1.27)
							)
						)
					)
					(number "E8"
						(effects
							(font
								(size 1.27 1.27)
							)
						)
					)
				)
				(pin passive line
					(at 0 -60.96 0)
					(length 5.08)
					(hide yes)
					(name "VSS"
						(effects
							(font
								(size 1.27 1.27)
							)
						)
					)
					(number "G1"
						(effects
							(font
								(size 1.27 1.27)
							)
						)
					)
				)
				(pin passive line
					(at 0 -60.96 0)
					(length 5.08)
					(hide yes)
					(name "VSS"
						(effects
							(font
								(size 1.27 1.27)
							)
						)
					)
					(number "G3"
						(effects
							(font
								(size 1.27 1.27)
							)
						)
					)
				)
				(pin passive line
					(at 0 -60.96 0)
					(length 5.08)
					(hide yes)
					(name "VSS"
						(effects
							(font
								(size 1.27 1.27)
							)
						)
					)
					(number "G5"
						(effects
							(font
								(size 1.27 1.27)
							)
						)
					)
				)
				(pin passive line
					(at 0 -60.96 0)
					(length 5.08)
					(hide yes)
					(name "VSS"
						(effects
							(font
								(size 1.27 1.27)
							)
						)
					)
					(number "G8"
						(effects
							(font
								(size 1.27 1.27)
							)
						)
					)
				)
				(pin passive line
					(at 0 -60.96 0)
					(length 5.08)
					(hide yes)
					(name "VSS"
						(effects
							(font
								(size 1.27 1.27)
							)
						)
					)
					(number "J1"
						(effects
							(font
								(size 1.27 1.27)
							)
						)
					)
				)
				(pin passive line
					(at 0 -60.96 0)
					(length 5.08)
					(hide yes)
					(name "VSS"
						(effects
							(font
								(size 1.27 1.27)
							)
						)
					)
					(number "J3"
						(effects
							(font
								(size 1.27 1.27)
							)
						)
					)
				)
				(pin passive line
					(at 0 -60.96 0)
					(length 5.08)
					(hide yes)
					(name "VSS"
						(effects
							(font
								(size 1.27 1.27)
							)
						)
					)
					(number "K2"
						(effects
							(font
								(size 1.27 1.27)
							)
						)
					)
				)
				(pin passive line
					(at 0 -60.96 0)
					(length 5.08)
					(hide yes)
					(name "VSS"
						(effects
							(font
								(size 1.27 1.27)
							)
						)
					)
					(number "K4"
						(effects
							(font
								(size 1.27 1.27)
							)
						)
					)
				)
				(pin passive line
					(at 0 -60.96 0)
					(length 5.08)
					(hide yes)
					(name "VSS"
						(effects
							(font
								(size 1.27 1.27)
							)
						)
					)
					(number "K9"
						(effects
							(font
								(size 1.27 1.27)
							)
						)
					)
				)
				(pin passive line
					(at 0 -60.96 0)
					(length 5.08)
					(hide yes)
					(name "VSS"
						(effects
							(font
								(size 1.27 1.27)
							)
						)
					)
					(number "N2"
						(effects
							(font
								(size 1.27 1.27)
							)
						)
					)
				)
				(pin passive line
					(at 0 -60.96 0)
					(length 5.08)
					(hide yes)
					(name "VSS"
						(effects
							(font
								(size 1.27 1.27)
							)
						)
					)
					(number "N4"
						(effects
							(font
								(size 1.27 1.27)
							)
						)
					)
				)
				(pin passive line
					(at 0 -60.96 0)
					(length 5.08)
					(hide yes)
					(name "VSS"
						(effects
							(font
								(size 1.27 1.27)
							)
						)
					)
					(number "N9"
						(effects
							(font
								(size 1.27 1.27)
							)
						)
					)
				)
				(pin passive line
					(at 0 -60.96 0)
					(length 5.08)
					(hide yes)
					(name "VSS"
						(effects
							(font
								(size 1.27 1.27)
							)
						)
					)
					(number "P1"
						(effects
							(font
								(size 1.27 1.27)
							)
						)
					)
				)
				(pin passive line
					(at 0 -60.96 0)
					(length 5.08)
					(hide yes)
					(name "VSS"
						(effects
							(font
								(size 1.27 1.27)
							)
						)
					)
					(number "P3"
						(effects
							(font
								(size 1.27 1.27)
							)
						)
					)
				)
				(pin passive line
					(at 0 -60.96 0)
					(length 5.08)
					(hide yes)
					(name "VSS"
						(effects
							(font
								(size 1.27 1.27)
							)
						)
					)
					(number "T1"
						(effects
							(font
								(size 1.27 1.27)
							)
						)
					)
				)
				(pin passive line
					(at 0 -60.96 0)
					(length 5.08)
					(hide yes)
					(name "VSS"
						(effects
							(font
								(size 1.27 1.27)
							)
						)
					)
					(number "T3"
						(effects
							(font
								(size 1.27 1.27)
							)
						)
					)
				)
				(pin passive line
					(at 0 -60.96 0)
					(length 5.08)
					(hide yes)
					(name "VSS"
						(effects
							(font
								(size 1.27 1.27)
							)
						)
					)
					(number "T5"
						(effects
							(font
								(size 1.27 1.27)
							)
						)
					)
				)
				(pin passive line
					(at 0 -60.96 0)
					(length 5.08)
					(hide yes)
					(name "VSS"
						(effects
							(font
								(size 1.27 1.27)
							)
						)
					)
					(number "T8"
						(effects
							(font
								(size 1.27 1.27)
							)
						)
					)
				)
				(pin no_connect line
					(at 5.08 -38.1 0)
					(length 5.08)
					(hide yes)
					(name "NC"
						(effects
							(font
								(size 1.27 1.27)
							)
						)
					)
					(number "K8"
						(effects
							(font
								(size 1.27 1.27)
							)
						)
					)
				)
				(pin no_connect line
					(at 5.08 -40.64 0)
					(length 5.08)
					(hide yes)
					(name "NC"
						(effects
							(font
								(size 1.27 1.27)
							)
						)
					)
					(number "K5"
						(effects
							(font
								(size 1.27 1.27)
							)
						)
					)
				)
				(pin no_connect line
					(at 5.08 -43.18 0)
					(length 5.08)
					(hide yes)
					(name "NC"
						(effects
							(font
								(size 1.27 1.27)
							)
						)
					)
					(number "J5"
						(effects
							(font
								(size 1.27 1.27)
							)
						)
					)
				)
				(pin no_connect line
					(at 5.08 -45.72 0)
					(length 5.08)
					(hide yes)
					(name "NC"
						(effects
							(font
								(size 1.27 1.27)
							)
						)
					)
					(number "H3"
						(effects
							(font
								(size 1.27 1.27)
							)
						)
					)
				)
				(pin no_connect line
					(at 5.08 -48.26 0)
					(length 5.08)
					(hide yes)
					(name "NC"
						(effects
							(font
								(size 1.27 1.27)
							)
						)
					)
					(number "R3"
						(effects
							(font
								(size 1.27 1.27)
							)
						)
					)
				)
				(pin no_connect line
					(at 5.08 -50.8 0)
					(length 5.08)
					(hide yes)
					(name "NC"
						(effects
							(font
								(size 1.27 1.27)
							)
						)
					)
					(number "P5"
						(effects
							(font
								(size 1.27 1.27)
							)
						)
					)
				)
				(pin no_connect line
					(at 29.21 -55.88 180)
					(length 5.08)
					(hide yes)
					(name "NC"
						(effects
							(font
								(size 1.27 1.27)
							)
						)
					)
					(number "N8"
						(effects
							(font
								(size 1.27 1.27)
							)
						)
					)
				)
				(pin no_connect line
					(at 29.21 -58.42 180)
					(length 5.08)
					(hide yes)
					(name "NC"
						(effects
							(font
								(size 1.27 1.27)
							)
						)
					)
					(number "N5"
						(effects
							(font
								(size 1.27 1.27)
							)
						)
					)
				)
				(pin bidirectional line
					(at 34.29 0 180)
					(length 5.08)
					(name "DQS0_c_A"
						(effects
							(font
								(size 1.27 1.27)
							)
						)
					)
					(number "E3"
						(effects
							(font
								(size 1.27 1.27)
							)
						)
					)
				)
				(pin bidirectional line
					(at 34.29 -2.54 180)
					(length 5.08)
					(name "DQS0_t_A"
						(effects
							(font
								(size 1.27 1.27)
							)
						)
					)
					(number "D3"
						(effects
							(font
								(size 1.27 1.27)
							)
						)
					)
				)
				(pin bidirectional line
					(at 34.29 -5.08 180)
					(length 5.08)
					(name "DQS1_c_A"
						(effects
							(font
								(size 1.27 1.27)
							)
						)
					)
					(number "E10"
						(effects
							(font
								(size 1.27 1.27)
							)
						)
					)
				)
				(pin bidirectional line
					(at 34.29 -7.62 180)
					(length 5.08)
					(name "DQS1_t_A"
						(effects
							(font
								(size 1.27 1.27)
							)
						)
					)
					(number "D10"
						(effects
							(font
								(size 1.27 1.27)
							)
						)
					)
				)
				(pin bidirectional line
					(at 34.29 -10.16 180)
					(length 5.08)
					(name "DQ0_A"
						(effects
							(font
								(size 1.27 1.27)
							)
						)
					)
					(number "B2"
						(effects
							(font
								(size 1.27 1.27)
							)
						)
					)
				)
				(pin bidirectional line
					(at 34.29 -12.7 180)
					(length 5.08)
					(name "DQ1_A"
						(effects
							(font
								(size 1.27 1.27)
							)
						)
					)
					(number "C2"
						(effects
							(font
								(size 1.27 1.27)
							)
						)
					)
				)
				(pin bidirectional line
					(at 34.29 -15.24 180)
					(length 5.08)
					(name "DQ2_A"
						(effects
							(font
								(size 1.27 1.27)
							)
						)
					)
					(number "E2"
						(effects
							(font
								(size 1.27 1.27)
							)
						)
					)
				)
				(pin bidirectional line
					(at 34.29 -17.78 180)
					(length 5.08)
					(name "DQ3_A"
						(effects
							(font
								(size 1.27 1.27)
							)
						)
					)
					(number "F2"
						(effects
							(font
								(size 1.27 1.27)
							)
						)
					)
				)
				(pin bidirectional line
					(at 34.29 -20.32 180)
					(length 5.08)
					(name "DQ4_A"
						(effects
							(font
								(size 1.27 1.27)
							)
						)
					)
					(number "F4"
						(effects
							(font
								(size 1.27 1.27)
							)
						)
					)
				)
				(pin bidirectional line
					(at 34.29 -22.86 180)
					(length 5.08)
					(name "DQ5_A"
						(effects
							(font
								(size 1.27 1.27)
							)
						)
					)
					(number "E4"
						(effects
							(font
								(size 1.27 1.27)
							)
						)
					)
				)
				(pin bidirectional line
					(at 34.29 -25.4 180)
					(length 5.08)
					(name "DQ6_A"
						(effects
							(font
								(size 1.27 1.27)
							)
						)
					)
					(number "C4"
						(effects
							(font
								(size 1.27 1.27)
							)
						)
					)
				)
				(pin bidirectional line
					(at 34.29 -27.94 180)
					(length 5.08)
					(name "DQ7_A"
						(effects
							(font
								(size 1.27 1.27)
							)
						)
					)
					(number "B4"
						(effects
							(font
								(size 1.27 1.27)
							)
						)
					)
				)
				(pin bidirectional line
					(at 34.29 -30.48 180)
					(length 5.08)
					(name "DQ8_A"
						(effects
							(font
								(size 1.27 1.27)
							)
						)
					)
					(number "B11"
						(effects
							(font
								(size 1.27 1.27)
							)
						)
					)
				)
				(pin bidirectional line
					(at 34.29 -33.02 180)
					(length 5.08)
					(name "DQ9_A"
						(effects
							(font
								(size 1.27 1.27)
							)
						)
					)
					(number "C11"
						(effects
							(font
								(size 1.27 1.27)
							)
						)
					)
				)
				(pin bidirectional line
					(at 34.29 -35.56 180)
					(length 5.08)
					(name "DQ10_A"
						(effects
							(font
								(size 1.27 1.27)
							)
						)
					)
					(number "E11"
						(effects
							(font
								(size 1.27 1.27)
							)
						)
					)
				)
				(pin bidirectional line
					(at 34.29 -38.1 180)
					(length 5.08)
					(name "DQ11_A"
						(effects
							(font
								(size 1.27 1.27)
							)
						)
					)
					(number "F11"
						(effects
							(font
								(size 1.27 1.27)
							)
						)
					)
				)
				(pin bidirectional line
					(at 34.29 -40.64 180)
					(length 5.08)
					(name "DQ12_A"
						(effects
							(font
								(size 1.27 1.27)
							)
						)
					)
					(number "F9"
						(effects
							(font
								(size 1.27 1.27)
							)
						)
					)
				)
				(pin bidirectional line
					(at 34.29 -43.18 180)
					(length 5.08)
					(name "DQ13_A"
						(effects
							(font
								(size 1.27 1.27)
							)
						)
					)
					(number "E9"
						(effects
							(font
								(size 1.27 1.27)
							)
						)
					)
				)
				(pin bidirectional line
					(at 34.29 -45.72 180)
					(length 5.08)
					(name "DQ14_A"
						(effects
							(font
								(size 1.27 1.27)
							)
						)
					)
					(number "C9"
						(effects
							(font
								(size 1.27 1.27)
							)
						)
					)
				)
				(pin bidirectional line
					(at 34.29 -48.26 180)
					(length 5.08)
					(name "DQ15_A"
						(effects
							(font
								(size 1.27 1.27)
							)
						)
					)
					(number "B9"
						(effects
							(font
								(size 1.27 1.27)
							)
						)
					)
				)
				(pin bidirectional line
					(at 34.29 -50.8 180)
					(length 5.08)
					(name "DMI0_A"
						(effects
							(font
								(size 1.27 1.27)
							)
						)
					)
					(number "C3"
						(effects
							(font
								(size 1.27 1.27)
							)
						)
					)
				)
				(pin bidirectional line
					(at 34.29 -53.34 180)
					(length 5.08)
					(name "DMI1_A"
						(effects
							(font
								(size 1.27 1.27)
							)
						)
					)
					(number "C10"
						(effects
							(font
								(size 1.27 1.27)
							)
						)
					)
				)
				(pin unspecified line
					(at 34.29 -60.96 180)
					(length 5.08)
					(name "ZQ0"
						(effects
							(font
								(size 1.27 1.27)
							)
						)
					)
					(number "A5"
						(effects
							(font
								(size 1.27 1.27)
							)
						)
					)
				)
			)
			(symbol "MT53D512M32D2_WFBGA_2_1"
				(rectangle
					(start 5.08 2.54)
					(end 29.21 -60.96)
					(stroke
						(width 0.254)
						(type default)
					)
					(fill
						(type background)
					)
				)
				(pin power_in line
					(at 0 0 0)
					(length 5.08)
					(name "VDD2"
						(effects
							(font
								(size 1.27 1.27)
							)
						)
					)
					(number "AB4"
						(effects
							(font
								(size 1.27 1.27)
							)
						)
					)
				)
				(pin passive line
					(at 0 0 0)
					(length 5.08)
					(hide yes)
					(name "VDD2"
						(effects
							(font
								(size 1.27 1.27)
							)
						)
					)
					(number "AB9"
						(effects
							(font
								(size 1.27 1.27)
							)
						)
					)
				)
				(pin passive line
					(at 0 0 0)
					(length 5.08)
					(hide yes)
					(name "VDD2"
						(effects
							(font
								(size 1.27 1.27)
							)
						)
					)
					(number "H12"
						(effects
							(font
								(size 1.27 1.27)
							)
						)
					)
				)
				(pin passive line
					(at 0 0 0)
					(length 5.08)
					(hide yes)
					(name "VDD2"
						(effects
							(font
								(size 1.27 1.27)
							)
						)
					)
					(number "K10"
						(effects
							(font
								(size 1.27 1.27)
							)
						)
					)
				)
				(pin passive line
					(at 0 0 0)
					(length 5.08)
					(hide yes)
					(name "VDD2"
						(effects
							(font
								(size 1.27 1.27)
							)
						)
					)
					(number "K12"
						(effects
							(font
								(size 1.27 1.27)
							)
						)
					)
				)
				(pin passive line
					(at 0 0 0)
					(length 5.08)
					(hide yes)
					(name "VDD2"
						(effects
							(font
								(size 1.27 1.27)
							)
						)
					)
					(number "N10"
						(effects
							(font
								(size 1.27 1.27)
							)
						)
					)
				)
				(pin passive line
					(at 0 0 0)
					(length 5.08)
					(hide yes)
					(name "VDD2"
						(effects
							(font
								(size 1.27 1.27)
							)
						)
					)
					(number "N12"
						(effects
							(font
								(size 1.27 1.27)
							)
						)
					)
				)
				(pin passive line
					(at 0 0 0)
					(length 5.08)
					(hide yes)
					(name "VDD2"
						(effects
							(font
								(size 1.27 1.27)
							)
						)
					)
					(number "R12"
						(effects
							(font
								(size 1.27 1.27)
							)
						)
					)
				)
				(pin passive line
					(at 0 0 0)
					(length 5.08)
					(hide yes)
					(name "VDD2"
						(effects
							(font
								(size 1.27 1.27)
							)
						)
					)
					(number "U5"
						(effects
							(font
								(size 1.27 1.27)
							)
						)
					)
				)
				(pin passive line
					(at 0 0 0)
					(length 5.08)
					(hide yes)
					(name "VDD2"
						(effects
							(font
								(size 1.27 1.27)
							)
						)
					)
					(number "U8"
						(effects
							(font
								(size 1.27 1.27)
							)
						)
					)
				)
				(pin power_in line
					(at 0 -2.54 0)
					(length 5.08)
					(name "VDD1"
						(effects
							(font
								(size 1.27 1.27)
							)
						)
					)
					(number "F12"
						(effects
							(font
								(size 1.27 1.27)
							)
						)
					)
				)
				(pin passive line
					(at 0 -2.54 0)
					(length 5.08)
					(hide yes)
					(name "VDD1"
						(effects
							(font
								(size 1.27 1.27)
							)
						)
					)
					(number "U12"
						(effects
							(font
								(size 1.27 1.27)
							)
						)
					)
				)
				(pin power_in line
					(at 0 -5.08 0)
					(length 5.08)
					(name "VDDQ"
						(effects
							(font
								(size 1.27 1.27)
							)
						)
					)
					(number "AA10"
						(effects
							(font
								(size 1.27 1.27)
							)
						)
					)
				)
				(pin passive line
					(at 0 -5.08 0)
					(length 5.08)
					(hide yes)
					(name "VDDQ"
						(effects
							(font
								(size 1.27 1.27)
							)
						)
					)
					(number "AA3"
						(effects
							(font
								(size 1.27 1.27)
							)
						)
					)
				)
				(pin passive line
					(at 0 -5.08 0)
					(length 5.08)
					(hide yes)
					(name "VDDQ"
						(effects
							(font
								(size 1.27 1.27)
							)
						)
					)
					(number "AA5"
						(effects
							(font
								(size 1.27 1.27)
							)
						)
					)
				)
				(pin passive line
					(at 0 -5.08 0)
					(length 5.08)
					(hide yes)
					(name "VDDQ"
						(effects
							(font
								(size 1.27 1.27)
							)
						)
					)
					(number "AA8"
						(effects
							(font
								(size 1.27 1.27)
							)
						)
					)
				)
				(pin passive line
					(at 0 -5.08 0)
					(length 5.08)
					(hide yes)
					(name "VDDQ"
						(effects
							(font
								(size 1.27 1.27)
							)
						)
					)
					(number "B10"
						(effects
							(font
								(size 1.27 1.27)
							)
						)
					)
				)
				(pin passive line
					(at 0 -5.08 0)
					(length 5.08)
					(hide yes)
					(name "VDDQ"
						(effects
							(font
								(size 1.27 1.27)
							)
						)
					)
					(number "D12"
						(effects
							(font
								(size 1.27 1.27)
							)
						)
					)
				)
				(pin passive line
					(at 0 -5.08 0)
					(length 5.08)
					(hide yes)
					(name "VDDQ"
						(effects
							(font
								(size 1.27 1.27)
							)
						)
					)
					(number "F10"
						(effects
							(font
								(size 1.27 1.27)
							)
						)
					)
				)
				(pin passive line
					(at 0 -5.08 0)
					(length 5.08)
					(hide yes)
					(name "VDDQ"
						(effects
							(font
								(size 1.27 1.27)
							)
						)
					)
					(number "U10"
						(effects
							(font
								(size 1.27 1.27)
							)
						)
					)
				)
				(pin passive line
					(at 0 -5.08 0)
					(length 5.08)
					(hide yes)
					(name "VDDQ"
						(effects
							(font
								(size 1.27 1.27)
							)
						)
					)
					(number "U3"
						(effects
							(font
								(size 1.27 1.27)
							)
						)
					)
				)
				(pin passive line
					(at 0 -5.08 0)
					(length 5.08)
					(hide yes)
					(name "VDDQ"
						(effects
							(font
								(size 1.27 1.27)
							)
						)
					)
					(number "W1"
						(effects
							(font
								(size 1.27 1.27)
							)
						)
					)
				)
				(pin passive line
					(at 0 -5.08 0)
					(length 5.08)
					(hide yes)
					(name "VDDQ"
						(effects
							(font
								(size 1.27 1.27)
							)
						)
					)
					(number "W12"
						(effects
							(font
								(size 1.27 1.27)
							)
						)
					)
				)
				(pin passive line
					(at 0 -5.08 0)
					(length 5.08)
					(hide yes)
					(name "VDDQ"
						(effects
							(font
								(size 1.27 1.27)
							)
						)
					)
					(number "W5"
						(effects
							(font
								(size 1.27 1.27)
							)
						)
					)
				)
				(pin passive line
					(at 0 -5.08 0)
					(length 5.08)
					(hide yes)
					(name "VDDQ"
						(effects
							(font
								(size 1.27 1.27)
							)
						)
					)
					(number "W8"
						(effects
							(font
								(size 1.27 1.27)
							)
						)
					)
				)
				(pin input line
					(at 0 -7.62 0)
					(length 5.08)
					(name "CA5_B"
						(effects
							(font
								(size 1.27 1.27)
							)
						)
					)
					(number "P11"
						(effects
							(font
								(size 1.27 1.27)
							)
						)
					)
				)
				(pin input line
					(at 0 -10.16 0)
					(length 5.08)
					(name "CA4_B"
						(effects
							(font
								(size 1.27 1.27)
							)
						)
					)
					(number "R11"
						(effects
							(font
								(size 1.27 1.27)
							)
						)
					)
				)
				(pin input line
					(at 0 -12.7 0)
					(length 5.08)
					(name "CA3_B"
						(effects
							(font
								(size 1.27 1.27)
							)
						)
					)
					(number "R10"
						(effects
							(font
								(size 1.27 1.27)
							)
						)
					)
				)
				(pin input line
					(at 0 -15.24 0)
					(length 5.08)
					(name "CA2_B"
						(effects
							(font
								(size 1.27 1.27)
							)
						)
					)
					(number "R9"
						(effects
							(font
								(size 1.27 1.27)
							)
						)
					)
				)
				(pin input line
					(at 0 -17.78 0)
					(length 5.08)
					(name "CA1_B"
						(effects
							(font
								(size 1.27 1.27)
							)
						)
					)
					(number "P2"
						(effects
							(font
								(size 1.27 1.27)
							)
						)
					)
				)
				(pin input line
					(at 0 -20.32 0)
					(length 5.08)
					(name "CA0_B"
						(effects
							(font
								(size 1.27 1.27)
							)
						)
					)
					(number "R2"
						(effects
							(font
								(size 1.27 1.27)
							)
						)
					)
				)
				(pin input line
					(at 0 -22.86 0)
					(length 5.08)
					(name "CS0_B"
						(effects
							(font
								(size 1.27 1.27)
							)
						)
					)
					(number "R4"
						(effects
							(font
								(size 1.27 1.27)
							)
						)
					)
				)
				(pin input line
					(at 0 -25.4 0)
					(length 5.08)
					(name "ODT_CA_B"
						(effects
							(font
								(size 1.27 1.27)
							)
						)
					)
					(number "T2"
						(effects
							(font
								(size 1.27 1.27)
							)
						)
					)
				)
				(pin input line
					(at 0 -27.94 0)
					(length 5.08)
					(name "CKE0_B"
						(effects
							(font
								(size 1.27 1.27)
							)
						)
					)
					(number "P4"
						(effects
							(font
								(size 1.27 1.27)
							)
						)
					)
				)
				(pin input line
					(at 0 -30.48 0)
					(length 5.08)
					(name "CK_c_B"
						(effects
							(font
								(size 1.27 1.27)
							)
						)
					)
					(number "P9"
						(effects
							(font
								(size 1.27 1.27)
							)
						)
					)
				)
				(pin input line
					(at 0 -33.02 0)
					(length 5.08)
					(name "CK_t_B"
						(effects
							(font
								(size 1.27 1.27)
							)
						)
					)
					(number "P8"
						(effects
							(font
								(size 1.27 1.27)
							)
						)
					)
				)
				(pin no_connect line
					(at 0 -35.56 0)
					(length 5.08)
					(name "DNU"
						(effects
							(font
								(size 1.27 1.27)
							)
						)
					)
					(number "AB12"
						(effects
							(font
								(size 1.27 1.27)
							)
						)
					)
				)
				(pin no_connect line
					(at 0 -38.1 0)
					(length 5.08)
					(name "DNU"
						(effects
							(font
								(size 1.27 1.27)
							)
						)
					)
					(number "AB11"
						(effects
							(font
								(size 1.27 1.27)
							)
						)
					)
				)
				(pin no_connect line
					(at 0 -40.64 0)
					(length 5.08)
					(name "DNU"
						(effects
							(font
								(size 1.27 1.27)
							)
						)
					)
					(number "A11"
						(effects
							(font
								(size 1.27 1.27)
							)
						)
					)
				)
				(pin no_connect line
					(at 0 -43.18 0)
					(length 5.08)
					(name "DNU"
						(effects
							(font
								(size 1.27 1.27)
							)
						)
					)
					(number "AB1"
						(effects
							(font
								(size 1.27 1.27)
							)
						)
					)
				)
				(pin no_connect line
					(at 0 -45.72 0)
					(length 5.08)
					(name "DNU"
						(effects
							(font
								(size 1.27 1.27)
							)
						)
					)
					(number "AA12"
						(effects
							(font
								(size 1.27 1.27)
							)
						)
					)
				)
				(pin no_connect line
					(at 0 -48.26 0)
					(length 5.08)
					(name "DNU"
						(effects
							(font
								(size 1.27 1.27)
							)
						)
					)
					(number "AA1"
						(effects
							(font
								(size 1.27 1.27)
							)
						)
					)
				)
				(pin no_connect line
					(at 0 -50.8 0)
					(length 5.08)
					(name "DNU"
						(effects
							(font
								(size 1.27 1.27)
							)
						)
					)
					(number "A12"
						(effects
							(font
								(size 1.27 1.27)
							)
						)
					)
				)
				(pin no_connect line
					(at 0 -53.34 0)
					(length 5.08)
					(name "DNU"
						(effects
							(font
								(size 1.27 1.27)
							)
						)
					)
					(number "AB2"
						(effects
							(font
								(size 1.27 1.27)
							)
						)
					)
				)
				(pin no_connect line
					(at 0 -55.88 0)
					(length 5.08)
					(name "DNU"
						(effects
							(font
								(size 1.27 1.27)
							)
						)
					)
					(number "B12"
						(effects
							(font
								(size 1.27 1.27)
							)
						)
					)
				)
				(pin power_out line
					(at 0 -58.42 0)
					(length 5.08)
					(name "VSS"
						(effects
							(font
								(size 1.27 1.27)
							)
						)
					)
					(number "A10"
						(effects
							(font
								(size 1.27 1.27)
							)
						)
					)
				)
				(pin passive line
					(at 0 -58.42 0)
					(length 5.08)
					(hide yes)
					(name "VSS"
						(effects
							(font
								(size 1.27 1.27)
							)
						)
					)
					(number "AB10"
						(effects
							(font
								(size 1.27 1.27)
							)
						)
					)
				)
				(pin passive line
					(at 0 -58.42 0)
					(length 5.08)
					(hide yes)
					(name "VSS"
						(effects
							(font
								(size 1.27 1.27)
							)
						)
					)
					(number "AB3"
						(effects
							(font
								(size 1.27 1.27)
							)
						)
					)
				)
				(pin passive line
					(at 0 -58.42 0)
					(length 5.08)
					(hide yes)
					(name "VSS"
						(effects
							(font
								(size 1.27 1.27)
							)
						)
					)
					(number "AB5"
						(effects
							(font
								(size 1.27 1.27)
							)
						)
					)
				)
				(pin passive line
					(at 0 -58.42 0)
					(length 5.08)
					(hide yes)
					(name "VSS"
						(effects
							(font
								(size 1.27 1.27)
							)
						)
					)
					(number "AB8"
						(effects
							(font
								(size 1.27 1.27)
							)
						)
					)
				)
				(pin passive line
					(at 0 -58.42 0)
					(length 5.08)
					(hide yes)
					(name "VSS"
						(effects
							(font
								(size 1.27 1.27)
							)
						)
					)
					(number "C12"
						(effects
							(font
								(size 1.27 1.27)
							)
						)
					)
				)
				(pin passive line
					(at 0 -58.42 0)
					(length 5.08)
					(hide yes)
					(name "VSS"
						(effects
							(font
								(size 1.27 1.27)
							)
						)
					)
					(number "D11"
						(effects
							(font
								(size 1.27 1.27)
							)
						)
					)
				)
				(pin passive line
					(at 0 -58.42 0)
					(length 5.08)
					(hide yes)
					(name "VSS"
						(effects
							(font
								(size 1.27 1.27)
							)
						)
					)
					(number "E12"
						(effects
							(font
								(size 1.27 1.27)
							)
						)
					)
				)
				(pin passive line
					(at 0 -58.42 0)
					(length 5.08)
					(hide yes)
					(name "VSS"
						(effects
							(font
								(size 1.27 1.27)
							)
						)
					)
					(number "G10"
						(effects
							(font
								(size 1.27 1.27)
							)
						)
					)
				)
				(pin passive line
					(at 0 -58.42 0)
					(length 5.08)
					(hide yes)
					(name "VSS"
						(effects
							(font
								(size 1.27 1.27)
							)
						)
					)
					(number "G12"
						(effects
							(font
								(size 1.27 1.27)
							)
						)
					)
				)
				(pin passive line
					(at 0 -58.42 0)
					(length 5.08)
					(hide yes)
					(name "VSS"
						(effects
							(font
								(size 1.27 1.27)
							)
						)
					)
					(number "J10"
						(effects
							(font
								(size 1.27 1.27)
							)
						)
					)
				)
				(pin passive line
					(at 0 -58.42 0)
					(length 5.08)
					(hide yes)
					(name "VSS"
						(effects
							(font
								(size 1.27 1.27)
							)
						)
					)
					(number "J12"
						(effects
							(font
								(size 1.27 1.27)
							)
						)
					)
				)
				(pin passive line
					(at 0 -58.42 0)
					(length 5.08)
					(hide yes)
					(name "VSS"
						(effects
							(font
								(size 1.27 1.27)
							)
						)
					)
					(number "K11"
						(effects
							(font
								(size 1.27 1.27)
							)
						)
					)
				)
				(pin passive line
					(at 0 -58.42 0)
					(length 5.08)
					(hide yes)
					(name "VSS"
						(effects
							(font
								(size 1.27 1.27)
							)
						)
					)
					(number "N11"
						(effects
							(font
								(size 1.27 1.27)
							)
						)
					)
				)
				(pin passive line
					(at 0 -58.42 0)
					(length 5.08)
					(hide yes)
					(name "VSS"
						(effects
							(font
								(size 1.27 1.27)
							)
						)
					)
					(number "P10"
						(effects
							(font
								(size 1.27 1.27)
							)
						)
					)
				)
				(pin passive line
					(at 0 -58.42 0)
					(length 5.08)
					(hide yes)
					(name "VSS"
						(effects
							(font
								(size 1.27 1.27)
							)
						)
					)
					(number "P12"
						(effects
							(font
								(size 1.27 1.27)
							)
						)
					)
				)
				(pin passive line
					(at 0 -58.42 0)
					(length 5.08)
					(hide yes)
					(name "VSS"
						(effects
							(font
								(size 1.27 1.27)
							)
						)
					)
					(number "T10"
						(effects
							(font
								(size 1.27 1.27)
							)
						)
					)
				)
				(pin passive line
					(at 0 -58.42 0)
					(length 5.08)
					(hide yes)
					(name "VSS"
						(effects
							(font
								(size 1.27 1.27)
							)
						)
					)
					(number "T12"
						(effects
							(font
								(size 1.27 1.27)
							)
						)
					)
				)
				(pin passive line
					(at 0 -58.42 0)
					(length 5.08)
					(hide yes)
					(name "VSS"
						(effects
							(font
								(size 1.27 1.27)
							)
						)
					)
					(number "V1"
						(effects
							(font
								(size 1.27 1.27)
							)
						)
					)
				)
				(pin passive line
					(at 0 -58.42 0)
					(length 5.08)
					(hide yes)
					(name "VSS"
						(effects
							(font
								(size 1.27 1.27)
							)
						)
					)
					(number "V12"
						(effects
							(font
								(size 1.27 1.27)
							)
						)
					)
				)
				(pin passive line
					(at 0 -58.42 0)
					(length 5.08)
					(hide yes)
					(name "VSS"
						(effects
							(font
								(size 1.27 1.27)
							)
						)
					)
					(number "V5"
						(effects
							(font
								(size 1.27 1.27)
							)
						)
					)
				)
				(pin passive line
					(at 0 -58.42 0)
					(length 5.08)
					(hide yes)
					(name "VSS"
						(effects
							(font
								(size 1.27 1.27)
							)
						)
					)
					(number "V8"
						(effects
							(font
								(size 1.27 1.27)
							)
						)
					)
				)
				(pin passive line
					(at 0 -58.42 0)
					(length 5.08)
					(hide yes)
					(name "VSS"
						(effects
							(font
								(size 1.27 1.27)
							)
						)
					)
					(number "W11"
						(effects
							(font
								(size 1.27 1.27)
							)
						)
					)
				)
				(pin passive line
					(at 0 -58.42 0)
					(length 5.08)
					(hide yes)
					(name "VSS"
						(effects
							(font
								(size 1.27 1.27)
							)
						)
					)
					(number "W2"
						(effects
							(font
								(size 1.27 1.27)
							)
						)
					)
				)
				(pin passive line
					(at 0 -58.42 0)
					(length 5.08)
					(hide yes)
					(name "VSS"
						(effects
							(font
								(size 1.27 1.27)
							)
						)
					)
					(number "W4"
						(effects
							(font
								(size 1.27 1.27)
							)
						)
					)
				)
				(pin passive line
					(at 0 -58.42 0)
					(length 5.08)
					(hide yes)
					(name "VSS"
						(effects
							(font
								(size 1.27 1.27)
							)
						)
					)
					(number "W9"
						(effects
							(font
								(size 1.27 1.27)
							)
						)
					)
				)
				(pin passive line
					(at 0 -58.42 0)
					(length 5.08)
					(hide yes)
					(name "VSS"
						(effects
							(font
								(size 1.27 1.27)
							)
						)
					)
					(number "Y1"
						(effects
							(font
								(size 1.27 1.27)
							)
						)
					)
				)
				(pin passive line
					(at 0 -58.42 0)
					(length 5.08)
					(hide yes)
					(name "VSS"
						(effects
							(font
								(size 1.27 1.27)
							)
						)
					)
					(number "Y12"
						(effects
							(font
								(size 1.27 1.27)
							)
						)
					)
				)
				(pin passive line
					(at 0 -58.42 0)
					(length 5.08)
					(hide yes)
					(name "VSS"
						(effects
							(font
								(size 1.27 1.27)
							)
						)
					)
					(number "Y5"
						(effects
							(font
								(size 1.27 1.27)
							)
						)
					)
				)
				(pin passive line
					(at 0 -58.42 0)
					(length 5.08)
					(hide yes)
					(name "VSS"
						(effects
							(font
								(size 1.27 1.27)
							)
						)
					)
					(number "Y8"
						(effects
							(font
								(size 1.27 1.27)
							)
						)
					)
				)
				(pin no_connect line
					(at 29.21 -55.88 180)
					(length 5.08)
					(hide yes)
					(name "NC"
						(effects
							(font
								(size 1.27 1.27)
							)
						)
					)
					(number "G11"
						(effects
							(font
								(size 1.27 1.27)
							)
						)
					)
				)
				(pin no_connect line
					(at 29.21 -58.42 180)
					(length 5.08)
					(hide yes)
					(name "NC"
						(effects
							(font
								(size 1.27 1.27)
							)
						)
					)
					(number "A8"
						(effects
							(font
								(size 1.27 1.27)
							)
						)
					)
				)
				(pin bidirectional line
					(at 34.29 0 180)
					(length 5.08)
					(name "DQS0_c_B"
						(effects
							(font
								(size 1.27 1.27)
							)
						)
					)
					(number "V3"
						(effects
							(font
								(size 1.27 1.27)
							)
						)
					)
				)
				(pin bidirectional line
					(at 34.29 -2.54 180)
					(length 5.08)
					(name "DQS0_t_B"
						(effects
							(font
								(size 1.27 1.27)
							)
						)
					)
					(number "W3"
						(effects
							(font
								(size 1.27 1.27)
							)
						)
					)
				)
				(pin bidirectional line
					(at 34.29 -5.08 180)
					(length 5.08)
					(name "DQS1_c_B"
						(effects
							(font
								(size 1.27 1.27)
							)
						)
					)
					(number "V10"
						(effects
							(font
								(size 1.27 1.27)
							)
						)
					)
				)
				(pin bidirectional line
					(at 34.29 -7.62 180)
					(length 5.08)
					(name "DQS1_t_B"
						(effects
							(font
								(size 1.27 1.27)
							)
						)
					)
					(number "W10"
						(effects
							(font
								(size 1.27 1.27)
							)
						)
					)
				)
				(pin bidirectional line
					(at 34.29 -10.16 180)
					(length 5.08)
					(name "DQ0_B"
						(effects
							(font
								(size 1.27 1.27)
							)
						)
					)
					(number "AA2"
						(effects
							(font
								(size 1.27 1.27)
							)
						)
					)
				)
				(pin bidirectional line
					(at 34.29 -12.7 180)
					(length 5.08)
					(name "DQ1_B"
						(effects
							(font
								(size 1.27 1.27)
							)
						)
					)
					(number "Y2"
						(effects
							(font
								(size 1.27 1.27)
							)
						)
					)
				)
				(pin bidirectional line
					(at 34.29 -15.24 180)
					(length 5.08)
					(name "DQ2_B"
						(effects
							(font
								(size 1.27 1.27)
							)
						)
					)
					(number "V2"
						(effects
							(font
								(size 1.27 1.27)
							)
						)
					)
				)
				(pin bidirectional line
					(at 34.29 -17.78 180)
					(length 5.08)
					(name "DQ3_B"
						(effects
							(font
								(size 1.27 1.27)
							)
						)
					)
					(number "U2"
						(effects
							(font
								(size 1.27 1.27)
							)
						)
					)
				)
				(pin bidirectional line
					(at 34.29 -20.32 180)
					(length 5.08)
					(name "DQ4_B"
						(effects
							(font
								(size 1.27 1.27)
							)
						)
					)
					(number "U4"
						(effects
							(font
								(size 1.27 1.27)
							)
						)
					)
				)
				(pin bidirectional line
					(at 34.29 -22.86 180)
					(length 5.08)
					(name "DQ5_B"
						(effects
							(font
								(size 1.27 1.27)
							)
						)
					)
					(number "V4"
						(effects
							(font
								(size 1.27 1.27)
							)
						)
					)
				)
				(pin bidirectional line
					(at 34.29 -25.4 180)
					(length 5.08)
					(name "DQ6_B"
						(effects
							(font
								(size 1.27 1.27)
							)
						)
					)
					(number "Y4"
						(effects
							(font
								(size 1.27 1.27)
							)
						)
					)
				)
				(pin bidirectional line
					(at 34.29 -27.94 180)
					(length 5.08)
					(name "DQ7_B"
						(effects
							(font
								(size 1.27 1.27)
							)
						)
					)
					(number "AA4"
						(effects
							(font
								(size 1.27 1.27)
							)
						)
					)
				)
				(pin bidirectional line
					(at 34.29 -30.48 180)
					(length 5.08)
					(name "DQ8_B"
						(effects
							(font
								(size 1.27 1.27)
							)
						)
					)
					(number "AA11"
						(effects
							(font
								(size 1.27 1.27)
							)
						)
					)
				)
				(pin bidirectional line
					(at 34.29 -33.02 180)
					(length 5.08)
					(name "DQ9_B"
						(effects
							(font
								(size 1.27 1.27)
							)
						)
					)
					(number "Y11"
						(effects
							(font
								(size 1.27 1.27)
							)
						)
					)
				)
				(pin bidirectional line
					(at 34.29 -35.56 180)
					(length 5.08)
					(name "DQ10_B"
						(effects
							(font
								(size 1.27 1.27)
							)
						)
					)
					(number "V11"
						(effects
							(font
								(size 1.27 1.27)
							)
						)
					)
				)
				(pin bidirectional line
					(at 34.29 -38.1 180)
					(length 5.08)
					(name "DQ11_B"
						(effects
							(font
								(size 1.27 1.27)
							)
						)
					)
					(number "U11"
						(effects
							(font
								(size 1.27 1.27)
							)
						)
					)
				)
				(pin bidirectional line
					(at 34.29 -40.64 180)
					(length 5.08)
					(name "DQ12_B"
						(effects
							(font
								(size 1.27 1.27)
							)
						)
					)
					(number "U9"
						(effects
							(font
								(size 1.27 1.27)
							)
						)
					)
				)
				(pin bidirectional line
					(at 34.29 -43.18 180)
					(length 5.08)
					(name "DQ13_B"
						(effects
							(font
								(size 1.27 1.27)
							)
						)
					)
					(number "V9"
						(effects
							(font
								(size 1.27 1.27)
							)
						)
					)
				)
				(pin bidirectional line
					(at 34.29 -45.72 180)
					(length 5.08)
					(name "DQ14_B"
						(effects
							(font
								(size 1.27 1.27)
							)
						)
					)
					(number "Y9"
						(effects
							(font
								(size 1.27 1.27)
							)
						)
					)
				)
				(pin bidirectional line
					(at 34.29 -48.26 180)
					(length 5.08)
					(name "DQ15_B"
						(effects
							(font
								(size 1.27 1.27)
							)
						)
					)
					(number "AA9"
						(effects
							(font
								(size 1.27 1.27)
							)
						)
					)
				)
				(pin bidirectional line
					(at 34.29 -50.8 180)
					(length 5.08)
					(name "DMI0_B"
						(effects
							(font
								(size 1.27 1.27)
							)
						)
					)
					(number "Y3"
						(effects
							(font
								(size 1.27 1.27)
							)
						)
					)
				)
				(pin bidirectional line
					(at 34.29 -53.34 180)
					(length 5.08)
					(name "DMI1_B"
						(effects
							(font
								(size 1.27 1.27)
							)
						)
					)
					(number "Y10"
						(effects
							(font
								(size 1.27 1.27)
							)
						)
					)
				)
			)
		)
	(symbol "antmicroMemory:SDINBDG4-8G"
			(exclude_from_sim no)
			(in_bom yes)
			(on_board yes)
			(property "Reference" "U"
				(at 38.1 -2.54 0)
				(effects
					(font
						(size 1.27 1.27)
						(thickness 0.15)
					)
					(justify left bottom)
				)
			)
			(property "Value" "SDINBDG4-8G"
				(at 38.1 -7.62 0)
				(effects
					(font
						(size 1.27 1.27)
						(thickness 0.15)
					)
					(justify left bottom)
					(hide yes)
				)
			)
			(property "Footprint" "antmicro-footprints:BGA-196-153_11.5x13mm_Layout14x14_P0.5x0.5mm"
				(at 38.1 -10.16 0)
				(effects
					(font
						(size 1.27 1.27)
						(thickness 0.15)
					)
					(justify left bottom)
					(hide yes)
				)
			)
			(property "Datasheet" "https://www.infineon.com/dgdl/Infineon-AN98491_Recommended_PCB_Routing_Guidelines_for_a_Infineon_e.MMC_Memory_Device-ApplicationNotes-v05_00-EN.pdf?fileId=8ac78c8c7d718a49017d71baea97084d"
				(at 38.1 -12.7 0)
				(effects
					(font
						(size 1.27 1.27)
						(thickness 0.15)
					)
					(justify left bottom)
					(hide yes)
				)
			)
			(property "Description" "NAND Flash Serial e-MMC 64G-bit SanDisk iNAND 7250 Industrial emmc"
				(at 0 0 0)
				(effects
					(font
						(size 1.27 1.27)
					)
					(hide yes)
				)
			)
			(property "MPN" "SDINBDG4-8G"
				(at 38.1 -5.08 0)
				(effects
					(font
						(size 1.27 1.27)
						(thickness 0.15)
					)
					(justify left bottom)
				)
			)
			(property "Manufacturer" "SanDisk"
				(at 38.1 -15.24 0)
				(effects
					(font
						(size 1.27 1.27)
						(thickness 0.15)
					)
					(justify left bottom)
					(hide yes)
				)
			)
			(property "Author" "Antmicro"
				(at 38.1 -20.32 0)
				(effects
					(font
						(size 1.27 1.27)
						(thickness 0.15)
					)
					(justify left bottom)
					(hide yes)
				)
			)
			(property "License" "Apache-2.0"
				(at 38.1 -22.86 0)
				(effects
					(font
						(size 1.27 1.27)
						(thickness 0.15)
					)
					(justify left bottom)
					(hide yes)
				)
			)
			(property "ki_locked" ""
				(at 0 0 0)
				(effects
					(font
						(size 1.27 1.27)
					)
				)
			)
			(property "ki_keywords" "IC, MEMORY, SMT, FLASH"
				(at 0 0 0)
				(effects
					(font
						(size 1.27 1.27)
					)
					(hide yes)
				)
			)
			(symbol "SDINBDG4-8G_1_1"
				(rectangle
					(start 3.81 2.54)
					(end 20.32 -35.56)
					(stroke
						(width 0.254)
						(type default)
					)
					(fill
						(type background)
					)
				)
				(pin passive line
					(at 0 0 0)
					(length 3.81)
					(name "VDDI"
						(effects
							(font
								(size 1.27 1.27)
							)
						)
					)
					(number "C2"
						(effects
							(font
								(size 1.27 1.27)
							)
						)
					)
				)
				(pin power_in line
					(at 0 -2.54 0)
					(length 3.81)
					(name "VCC"
						(effects
							(font
								(size 1.27 1.27)
							)
						)
					)
					(number "E6"
						(effects
							(font
								(size 1.27 1.27)
							)
						)
					)
				)
				(pin passive line
					(at 0 -2.54 0)
					(length 3.81)
					(hide yes)
					(name "VCC"
						(effects
							(font
								(size 1.27 1.27)
							)
						)
					)
					(number "F5"
						(effects
							(font
								(size 1.27 1.27)
							)
						)
					)
				)
				(pin passive line
					(at 0 -2.54 0)
					(length 3.81)
					(hide yes)
					(name "VCC"
						(effects
							(font
								(size 1.27 1.27)
							)
						)
					)
					(number "J10"
						(effects
							(font
								(size 1.27 1.27)
							)
						)
					)
				)
				(pin passive line
					(at 0 -2.54 0)
					(length 3.81)
					(hide yes)
					(name "VCC"
						(effects
							(font
								(size 1.27 1.27)
							)
						)
					)
					(number "K9"
						(effects
							(font
								(size 1.27 1.27)
							)
						)
					)
				)
				(pin power_in line
					(at 0 -5.08 0)
					(length 3.81)
					(name "VCCQ"
						(effects
							(font
								(size 1.27 1.27)
							)
						)
					)
					(number "C6"
						(effects
							(font
								(size 1.27 1.27)
							)
						)
					)
				)
				(pin passive line
					(at 0 -5.08 0)
					(length 3.81)
					(hide yes)
					(name "VCCQ"
						(effects
							(font
								(size 1.27 1.27)
							)
						)
					)
					(number "M4"
						(effects
							(font
								(size 1.27 1.27)
							)
						)
					)
				)
				(pin passive line
					(at 0 -5.08 0)
					(length 3.81)
					(hide yes)
					(name "VCCQ"
						(effects
							(font
								(size 1.27 1.27)
							)
						)
					)
					(number "N4"
						(effects
							(font
								(size 1.27 1.27)
							)
						)
					)
				)
				(pin passive line
					(at 0 -5.08 0)
					(length 3.81)
					(hide yes)
					(name "VCCQ"
						(effects
							(font
								(size 1.27 1.27)
							)
						)
					)
					(number "P3"
						(effects
							(font
								(size 1.27 1.27)
							)
						)
					)
				)
				(pin passive line
					(at 0 -5.08 0)
					(length 3.81)
					(hide yes)
					(name "VCCQ"
						(effects
							(font
								(size 1.27 1.27)
							)
						)
					)
					(number "P5"
						(effects
							(font
								(size 1.27 1.27)
							)
						)
					)
				)
				(pin input clock
					(at 0 -7.62 0)
					(length 3.81)
					(name "CLK"
						(effects
							(font
								(size 1.27 1.27)
							)
						)
					)
					(number "M6"
						(effects
							(font
								(size 1.27 1.27)
							)
						)
					)
				)
				(pin input line
					(at 0 -10.16 0)
					(length 3.81)
					(name "RST_N"
						(effects
							(font
								(size 1.27 1.27)
							)
						)
					)
					(number "K5"
						(effects
							(font
								(size 1.27 1.27)
							)
						)
					)
				)
				(pin power_in line
					(at 0 -31.75 0)
					(length 3.81)
					(name "VSSQ"
						(effects
							(font
								(size 1.27 1.27)
							)
						)
					)
					(number "C4"
						(effects
							(font
								(size 1.27 1.27)
							)
						)
					)
				)
				(pin passive line
					(at 0 -31.75 0)
					(length 3.81)
					(hide yes)
					(name "VSSQ"
						(effects
							(font
								(size 1.27 1.27)
							)
						)
					)
					(number "N2"
						(effects
							(font
								(size 1.27 1.27)
							)
						)
					)
				)
				(pin passive line
					(at 0 -31.75 0)
					(length 3.81)
					(hide yes)
					(name "VSSQ"
						(effects
							(font
								(size 1.27 1.27)
							)
						)
					)
					(number "N5"
						(effects
							(font
								(size 1.27 1.27)
							)
						)
					)
				)
				(pin passive line
					(at 0 -31.75 0)
					(length 3.81)
					(hide yes)
					(name "VSSQ"
						(effects
							(font
								(size 1.27 1.27)
							)
						)
					)
					(number "P4"
						(effects
							(font
								(size 1.27 1.27)
							)
						)
					)
				)
				(pin passive line
					(at 0 -31.75 0)
					(length 3.81)
					(hide yes)
					(name "VSSQ"
						(effects
							(font
								(size 1.27 1.27)
							)
						)
					)
					(number "P6"
						(effects
							(font
								(size 1.27 1.27)
							)
						)
					)
				)
				(pin power_in line
					(at 0 -34.29 0)
					(length 3.81)
					(name "VSS"
						(effects
							(font
								(size 1.27 1.27)
							)
						)
					)
					(number "A6"
						(effects
							(font
								(size 1.27 1.27)
							)
						)
					)
				)
				(pin passive line
					(at 0 -34.29 0)
					(length 3.81)
					(hide yes)
					(name "VSS"
						(effects
							(font
								(size 1.27 1.27)
							)
						)
					)
					(number "E7"
						(effects
							(font
								(size 1.27 1.27)
							)
						)
					)
				)
				(pin passive line
					(at 0 -34.29 0)
					(length 3.81)
					(hide yes)
					(name "VSS"
						(effects
							(font
								(size 1.27 1.27)
							)
						)
					)
					(number "G5"
						(effects
							(font
								(size 1.27 1.27)
							)
						)
					)
				)
				(pin passive line
					(at 0 -34.29 0)
					(length 3.81)
					(hide yes)
					(name "VSS"
						(effects
							(font
								(size 1.27 1.27)
							)
						)
					)
					(number "H10"
						(effects
							(font
								(size 1.27 1.27)
							)
						)
					)
				)
				(pin passive line
					(at 0 -34.29 0)
					(length 3.81)
					(hide yes)
					(name "VSS"
						(effects
							(font
								(size 1.27 1.27)
							)
						)
					)
					(number "J5"
						(effects
							(font
								(size 1.27 1.27)
							)
						)
					)
				)
				(pin passive line
					(at 0 -34.29 0)
					(length 3.81)
					(hide yes)
					(name "VSS"
						(effects
							(font
								(size 1.27 1.27)
							)
						)
					)
					(number "K8"
						(effects
							(font
								(size 1.27 1.27)
							)
						)
					)
				)
				(pin no_connect line
					(at 3.81 -13.97 0)
					(length 3.81)
					(hide yes)
					(name "VSF"
						(effects
							(font
								(size 1.27 1.27)
							)
						)
					)
					(number "E10"
						(effects
							(font
								(size 1.27 1.27)
							)
						)
					)
				)
				(pin no_connect line
					(at 3.81 -15.24 0)
					(length 3.81)
					(hide yes)
					(name "VSF"
						(effects
							(font
								(size 1.27 1.27)
							)
						)
					)
					(number "F10"
						(effects
							(font
								(size 1.27 1.27)
							)
						)
					)
				)
				(pin no_connect line
					(at 3.81 -16.51 0)
					(length 3.81)
					(hide yes)
					(name "VSF"
						(effects
							(font
								(size 1.27 1.27)
							)
						)
					)
					(number "E9"
						(effects
							(font
								(size 1.27 1.27)
							)
						)
					)
				)
				(pin no_connect line
					(at 3.81 -17.78 0)
					(length 3.81)
					(hide yes)
					(name "RFU"
						(effects
							(font
								(size 1.27 1.27)
							)
						)
					)
					(number "E5"
						(effects
							(font
								(size 1.27 1.27)
							)
						)
					)
				)
				(pin no_connect line
					(at 3.81 -19.05 0)
					(length 3.81)
					(hide yes)
					(name "RFU"
						(effects
							(font
								(size 1.27 1.27)
							)
						)
					)
					(number "E8"
						(effects
							(font
								(size 1.27 1.27)
							)
						)
					)
				)
				(pin no_connect line
					(at 3.81 -20.32 0)
					(length 3.81)
					(hide yes)
					(name "RFU"
						(effects
							(font
								(size 1.27 1.27)
							)
						)
					)
					(number "G10"
						(effects
							(font
								(size 1.27 1.27)
							)
						)
					)
				)
				(pin no_connect line
					(at 3.81 -21.59 0)
					(length 3.81)
					(hide yes)
					(name "RFU"
						(effects
							(font
								(size 1.27 1.27)
							)
						)
					)
					(number "G3"
						(effects
							(font
								(size 1.27 1.27)
							)
						)
					)
				)
				(pin no_connect line
					(at 3.81 -22.86 0)
					(length 3.81)
					(hide yes)
					(name "RFU"
						(effects
							(font
								(size 1.27 1.27)
							)
						)
					)
					(number "K10"
						(effects
							(font
								(size 1.27 1.27)
							)
						)
					)
				)
				(pin no_connect line
					(at 3.81 -24.13 0)
					(length 3.81)
					(hide yes)
					(name "RFU"
						(effects
							(font
								(size 1.27 1.27)
							)
						)
					)
					(number "K6"
						(effects
							(font
								(size 1.27 1.27)
							)
						)
					)
				)
				(pin no_connect line
					(at 3.81 -25.4 0)
					(length 3.81)
					(hide yes)
					(name "RFU"
						(effects
							(font
								(size 1.27 1.27)
							)
						)
					)
					(number "K7"
						(effects
							(font
								(size 1.27 1.27)
							)
						)
					)
				)
				(pin no_connect line
					(at 3.81 -26.67 0)
					(length 3.81)
					(hide yes)
					(name "RFU"
						(effects
							(font
								(size 1.27 1.27)
							)
						)
					)
					(number "P10"
						(effects
							(font
								(size 1.27 1.27)
							)
						)
					)
				)
				(pin no_connect line
					(at 3.81 -27.94 0)
					(length 3.81)
					(hide yes)
					(name "RFU"
						(effects
							(font
								(size 1.27 1.27)
							)
						)
					)
					(number "P7"
						(effects
							(font
								(size 1.27 1.27)
							)
						)
					)
				)
				(pin no_connect line
					(at 3.81 -29.21 0)
					(length 3.81)
					(hide yes)
					(name "RFU"
						(effects
							(font
								(size 1.27 1.27)
							)
						)
					)
					(number "A7"
						(effects
							(font
								(size 1.27 1.27)
							)
						)
					)
				)
				(pin bidirectional line
					(at 24.13 0 180)
					(length 3.81)
					(name "DAT0"
						(effects
							(font
								(size 1.27 1.27)
							)
						)
					)
					(number "A3"
						(effects
							(font
								(size 1.27 1.27)
							)
						)
					)
				)
				(pin bidirectional line
					(at 24.13 -2.54 180)
					(length 3.81)
					(name "DAT1"
						(effects
							(font
								(size 1.27 1.27)
							)
						)
					)
					(number "A4"
						(effects
							(font
								(size 1.27 1.27)
							)
						)
					)
				)
				(pin bidirectional line
					(at 24.13 -5.08 180)
					(length 3.81)
					(name "DAT2"
						(effects
							(font
								(size 1.27 1.27)
							)
						)
					)
					(number "A5"
						(effects
							(font
								(size 1.27 1.27)
							)
						)
					)
				)
				(pin bidirectional line
					(at 24.13 -7.62 180)
					(length 3.81)
					(name "DAT3"
						(effects
							(font
								(size 1.27 1.27)
							)
						)
					)
					(number "B2"
						(effects
							(font
								(size 1.27 1.27)
							)
						)
					)
				)
				(pin bidirectional line
					(at 24.13 -10.16 180)
					(length 3.81)
					(name "DAT4"
						(effects
							(font
								(size 1.27 1.27)
							)
						)
					)
					(number "B3"
						(effects
							(font
								(size 1.27 1.27)
							)
						)
					)
				)
				(pin bidirectional line
					(at 24.13 -12.7 180)
					(length 3.81)
					(name "DAT5"
						(effects
							(font
								(size 1.27 1.27)
							)
						)
					)
					(number "B4"
						(effects
							(font
								(size 1.27 1.27)
							)
						)
					)
				)
				(pin bidirectional line
					(at 24.13 -15.24 180)
					(length 3.81)
					(name "DAT6"
						(effects
							(font
								(size 1.27 1.27)
							)
						)
					)
					(number "B5"
						(effects
							(font
								(size 1.27 1.27)
							)
						)
					)
				)
				(pin bidirectional line
					(at 24.13 -17.78 180)
					(length 3.81)
					(name "DAT7"
						(effects
							(font
								(size 1.27 1.27)
							)
						)
					)
					(number "B6"
						(effects
							(font
								(size 1.27 1.27)
							)
						)
					)
				)
				(pin bidirectional line
					(at 24.13 -20.32 180)
					(length 3.81)
					(name "CMD"
						(effects
							(font
								(size 1.27 1.27)
							)
						)
					)
					(number "M5"
						(effects
							(font
								(size 1.27 1.27)
							)
						)
					)
				)
				(pin output clock
					(at 24.13 -22.86 180)
					(length 3.81)
					(name "RCLK"
						(effects
							(font
								(size 1.27 1.27)
							)
						)
					)
					(number "H5"
						(effects
							(font
								(size 1.27 1.27)
							)
						)
					)
				)
			)
			(symbol "SDINBDG4-8G_2_1"
				(rectangle
					(start 0 -2.54)
					(end 16.51 -74.93)
					(stroke
						(width 0.254)
						(type default)
					)
					(fill
						(type background)
					)
				)
				(pin free line
					(at 0 -5.08 0)
					(length 3.81)
					(hide yes)
					(name "NC"
						(effects
							(font
								(size 1.27 1.27)
							)
						)
					)
					(number "B1"
						(effects
							(font
								(size 1.27 1.27)
							)
						)
					)
				)
				(pin free line
					(at 0 -6.35 0)
					(length 3.81)
					(hide yes)
					(name "NC"
						(effects
							(font
								(size 1.27 1.27)
							)
						)
					)
					(number "B10"
						(effects
							(font
								(size 1.27 1.27)
							)
						)
					)
				)
				(pin free line
					(at 0 -7.62 0)
					(length 3.81)
					(hide yes)
					(name "NC"
						(effects
							(font
								(size 1.27 1.27)
							)
						)
					)
					(number "B11"
						(effects
							(font
								(size 1.27 1.27)
							)
						)
					)
				)
				(pin free line
					(at 0 -8.89 0)
					(length 3.81)
					(hide yes)
					(name "NC"
						(effects
							(font
								(size 1.27 1.27)
							)
						)
					)
					(number "B12"
						(effects
							(font
								(size 1.27 1.27)
							)
						)
					)
				)
				(pin free line
					(at 0 -10.16 0)
					(length 3.81)
					(hide yes)
					(name "NC"
						(effects
							(font
								(size 1.27 1.27)
							)
						)
					)
					(number "B13"
						(effects
							(font
								(size 1.27 1.27)
							)
						)
					)
				)
				(pin free line
					(at 0 -11.43 0)
					(length 3.81)
					(hide yes)
					(name "NC"
						(effects
							(font
								(size 1.27 1.27)
							)
						)
					)
					(number "B14"
						(effects
							(font
								(size 1.27 1.27)
							)
						)
					)
				)
				(pin free line
					(at 0 -12.7 0)
					(length 3.81)
					(hide yes)
					(name "NC"
						(effects
							(font
								(size 1.27 1.27)
							)
						)
					)
					(number "B7"
						(effects
							(font
								(size 1.27 1.27)
							)
						)
					)
				)
				(pin free line
					(at 0 -13.97 0)
					(length 3.81)
					(hide yes)
					(name "NC"
						(effects
							(font
								(size 1.27 1.27)
							)
						)
					)
					(number "B8"
						(effects
							(font
								(size 1.27 1.27)
							)
						)
					)
				)
				(pin free line
					(at 0 -15.24 0)
					(length 3.81)
					(hide yes)
					(name "NC"
						(effects
							(font
								(size 1.27 1.27)
							)
						)
					)
					(number "B9"
						(effects
							(font
								(size 1.27 1.27)
							)
						)
					)
				)
				(pin free line
					(at 0 -16.51 0)
					(length 3.81)
					(hide yes)
					(name "NC"
						(effects
							(font
								(size 1.27 1.27)
							)
						)
					)
					(number "C1"
						(effects
							(font
								(size 1.27 1.27)
							)
						)
					)
				)
				(pin free line
					(at 0 -17.78 0)
					(length 3.81)
					(hide yes)
					(name "NC"
						(effects
							(font
								(size 1.27 1.27)
							)
						)
					)
					(number "C10"
						(effects
							(font
								(size 1.27 1.27)
							)
						)
					)
				)
				(pin free line
					(at 0 -19.05 0)
					(length 3.81)
					(hide yes)
					(name "NC"
						(effects
							(font
								(size 1.27 1.27)
							)
						)
					)
					(number "C11"
						(effects
							(font
								(size 1.27 1.27)
							)
						)
					)
				)
				(pin free line
					(at 0 -20.32 0)
					(length 3.81)
					(hide yes)
					(name "NC"
						(effects
							(font
								(size 1.27 1.27)
							)
						)
					)
					(number "C12"
						(effects
							(font
								(size 1.27 1.27)
							)
						)
					)
				)
				(pin free line
					(at 0 -21.59 0)
					(length 3.81)
					(hide yes)
					(name "NC"
						(effects
							(font
								(size 1.27 1.27)
							)
						)
					)
					(number "C13"
						(effects
							(font
								(size 1.27 1.27)
							)
						)
					)
				)
				(pin free line
					(at 0 -22.86 0)
					(length 3.81)
					(hide yes)
					(name "NC"
						(effects
							(font
								(size 1.27 1.27)
							)
						)
					)
					(number "C14"
						(effects
							(font
								(size 1.27 1.27)
							)
						)
					)
				)
				(pin free line
					(at 0 -24.13 0)
					(length 3.81)
					(hide yes)
					(name "NC"
						(effects
							(font
								(size 1.27 1.27)
							)
						)
					)
					(number "C3"
						(effects
							(font
								(size 1.27 1.27)
							)
						)
					)
				)
				(pin free line
					(at 0 -25.4 0)
					(length 3.81)
					(hide yes)
					(name "NC"
						(effects
							(font
								(size 1.27 1.27)
							)
						)
					)
					(number "C5"
						(effects
							(font
								(size 1.27 1.27)
							)
						)
					)
				)
				(pin free line
					(at 0 -26.67 0)
					(length 3.81)
					(hide yes)
					(name "NC"
						(effects
							(font
								(size 1.27 1.27)
							)
						)
					)
					(number "C7"
						(effects
							(font
								(size 1.27 1.27)
							)
						)
					)
				)
				(pin free line
					(at 0 -27.94 0)
					(length 3.81)
					(hide yes)
					(name "NC"
						(effects
							(font
								(size 1.27 1.27)
							)
						)
					)
					(number "C8"
						(effects
							(font
								(size 1.27 1.27)
							)
						)
					)
				)
				(pin free line
					(at 0 -29.21 0)
					(length 3.81)
					(hide yes)
					(name "NC"
						(effects
							(font
								(size 1.27 1.27)
							)
						)
					)
					(number "C9"
						(effects
							(font
								(size 1.27 1.27)
							)
						)
					)
				)
				(pin free line
					(at 0 -30.48 0)
					(length 3.81)
					(hide yes)
					(name "NC"
						(effects
							(font
								(size 1.27 1.27)
							)
						)
					)
					(number "D1"
						(effects
							(font
								(size 1.27 1.27)
							)
						)
					)
				)
				(pin free line
					(at 0 -31.75 0)
					(length 3.81)
					(hide yes)
					(name "NC"
						(effects
							(font
								(size 1.27 1.27)
							)
						)
					)
					(number "D12"
						(effects
							(font
								(size 1.27 1.27)
							)
						)
					)
				)
				(pin free line
					(at 0 -33.02 0)
					(length 3.81)
					(hide yes)
					(name "NC"
						(effects
							(font
								(size 1.27 1.27)
							)
						)
					)
					(number "D13"
						(effects
							(font
								(size 1.27 1.27)
							)
						)
					)
				)
				(pin free line
					(at 0 -34.29 0)
					(length 3.81)
					(hide yes)
					(name "NC"
						(effects
							(font
								(size 1.27 1.27)
							)
						)
					)
					(number "D14"
						(effects
							(font
								(size 1.27 1.27)
							)
						)
					)
				)
				(pin free line
					(at 0 -35.56 0)
					(length 3.81)
					(hide yes)
					(name "NC"
						(effects
							(font
								(size 1.27 1.27)
							)
						)
					)
					(number "D2"
						(effects
							(font
								(size 1.27 1.27)
							)
						)
					)
				)
				(pin free line
					(at 0 -36.83 0)
					(length 3.81)
					(hide yes)
					(name "NC"
						(effects
							(font
								(size 1.27 1.27)
							)
						)
					)
					(number "D3"
						(effects
							(font
								(size 1.27 1.27)
							)
						)
					)
				)
				(pin free line
					(at 0 -38.1 0)
					(length 3.81)
					(hide yes)
					(name "NC"
						(effects
							(font
								(size 1.27 1.27)
							)
						)
					)
					(number "D4"
						(effects
							(font
								(size 1.27 1.27)
							)
						)
					)
				)
				(pin free line
					(at 0 -39.37 0)
					(length 3.81)
					(hide yes)
					(name "NC"
						(effects
							(font
								(size 1.27 1.27)
							)
						)
					)
					(number "E1"
						(effects
							(font
								(size 1.27 1.27)
							)
						)
					)
				)
				(pin free line
					(at 0 -40.64 0)
					(length 3.81)
					(hide yes)
					(name "NC"
						(effects
							(font
								(size 1.27 1.27)
							)
						)
					)
					(number "E12"
						(effects
							(font
								(size 1.27 1.27)
							)
						)
					)
				)
				(pin free line
					(at 0 -41.91 0)
					(length 3.81)
					(hide yes)
					(name "NC"
						(effects
							(font
								(size 1.27 1.27)
							)
						)
					)
					(number "E13"
						(effects
							(font
								(size 1.27 1.27)
							)
						)
					)
				)
				(pin free line
					(at 0 -43.18 0)
					(length 3.81)
					(hide yes)
					(name "NC"
						(effects
							(font
								(size 1.27 1.27)
							)
						)
					)
					(number "E14"
						(effects
							(font
								(size 1.27 1.27)
							)
						)
					)
				)
				(pin free line
					(at 0 -44.45 0)
					(length 3.81)
					(hide yes)
					(name "NC"
						(effects
							(font
								(size 1.27 1.27)
							)
						)
					)
					(number "E2"
						(effects
							(font
								(size 1.27 1.27)
							)
						)
					)
				)
				(pin free line
					(at 0 -45.72 0)
					(length 3.81)
					(hide yes)
					(name "NC"
						(effects
							(font
								(size 1.27 1.27)
							)
						)
					)
					(number "E3"
						(effects
							(font
								(size 1.27 1.27)
							)
						)
					)
				)
				(pin free line
					(at 0 -46.99 0)
					(length 3.81)
					(hide yes)
					(name "NC"
						(effects
							(font
								(size 1.27 1.27)
							)
						)
					)
					(number "F1"
						(effects
							(font
								(size 1.27 1.27)
							)
						)
					)
				)
				(pin free line
					(at 0 -48.26 0)
					(length 3.81)
					(hide yes)
					(name "NC"
						(effects
							(font
								(size 1.27 1.27)
							)
						)
					)
					(number "F12"
						(effects
							(font
								(size 1.27 1.27)
							)
						)
					)
				)
				(pin free line
					(at 0 -49.53 0)
					(length 3.81)
					(hide yes)
					(name "NC"
						(effects
							(font
								(size 1.27 1.27)
							)
						)
					)
					(number "F14"
						(effects
							(font
								(size 1.27 1.27)
							)
						)
					)
				)
				(pin free line
					(at 0 -50.8 0)
					(length 3.81)
					(hide yes)
					(name "NC"
						(effects
							(font
								(size 1.27 1.27)
							)
						)
					)
					(number "M9"
						(effects
							(font
								(size 1.27 1.27)
							)
						)
					)
				)
				(pin free line
					(at 0 -52.07 0)
					(length 3.81)
					(hide yes)
					(name "NC"
						(effects
							(font
								(size 1.27 1.27)
							)
						)
					)
					(number "N1"
						(effects
							(font
								(size 1.27 1.27)
							)
						)
					)
				)
				(pin free line
					(at 0 -53.34 0)
					(length 3.81)
					(hide yes)
					(name "NC"
						(effects
							(font
								(size 1.27 1.27)
							)
						)
					)
					(number "N10"
						(effects
							(font
								(size 1.27 1.27)
							)
						)
					)
				)
				(pin free line
					(at 0 -54.61 0)
					(length 3.81)
					(hide yes)
					(name "NC"
						(effects
							(font
								(size 1.27 1.27)
							)
						)
					)
					(number "N11"
						(effects
							(font
								(size 1.27 1.27)
							)
						)
					)
				)
				(pin free line
					(at 0 -55.88 0)
					(length 3.81)
					(hide yes)
					(name "NC"
						(effects
							(font
								(size 1.27 1.27)
							)
						)
					)
					(number "N12"
						(effects
							(font
								(size 1.27 1.27)
							)
						)
					)
				)
				(pin free line
					(at 0 -57.15 0)
					(length 3.81)
					(hide yes)
					(name "NC"
						(effects
							(font
								(size 1.27 1.27)
							)
						)
					)
					(number "N13"
						(effects
							(font
								(size 1.27 1.27)
							)
						)
					)
				)
				(pin free line
					(at 0 -58.42 0)
					(length 3.81)
					(hide yes)
					(name "NC"
						(effects
							(font
								(size 1.27 1.27)
							)
						)
					)
					(number "N14"
						(effects
							(font
								(size 1.27 1.27)
							)
						)
					)
				)
				(pin free line
					(at 0 -59.69 0)
					(length 3.81)
					(hide yes)
					(name "NC"
						(effects
							(font
								(size 1.27 1.27)
							)
						)
					)
					(number "N3"
						(effects
							(font
								(size 1.27 1.27)
							)
						)
					)
				)
				(pin free line
					(at 0 -60.96 0)
					(length 3.81)
					(hide yes)
					(name "NC"
						(effects
							(font
								(size 1.27 1.27)
							)
						)
					)
					(number "N6"
						(effects
							(font
								(size 1.27 1.27)
							)
						)
					)
				)
				(pin free line
					(at 0 -62.23 0)
					(length 3.81)
					(hide yes)
					(name "NC"
						(effects
							(font
								(size 1.27 1.27)
							)
						)
					)
					(number "N7"
						(effects
							(font
								(size 1.27 1.27)
							)
						)
					)
				)
				(pin free line
					(at 0 -63.5 0)
					(length 3.81)
					(hide yes)
					(name "NC"
						(effects
							(font
								(size 1.27 1.27)
							)
						)
					)
					(number "N8"
						(effects
							(font
								(size 1.27 1.27)
							)
						)
					)
				)
				(pin free line
					(at 0 -64.77 0)
					(length 3.81)
					(hide yes)
					(name "NC"
						(effects
							(font
								(size 1.27 1.27)
							)
						)
					)
					(number "N9"
						(effects
							(font
								(size 1.27 1.27)
							)
						)
					)
				)
				(pin free line
					(at 0 -66.04 0)
					(length 3.81)
					(hide yes)
					(name "NC"
						(effects
							(font
								(size 1.27 1.27)
							)
						)
					)
					(number "P1"
						(effects
							(font
								(size 1.27 1.27)
							)
						)
					)
				)
				(pin free line
					(at 0 -67.31 0)
					(length 3.81)
					(hide yes)
					(name "NC"
						(effects
							(font
								(size 1.27 1.27)
							)
						)
					)
					(number "P11"
						(effects
							(font
								(size 1.27 1.27)
							)
						)
					)
				)
				(pin free line
					(at 0 -68.58 0)
					(length 3.81)
					(hide yes)
					(name "NC"
						(effects
							(font
								(size 1.27 1.27)
							)
						)
					)
					(number "P12"
						(effects
							(font
								(size 1.27 1.27)
							)
						)
					)
				)
				(pin free line
					(at 0 -69.85 0)
					(length 3.81)
					(hide yes)
					(name "NC"
						(effects
							(font
								(size 1.27 1.27)
							)
						)
					)
					(number "P13"
						(effects
							(font
								(size 1.27 1.27)
							)
						)
					)
				)
				(pin free line
					(at 0 -71.12 0)
					(length 3.81)
					(hide yes)
					(name "NC"
						(effects
							(font
								(size 1.27 1.27)
							)
						)
					)
					(number "P2"
						(effects
							(font
								(size 1.27 1.27)
							)
						)
					)
				)
				(pin free line
					(at 0 -72.39 0)
					(length 3.81)
					(hide yes)
					(name "NC"
						(effects
							(font
								(size 1.27 1.27)
							)
						)
					)
					(number "P14"
						(effects
							(font
								(size 1.27 1.27)
							)
						)
					)
				)
				(pin free line
					(at 16.51 -5.08 180)
					(length 3.81)
					(hide yes)
					(name "NC"
						(effects
							(font
								(size 1.27 1.27)
							)
						)
					)
					(number "A1"
						(effects
							(font
								(size 1.27 1.27)
							)
						)
					)
				)
				(pin free line
					(at 16.51 -6.35 180)
					(length 3.81)
					(hide yes)
					(name "NC"
						(effects
							(font
								(size 1.27 1.27)
							)
						)
					)
					(number "A10"
						(effects
							(font
								(size 1.27 1.27)
							)
						)
					)
				)
				(pin free line
					(at 16.51 -7.62 180)
					(length 3.81)
					(hide yes)
					(name "NC"
						(effects
							(font
								(size 1.27 1.27)
							)
						)
					)
					(number "A11"
						(effects
							(font
								(size 1.27 1.27)
							)
						)
					)
				)
				(pin free line
					(at 16.51 -8.89 180)
					(length 3.81)
					(hide yes)
					(name "NC"
						(effects
							(font
								(size 1.27 1.27)
							)
						)
					)
					(number "A12"
						(effects
							(font
								(size 1.27 1.27)
							)
						)
					)
				)
				(pin free line
					(at 16.51 -10.16 180)
					(length 3.81)
					(hide yes)
					(name "NC"
						(effects
							(font
								(size 1.27 1.27)
							)
						)
					)
					(number "A14"
						(effects
							(font
								(size 1.27 1.27)
							)
						)
					)
				)
				(pin free line
					(at 16.51 -11.43 180)
					(length 3.81)
					(hide yes)
					(name "NC"
						(effects
							(font
								(size 1.27 1.27)
							)
						)
					)
					(number "A13"
						(effects
							(font
								(size 1.27 1.27)
							)
						)
					)
				)
				(pin free line
					(at 16.51 -12.7 180)
					(length 3.81)
					(hide yes)
					(name "NC"
						(effects
							(font
								(size 1.27 1.27)
							)
						)
					)
					(number "A2"
						(effects
							(font
								(size 1.27 1.27)
							)
						)
					)
				)
				(pin free line
					(at 16.51 -13.97 180)
					(length 3.81)
					(hide yes)
					(name "NC"
						(effects
							(font
								(size 1.27 1.27)
							)
						)
					)
					(number "A8"
						(effects
							(font
								(size 1.27 1.27)
							)
						)
					)
				)
				(pin free line
					(at 16.51 -15.24 180)
					(length 3.81)
					(hide yes)
					(name "NC"
						(effects
							(font
								(size 1.27 1.27)
							)
						)
					)
					(number "A9"
						(effects
							(font
								(size 1.27 1.27)
							)
						)
					)
				)
				(pin free line
					(at 16.51 -16.51 180)
					(length 3.81)
					(hide yes)
					(name "NC"
						(effects
							(font
								(size 1.27 1.27)
							)
						)
					)
					(number "F13"
						(effects
							(font
								(size 1.27 1.27)
							)
						)
					)
				)
				(pin free line
					(at 16.51 -17.78 180)
					(length 3.81)
					(hide yes)
					(name "NC"
						(effects
							(font
								(size 1.27 1.27)
							)
						)
					)
					(number "F2"
						(effects
							(font
								(size 1.27 1.27)
							)
						)
					)
				)
				(pin free line
					(at 16.51 -19.05 180)
					(length 3.81)
					(hide yes)
					(name "NC"
						(effects
							(font
								(size 1.27 1.27)
							)
						)
					)
					(number "F3"
						(effects
							(font
								(size 1.27 1.27)
							)
						)
					)
				)
				(pin free line
					(at 16.51 -20.32 180)
					(length 3.81)
					(hide yes)
					(name "NC"
						(effects
							(font
								(size 1.27 1.27)
							)
						)
					)
					(number "G1"
						(effects
							(font
								(size 1.27 1.27)
							)
						)
					)
				)
				(pin free line
					(at 16.51 -21.59 180)
					(length 3.81)
					(hide yes)
					(name "NC"
						(effects
							(font
								(size 1.27 1.27)
							)
						)
					)
					(number "G12"
						(effects
							(font
								(size 1.27 1.27)
							)
						)
					)
				)
				(pin free line
					(at 16.51 -22.86 180)
					(length 3.81)
					(hide yes)
					(name "NC"
						(effects
							(font
								(size 1.27 1.27)
							)
						)
					)
					(number "G13"
						(effects
							(font
								(size 1.27 1.27)
							)
						)
					)
				)
				(pin free line
					(at 16.51 -24.13 180)
					(length 3.81)
					(hide yes)
					(name "NC"
						(effects
							(font
								(size 1.27 1.27)
							)
						)
					)
					(number "G14"
						(effects
							(font
								(size 1.27 1.27)
							)
						)
					)
				)
				(pin free line
					(at 16.51 -25.4 180)
					(length 3.81)
					(hide yes)
					(name "NC"
						(effects
							(font
								(size 1.27 1.27)
							)
						)
					)
					(number "J1"
						(effects
							(font
								(size 1.27 1.27)
							)
						)
					)
				)
				(pin free line
					(at 16.51 -26.67 180)
					(length 3.81)
					(hide yes)
					(name "NC"
						(effects
							(font
								(size 1.27 1.27)
							)
						)
					)
					(number "G2"
						(effects
							(font
								(size 1.27 1.27)
							)
						)
					)
				)
				(pin free line
					(at 16.51 -27.94 180)
					(length 3.81)
					(hide yes)
					(name "NC"
						(effects
							(font
								(size 1.27 1.27)
							)
						)
					)
					(number "H1"
						(effects
							(font
								(size 1.27 1.27)
							)
						)
					)
				)
				(pin free line
					(at 16.51 -29.21 180)
					(length 3.81)
					(hide yes)
					(name "NC"
						(effects
							(font
								(size 1.27 1.27)
							)
						)
					)
					(number "H12"
						(effects
							(font
								(size 1.27 1.27)
							)
						)
					)
				)
				(pin free line
					(at 16.51 -30.48 180)
					(length 3.81)
					(hide yes)
					(name "NC"
						(effects
							(font
								(size 1.27 1.27)
							)
						)
					)
					(number "H13"
						(effects
							(font
								(size 1.27 1.27)
							)
						)
					)
				)
				(pin free line
					(at 16.51 -31.75 180)
					(length 3.81)
					(hide yes)
					(name "NC"
						(effects
							(font
								(size 1.27 1.27)
							)
						)
					)
					(number "H14"
						(effects
							(font
								(size 1.27 1.27)
							)
						)
					)
				)
				(pin free line
					(at 16.51 -33.02 180)
					(length 3.81)
					(hide yes)
					(name "NC"
						(effects
							(font
								(size 1.27 1.27)
							)
						)
					)
					(number "H2"
						(effects
							(font
								(size 1.27 1.27)
							)
						)
					)
				)
				(pin free line
					(at 16.51 -34.29 180)
					(length 3.81)
					(hide yes)
					(name "NC"
						(effects
							(font
								(size 1.27 1.27)
							)
						)
					)
					(number "H3"
						(effects
							(font
								(size 1.27 1.27)
							)
						)
					)
				)
				(pin free line
					(at 16.51 -35.56 180)
					(length 3.81)
					(hide yes)
					(name "NC"
						(effects
							(font
								(size 1.27 1.27)
							)
						)
					)
					(number "J12"
						(effects
							(font
								(size 1.27 1.27)
							)
						)
					)
				)
				(pin free line
					(at 16.51 -36.83 180)
					(length 3.81)
					(hide yes)
					(name "NC"
						(effects
							(font
								(size 1.27 1.27)
							)
						)
					)
					(number "J13"
						(effects
							(font
								(size 1.27 1.27)
							)
						)
					)
				)
				(pin free line
					(at 16.51 -38.1 180)
					(length 3.81)
					(hide yes)
					(name "NC"
						(effects
							(font
								(size 1.27 1.27)
							)
						)
					)
					(number "J14"
						(effects
							(font
								(size 1.27 1.27)
							)
						)
					)
				)
				(pin free line
					(at 16.51 -39.37 180)
					(length 3.81)
					(hide yes)
					(name "NC"
						(effects
							(font
								(size 1.27 1.27)
							)
						)
					)
					(number "J2"
						(effects
							(font
								(size 1.27 1.27)
							)
						)
					)
				)
				(pin free line
					(at 16.51 -40.64 180)
					(length 3.81)
					(hide yes)
					(name "NC"
						(effects
							(font
								(size 1.27 1.27)
							)
						)
					)
					(number "K1"
						(effects
							(font
								(size 1.27 1.27)
							)
						)
					)
				)
				(pin free line
					(at 16.51 -41.91 180)
					(length 3.81)
					(hide yes)
					(name "NC"
						(effects
							(font
								(size 1.27 1.27)
							)
						)
					)
					(number "J3"
						(effects
							(font
								(size 1.27 1.27)
							)
						)
					)
				)
				(pin free line
					(at 16.51 -43.18 180)
					(length 3.81)
					(hide yes)
					(name "NC"
						(effects
							(font
								(size 1.27 1.27)
							)
						)
					)
					(number "K12"
						(effects
							(font
								(size 1.27 1.27)
							)
						)
					)
				)
				(pin free line
					(at 16.51 -44.45 180)
					(length 3.81)
					(hide yes)
					(name "NC"
						(effects
							(font
								(size 1.27 1.27)
							)
						)
					)
					(number "K13"
						(effects
							(font
								(size 1.27 1.27)
							)
						)
					)
				)
				(pin free line
					(at 16.51 -45.72 180)
					(length 3.81)
					(hide yes)
					(name "NC"
						(effects
							(font
								(size 1.27 1.27)
							)
						)
					)
					(number "K14"
						(effects
							(font
								(size 1.27 1.27)
							)
						)
					)
				)
				(pin free line
					(at 16.51 -46.99 180)
					(length 3.81)
					(hide yes)
					(name "NC"
						(effects
							(font
								(size 1.27 1.27)
							)
						)
					)
					(number "K2"
						(effects
							(font
								(size 1.27 1.27)
							)
						)
					)
				)
				(pin free line
					(at 16.51 -48.26 180)
					(length 3.81)
					(hide yes)
					(name "NC"
						(effects
							(font
								(size 1.27 1.27)
							)
						)
					)
					(number "K3"
						(effects
							(font
								(size 1.27 1.27)
							)
						)
					)
				)
				(pin free line
					(at 16.51 -49.53 180)
					(length 3.81)
					(hide yes)
					(name "NC"
						(effects
							(font
								(size 1.27 1.27)
							)
						)
					)
					(number "L1"
						(effects
							(font
								(size 1.27 1.27)
							)
						)
					)
				)
				(pin free line
					(at 16.51 -50.8 180)
					(length 3.81)
					(hide yes)
					(name "NC"
						(effects
							(font
								(size 1.27 1.27)
							)
						)
					)
					(number "L12"
						(effects
							(font
								(size 1.27 1.27)
							)
						)
					)
				)
				(pin free line
					(at 16.51 -52.07 180)
					(length 3.81)
					(hide yes)
					(name "NC"
						(effects
							(font
								(size 1.27 1.27)
							)
						)
					)
					(number "L13"
						(effects
							(font
								(size 1.27 1.27)
							)
						)
					)
				)
				(pin free line
					(at 16.51 -53.34 180)
					(length 3.81)
					(hide yes)
					(name "NC"
						(effects
							(font
								(size 1.27 1.27)
							)
						)
					)
					(number "L14"
						(effects
							(font
								(size 1.27 1.27)
							)
						)
					)
				)
				(pin free line
					(at 16.51 -54.61 180)
					(length 3.81)
					(hide yes)
					(name "NC"
						(effects
							(font
								(size 1.27 1.27)
							)
						)
					)
					(number "L2"
						(effects
							(font
								(size 1.27 1.27)
							)
						)
					)
				)
				(pin free line
					(at 16.51 -55.88 180)
					(length 3.81)
					(hide yes)
					(name "NC"
						(effects
							(font
								(size 1.27 1.27)
							)
						)
					)
					(number "L3"
						(effects
							(font
								(size 1.27 1.27)
							)
						)
					)
				)
				(pin free line
					(at 16.51 -57.15 180)
					(length 3.81)
					(hide yes)
					(name "NC"
						(effects
							(font
								(size 1.27 1.27)
							)
						)
					)
					(number "M1"
						(effects
							(font
								(size 1.27 1.27)
							)
						)
					)
				)
				(pin free line
					(at 16.51 -58.42 180)
					(length 3.81)
					(hide yes)
					(name "NC"
						(effects
							(font
								(size 1.27 1.27)
							)
						)
					)
					(number "M10"
						(effects
							(font
								(size 1.27 1.27)
							)
						)
					)
				)
				(pin free line
					(at 16.51 -59.69 180)
					(length 3.81)
					(hide yes)
					(name "NC"
						(effects
							(font
								(size 1.27 1.27)
							)
						)
					)
					(number "M11"
						(effects
							(font
								(size 1.27 1.27)
							)
						)
					)
				)
				(pin free line
					(at 16.51 -60.96 180)
					(length 3.81)
					(hide yes)
					(name "NC"
						(effects
							(font
								(size 1.27 1.27)
							)
						)
					)
					(number "M12"
						(effects
							(font
								(size 1.27 1.27)
							)
						)
					)
				)
				(pin free line
					(at 16.51 -62.23 180)
					(length 3.81)
					(hide yes)
					(name "NC"
						(effects
							(font
								(size 1.27 1.27)
							)
						)
					)
					(number "M13"
						(effects
							(font
								(size 1.27 1.27)
							)
						)
					)
				)
				(pin free line
					(at 16.51 -63.5 180)
					(length 3.81)
					(hide yes)
					(name "NC"
						(effects
							(font
								(size 1.27 1.27)
							)
						)
					)
					(number "M14"
						(effects
							(font
								(size 1.27 1.27)
							)
						)
					)
				)
				(pin free line
					(at 16.51 -64.77 180)
					(length 3.81)
					(hide yes)
					(name "NC"
						(effects
							(font
								(size 1.27 1.27)
							)
						)
					)
					(number "M2"
						(effects
							(font
								(size 1.27 1.27)
							)
						)
					)
				)
				(pin free line
					(at 16.51 -66.04 180)
					(length 3.81)
					(hide yes)
					(name "NC"
						(effects
							(font
								(size 1.27 1.27)
							)
						)
					)
					(number "M3"
						(effects
							(font
								(size 1.27 1.27)
							)
						)
					)
				)
				(pin free line
					(at 16.51 -67.31 180)
					(length 3.81)
					(hide yes)
					(name "NC"
						(effects
							(font
								(size 1.27 1.27)
							)
						)
					)
					(number "M7"
						(effects
							(font
								(size 1.27 1.27)
							)
						)
					)
				)
				(pin free line
					(at 16.51 -68.58 180)
					(length 3.81)
					(hide yes)
					(name "NC"
						(effects
							(font
								(size 1.27 1.27)
							)
						)
					)
					(number "M8"
						(effects
							(font
								(size 1.27 1.27)
							)
						)
					)
				)
				(pin free line
					(at 16.51 -69.85 180)
					(length 3.81)
					(hide yes)
					(name "NC"
						(effects
							(font
								(size 1.27 1.27)
							)
						)
					)
					(number "P8"
						(effects
							(font
								(size 1.27 1.27)
							)
						)
					)
				)
				(pin free line
					(at 16.51 -71.12 180)
					(length 3.81)
					(hide yes)
					(name "NC"
						(effects
							(font
								(size 1.27 1.27)
							)
						)
					)
					(number "P9"
						(effects
							(font
								(size 1.27 1.27)
							)
						)
					)
				)
			)
		)
	(symbol "antmicroOscillators:Oscillator_125MHz_DSC1103DI2"
			(exclude_from_sim no)
			(in_bom yes)
			(on_board yes)
			(property "Reference" "Y"
				(at 28.575 -1.905 0)
				(effects
					(font
						(size 1.27 1.27)
						(thickness 0.15)
					)
					(justify left bottom)
				)
			)
			(property "Value" "Oscillator_125MHz_DSC1103DI2"
				(at 28.575 -12.065 0)
				(effects
					(font
						(size 1.27 1.27)
						(thickness 0.15)
					)
					(justify left bottom)
					(hide yes)
				)
			)
			(property "Footprint" "antmicro-footprints:Oscillator_SMD_Microchip_DSC1103DI2_2.5x2x0.85mm"
				(at 28.575 -14.605 0)
				(effects
					(font
						(size 1.27 1.27)
						(thickness 0.15)
					)
					(justify left bottom)
					(hide yes)
				)
			)
			(property "Datasheet" "https://ww1.microchip.com/downloads/aemDocuments/documents/TCG/ProductDocuments/DataSheets/DSC1103-23-Low-Jitter-Precision-LVDS-Oscillator-DS20005745C.pdf"
				(at 28.575 -17.145 0)
				(effects
					(font
						(size 1.27 1.27)
						(thickness 0.15)
					)
					(justify left bottom)
					(hide yes)
				)
			)
			(property "Description" "125 MHz XO (Standard) LVDS Oscillator 3.3V Enable/Disable 6-SMD, No Lead"
				(at 0 0 0)
				(effects
					(font
						(size 1.27 1.27)
					)
					(hide yes)
				)
			)
			(property "Manufacturer" "Microchip Technology"
				(at 28.575 -4.445 0)
				(effects
					(font
						(size 1.27 1.27)
						(thickness 0.15)
					)
					(justify left bottom)
					(hide yes)
				)
			)
			(property "MPN" "DSC1103DI2-125.0000"
				(at 28.575 -6.985 0)
				(effects
					(font
						(size 1.27 1.27)
						(thickness 0.15)
					)
					(justify left bottom)
				)
			)
			(property "Val" "125 MHz"
				(at 28.575 -9.525 0)
				(effects
					(font
						(size 1.27 1.27)
						(thickness 0.15)
					)
					(justify left bottom)
				)
			)
			(property "Author" "Antmicro"
				(at 28.575 -19.685 0)
				(effects
					(font
						(size 1.27 1.27)
						(thickness 0.15)
					)
					(justify left bottom)
					(hide yes)
				)
			)
			(property "License" "Apache-2.0"
				(at 28.575 -22.225 0)
				(effects
					(font
						(size 1.27 1.27)
						(thickness 0.15)
					)
					(justify left bottom)
					(hide yes)
				)
			)
			(property "ki_keywords" "OSCILLATOR, LVDS"
				(at 0 0 0)
				(effects
					(font
						(size 1.27 1.27)
					)
					(hide yes)
				)
			)
			(symbol "Oscillator_125MHz_DSC1103DI2_1_1"
				(rectangle
					(start 2.54 2.54)
					(end 16.51 -7.62)
					(stroke
						(width 0.254)
						(type default)
					)
					(fill
						(type background)
					)
				)
				(polyline
					(pts
						(xy 7.62 -1.27) (xy 8.255 -1.27) (xy 8.255 0) (xy 8.89 0) (xy 8.89 -1.27) (xy 9.525 -1.27) (xy 9.525 0)
						(xy 10.16 0) (xy 10.16 -1.27)
					)
					(stroke
						(width 0.254)
						(type default)
					)
					(fill
						(type background)
					)
				)
				(pin power_in line
					(at 0 0 0)
					(length 2.54)
					(name "VCC"
						(effects
							(font
								(size 1.27 1.27)
							)
						)
					)
					(number "6"
						(effects
							(font
								(size 1.27 1.27)
							)
						)
					)
				)
				(pin input line
					(at 0 -2.54 0)
					(length 2.54)
					(name "EN"
						(effects
							(font
								(size 1.27 1.27)
							)
						)
					)
					(number "1"
						(effects
							(font
								(size 1.27 1.27)
							)
						)
					)
				)
				(pin power_in line
					(at 0 -5.08 0)
					(length 2.54)
					(name "GND"
						(effects
							(font
								(size 1.27 1.27)
							)
						)
					)
					(number "3"
						(effects
							(font
								(size 1.27 1.27)
							)
						)
					)
				)
				(pin no_connect line
					(at 16.51 -5.08 180)
					(length 2.54)
					(hide yes)
					(name "NC"
						(effects
							(font
								(size 1.27 1.27)
							)
						)
					)
					(number "2"
						(effects
							(font
								(size 1.27 1.27)
							)
						)
					)
				)
				(pin output line
					(at 19.05 0 180)
					(length 2.54)
					(name "OUT+"
						(effects
							(font
								(size 1.27 1.27)
							)
						)
					)
					(number "4"
						(effects
							(font
								(size 1.27 1.27)
							)
						)
					)
				)
				(pin output line
					(at 19.05 -2.54 180)
					(length 2.54)
					(name "OUT-"
						(effects
							(font
								(size 1.27 1.27)
							)
						)
					)
					(number "5"
						(effects
							(font
								(size 1.27 1.27)
							)
						)
					)
				)
			)
		)
	(symbol "antmicroOscillators:Oscillator_24MHz_ESC_2016MV"
			(exclude_from_sim no)
			(in_bom yes)
			(on_board yes)
			(property "Reference" "Y"
				(at 17.78 -5.08 0)
				(effects
					(font
						(size 1.27 1.27)
						(thickness 0.15)
					)
					(justify left bottom)
				)
			)
			(property "Value" "Oscillator_24MHz_ESC_2016MV"
				(at 17.78 -15.24 0)
				(effects
					(font
						(size 1.27 1.27)
						(thickness 0.15)
					)
					(justify left bottom)
					(hide yes)
				)
			)
			(property "Footprint" "antmicro-footprints:Oscillator_SMD_ECS_2016MV_2x1.6x0.85mm"
				(at 17.78 -17.78 0)
				(effects
					(font
						(size 1.27 1.27)
						(thickness 0.15)
					)
					(justify left bottom)
					(hide yes)
				)
			)
			(property "Datasheet" "https://ecsxtal.com/store/pdf/ECS-2016MV.pdf"
				(at 17.78 -20.32 0)
				(effects
					(font
						(size 1.27 1.27)
						(thickness 0.15)
					)
					(justify left bottom)
					(hide yes)
				)
			)
			(property "Description" "Oscillator, 24 MHz XO (Standard) CMOS 1.6V ~ 3.6V Enable/Disable 4-SMD, No Lead"
				(at 0 0 0)
				(effects
					(font
						(size 1.27 1.27)
					)
					(hide yes)
				)
			)
			(property "MPN" "ECS-2016MV-240-CN-TR"
				(at 17.78 -7.62 0)
				(effects
					(font
						(size 1.27 1.27)
						(thickness 0.15)
					)
					(justify left bottom)
				)
			)
			(property "Manufacturer" "ECS Inc. International"
				(at 17.78 -10.16 0)
				(effects
					(font
						(size 1.27 1.27)
						(thickness 0.15)
					)
					(justify left bottom)
					(hide yes)
				)
			)
			(property "Val" "24 MHz"
				(at 17.78 -12.7 0)
				(effects
					(font
						(size 1.27 1.27)
						(thickness 0.15)
					)
					(justify left bottom)
				)
			)
			(property "Author" "Antmicro"
				(at 17.78 -22.86 0)
				(effects
					(font
						(size 1.27 1.27)
						(thickness 0.15)
					)
					(justify left bottom)
					(hide yes)
				)
			)
			(property "License" "Apache-2.0"
				(at 17.78 -25.4 0)
				(effects
					(font
						(size 1.27 1.27)
						(thickness 0.15)
					)
					(justify left bottom)
					(hide yes)
				)
			)
			(property "ki_keywords" "OSCILLATOR"
				(at 0 0 0)
				(effects
					(font
						(size 1.27 1.27)
					)
					(hide yes)
				)
			)
			(symbol "Oscillator_24MHz_ESC_2016MV_1_1"
				(rectangle
					(start 2.54 2.54)
					(end 16.51 -7.62)
					(stroke
						(width 0.254)
						(type default)
					)
					(fill
						(type background)
					)
				)
				(polyline
					(pts
						(xy 7.62 -1.27) (xy 8.255 -1.27) (xy 8.255 0) (xy 8.89 0) (xy 8.89 -1.27) (xy 9.525 -1.27) (xy 9.525 0)
						(xy 10.16 0) (xy 10.16 -1.27)
					)
					(stroke
						(width 0.254)
						(type default)
					)
					(fill
						(type background)
					)
				)
				(pin power_in line
					(at 0 0 0)
					(length 2.54)
					(name "VDD"
						(effects
							(font
								(size 1.27 1.27)
							)
						)
					)
					(number "4"
						(effects
							(font
								(size 1.27 1.27)
							)
						)
					)
				)
				(pin input line
					(at 0 -2.54 0)
					(length 2.54)
					(name "EN"
						(effects
							(font
								(size 1.27 1.27)
							)
						)
					)
					(number "1"
						(effects
							(font
								(size 1.27 1.27)
							)
						)
					)
				)
				(pin power_in line
					(at 0 -5.08 0)
					(length 2.54)
					(name "GND"
						(effects
							(font
								(size 1.27 1.27)
							)
						)
					)
					(number "2"
						(effects
							(font
								(size 1.27 1.27)
							)
						)
					)
				)
				(pin output line
					(at 19.05 0 180)
					(length 2.54)
					(name "OUT"
						(effects
							(font
								(size 1.27 1.27)
							)
						)
					)
					(number "3"
						(effects
							(font
								(size 1.27 1.27)
							)
						)
					)
				)
			)
		)
	(symbol "antmicroOscillators:Oscillator_25MHz_ESC_2016MV"
			(exclude_from_sim no)
			(in_bom yes)
			(on_board yes)
			(property "Reference" "Y"
				(at 25.4 -2.54 0)
				(effects
					(font
						(size 1.27 1.27)
						(thickness 0.15)
					)
					(justify left bottom)
				)
			)
			(property "Value" "Oscillator_25MHz_ESC_2016MV"
				(at 25.4 -12.7 0)
				(effects
					(font
						(size 1.27 1.27)
						(thickness 0.15)
					)
					(justify left bottom)
					(hide yes)
				)
			)
			(property "Footprint" "antmicro-footprints:Oscillator_SMD_ECS_2016MV_2x1.6x0.85mm"
				(at 25.4 -15.24 0)
				(effects
					(font
						(size 1.27 1.27)
						(thickness 0.15)
					)
					(justify left bottom)
					(hide yes)
				)
			)
			(property "Datasheet" "https://ecsxtal.com/store/pdf/ECS-2016MV.pdf"
				(at 25.4 -17.78 0)
				(effects
					(font
						(size 1.27 1.27)
						(thickness 0.15)
					)
					(justify left bottom)
					(hide yes)
				)
			)
			(property "Description" "Oscillator, 25 MHz, HCMOS, SMD, 2mm x 1.6mm, MultiVolt ECS-2016MV Series"
				(at 0 0 0)
				(effects
					(font
						(size 1.27 1.27)
					)
					(hide yes)
				)
			)
			(property "MPN" "ECS-2016MV-250-CN-TR"
				(at 25.4 -5.08 0)
				(effects
					(font
						(size 1.27 1.27)
						(thickness 0.15)
					)
					(justify left bottom)
				)
			)
			(property "Manufacturer" "ECS Inc. International"
				(at 25.4 -7.62 0)
				(effects
					(font
						(size 1.27 1.27)
						(thickness 0.15)
					)
					(justify left bottom)
					(hide yes)
				)
			)
			(property "Val" "25 MHz"
				(at 25.4 -10.16 0)
				(effects
					(font
						(size 1.27 1.27)
						(thickness 0.15)
					)
					(justify left bottom)
				)
			)
			(property "Author" "Antmicro"
				(at 25.4 -20.32 0)
				(effects
					(font
						(size 1.27 1.27)
						(thickness 0.15)
					)
					(justify left bottom)
					(hide yes)
				)
			)
			(property "License" "Apache-2.0"
				(at 25.4 -22.86 0)
				(effects
					(font
						(size 1.27 1.27)
						(thickness 0.15)
					)
					(justify left bottom)
					(hide yes)
				)
			)
			(property "ki_keywords" "OSCILLATOR"
				(at 0 0 0)
				(effects
					(font
						(size 1.27 1.27)
					)
					(hide yes)
				)
			)
			(symbol "Oscillator_25MHz_ESC_2016MV_1_1"
				(rectangle
					(start 2.54 2.54)
					(end 16.51 -7.62)
					(stroke
						(width 0.254)
						(type default)
					)
					(fill
						(type background)
					)
				)
				(polyline
					(pts
						(xy 7.62 -1.27) (xy 8.255 -1.27) (xy 8.255 0) (xy 8.89 0) (xy 8.89 -1.27) (xy 9.525 -1.27) (xy 9.525 0)
						(xy 10.16 0) (xy 10.16 -1.27)
					)
					(stroke
						(width 0.254)
						(type default)
					)
					(fill
						(type background)
					)
				)
				(pin power_in line
					(at 0 0 0)
					(length 2.54)
					(name "VDD"
						(effects
							(font
								(size 1.27 1.27)
							)
						)
					)
					(number "4"
						(effects
							(font
								(size 1.27 1.27)
							)
						)
					)
				)
				(pin input line
					(at 0 -2.54 0)
					(length 2.54)
					(name "EN"
						(effects
							(font
								(size 1.27 1.27)
							)
						)
					)
					(number "1"
						(effects
							(font
								(size 1.27 1.27)
							)
						)
					)
				)
				(pin power_in line
					(at 0 -5.08 0)
					(length 2.54)
					(name "GND"
						(effects
							(font
								(size 1.27 1.27)
							)
						)
					)
					(number "2"
						(effects
							(font
								(size 1.27 1.27)
							)
						)
					)
				)
				(pin output line
					(at 19.05 0 180)
					(length 2.54)
					(name "OUT"
						(effects
							(font
								(size 1.27 1.27)
							)
						)
					)
					(number "3"
						(effects
							(font
								(size 1.27 1.27)
							)
						)
					)
				)
			)
		)
	(symbol "antmicroOscillators:Oscillator_32.768kHz_ECS_2520MV"
			(exclude_from_sim no)
			(in_bom yes)
			(on_board yes)
			(property "Reference" "Y"
				(at 26.035 -2.54 0)
				(effects
					(font
						(size 1.27 1.27)
						(thickness 0.15)
					)
					(justify left bottom)
				)
			)
			(property "Value" "Oscillator_32.768kHz_ECS_2520MV"
				(at 26.035 -12.7 0)
				(effects
					(font
						(size 1.27 1.27)
						(thickness 0.15)
					)
					(justify left bottom)
					(hide yes)
				)
			)
			(property "Footprint" "antmicro-footprints:Oscillator_SMD_ECS_2520MV_2.5x2mm"
				(at 26.035 -15.24 0)
				(effects
					(font
						(size 1.27 1.27)
						(thickness 0.15)
					)
					(justify left bottom)
					(hide yes)
				)
			)
			(property "Datasheet" "https://ecsxtal.com/store/pdf/ECS-327MVATX.pdf"
				(at 26.035 -17.78 0)
				(effects
					(font
						(size 1.27 1.27)
						(thickness 0.15)
					)
					(justify left bottom)
					(hide yes)
				)
			)
			(property "Description" "32.768 kHz XO (Standard) CMOS Oscillator 1.6V ~ 3.6V Enable/Disable 4-SMD, No Lead"
				(at 0 0 0)
				(effects
					(font
						(size 1.27 1.27)
					)
					(hide yes)
				)
			)
			(property "Manufacturer" "ECS Inc. International"
				(at 26.035 -7.62 0)
				(effects
					(font
						(size 1.27 1.27)
						(thickness 0.15)
					)
					(justify left bottom)
					(hide yes)
				)
			)
			(property "MPN" "ECS-327MVATX-2-CN-TR3"
				(at 26.035 -5.08 0)
				(effects
					(font
						(size 1.27 1.27)
						(thickness 0.15)
					)
					(justify left bottom)
				)
			)
			(property "Val" "32.768 kHz"
				(at 26.035 -10.16 0)
				(effects
					(font
						(size 1.27 1.27)
						(thickness 0.15)
					)
					(justify left bottom)
				)
			)
			(property "Author" "Antmicro"
				(at 26.035 -20.32 0)
				(effects
					(font
						(size 1.27 1.27)
						(thickness 0.15)
					)
					(justify left bottom)
					(hide yes)
				)
			)
			(property "License" "Apache-2.0"
				(at 26.035 -22.86 0)
				(effects
					(font
						(size 1.27 1.27)
						(thickness 0.15)
					)
					(justify left bottom)
					(hide yes)
				)
			)
			(property "ki_keywords" "OSCILLATOR"
				(at 0 0 0)
				(effects
					(font
						(size 1.27 1.27)
					)
					(hide yes)
				)
			)
			(symbol "Oscillator_32.768kHz_ECS_2520MV_1_1"
				(rectangle
					(start 2.54 2.54)
					(end 16.51 -7.62)
					(stroke
						(width 0.254)
						(type default)
					)
					(fill
						(type background)
					)
				)
				(polyline
					(pts
						(xy 7.62 -1.27) (xy 8.255 -1.27) (xy 8.255 0) (xy 8.89 0) (xy 8.89 -1.27) (xy 9.525 -1.27) (xy 9.525 0)
						(xy 10.16 0) (xy 10.16 -1.27)
					)
					(stroke
						(width 0.254)
						(type default)
					)
					(fill
						(type background)
					)
				)
				(pin power_in line
					(at 0 0 0)
					(length 2.54)
					(name "VDD"
						(effects
							(font
								(size 1.27 1.27)
							)
						)
					)
					(number "4"
						(effects
							(font
								(size 1.27 1.27)
							)
						)
					)
				)
				(pin input line
					(at 0 -2.54 0)
					(length 2.54)
					(name "EN"
						(effects
							(font
								(size 1.27 1.27)
							)
						)
					)
					(number "1"
						(effects
							(font
								(size 1.27 1.27)
							)
						)
					)
				)
				(pin power_in line
					(at 0 -5.08 0)
					(length 2.54)
					(name "GND"
						(effects
							(font
								(size 1.27 1.27)
							)
						)
					)
					(number "2"
						(effects
							(font
								(size 1.27 1.27)
							)
						)
					)
				)
				(pin output line
					(at 19.05 0 180)
					(length 2.54)
					(name "OUT"
						(effects
							(font
								(size 1.27 1.27)
							)
						)
					)
					(number "3"
						(effects
							(font
								(size 1.27 1.27)
							)
						)
					)
				)
			)
		)
	(symbol "antmicroOscillators:Oscillator_50MHz_ECS_1612MV"
			(exclude_from_sim no)
			(in_bom yes)
			(on_board yes)
			(property "Reference" "Y"
				(at 26.67 -4.445 0)
				(effects
					(font
						(size 1.27 1.27)
						(thickness 0.15)
					)
					(justify left bottom)
				)
			)
			(property "Value" "Oscillator_50MHz_ECS_1612MV"
				(at 26.67 -12.065 0)
				(effects
					(font
						(size 1.27 1.27)
						(thickness 0.15)
					)
					(justify left bottom)
					(hide yes)
				)
			)
			(property "Footprint" "antmicro-footprints:Oscillator_SMD_ECS_1612MV_1.6x1.2x0.6mm"
				(at 26.67 -14.605 0)
				(effects
					(font
						(size 1.27 1.27)
						(thickness 0.15)
					)
					(justify left bottom)
					(hide yes)
				)
			)
			(property "Datasheet" "https://ecsxtal.com/store/pdf/ECS-1612MV.pdf"
				(at 26.67 -17.145 0)
				(effects
					(font
						(size 1.27 1.27)
						(thickness 0.15)
					)
					(justify left bottom)
					(hide yes)
				)
			)
			(property "Description" "50 MHz XO (Standard) CMOS Oscillator 1.6V ~ 3.63V Standby 4-SMD, No Lead"
				(at 0 0 0)
				(effects
					(font
						(size 1.27 1.27)
					)
					(hide yes)
				)
			)
			(property "MPN" "ECS-1612MV-500-CN-TR"
				(at 26.67 -6.985 0)
				(effects
					(font
						(size 1.27 1.27)
						(thickness 0.15)
					)
					(justify left bottom)
				)
			)
			(property "Manufacturer" "ECS Inc. International"
				(at 26.67 -19.685 0)
				(effects
					(font
						(size 1.27 1.27)
						(thickness 0.15)
					)
					(justify left bottom)
					(hide yes)
				)
			)
			(property "Val" "50 MHz"
				(at 26.67 -9.525 0)
				(effects
					(font
						(size 1.27 1.27)
						(thickness 0.15)
					)
					(justify left bottom)
				)
			)
			(property "Author" "Antmicro"
				(at 26.67 -22.225 0)
				(effects
					(font
						(size 1.27 1.27)
						(thickness 0.15)
					)
					(justify left bottom)
					(hide yes)
				)
			)
			(property "License" "Apache-2.0"
				(at 26.67 -24.765 0)
				(effects
					(font
						(size 1.27 1.27)
						(thickness 0.15)
					)
					(justify left bottom)
					(hide yes)
				)
			)
			(property "ki_keywords" "OSCILLATOR"
				(at 0 0 0)
				(effects
					(font
						(size 1.27 1.27)
					)
					(hide yes)
				)
			)
			(symbol "Oscillator_50MHz_ECS_1612MV_1_1"
				(rectangle
					(start 2.54 2.54)
					(end 16.51 -7.62)
					(stroke
						(width 0.254)
						(type default)
					)
					(fill
						(type background)
					)
				)
				(polyline
					(pts
						(xy 7.62 -1.27) (xy 8.255 -1.27) (xy 8.255 0) (xy 8.89 0) (xy 8.89 -1.27) (xy 9.525 -1.27) (xy 9.525 0)
						(xy 10.16 0) (xy 10.16 -1.27)
					)
					(stroke
						(width 0.254)
						(type default)
					)
					(fill
						(type background)
					)
				)
				(pin power_in line
					(at 0 0 0)
					(length 2.54)
					(name "VDD"
						(effects
							(font
								(size 1.27 1.27)
							)
						)
					)
					(number "4"
						(effects
							(font
								(size 1.27 1.27)
							)
						)
					)
				)
				(pin input line
					(at 0 -2.54 0)
					(length 2.54)
					(name "EN"
						(effects
							(font
								(size 1.27 1.27)
							)
						)
					)
					(number "1"
						(effects
							(font
								(size 1.27 1.27)
							)
						)
					)
				)
				(pin power_in line
					(at 0 -5.08 0)
					(length 2.54)
					(name "GND"
						(effects
							(font
								(size 1.27 1.27)
							)
						)
					)
					(number "2"
						(effects
							(font
								(size 1.27 1.27)
							)
						)
					)
				)
				(pin output line
					(at 19.05 0 180)
					(length 2.54)
					(name "OUT"
						(effects
							(font
								(size 1.27 1.27)
							)
						)
					)
					(number "3"
						(effects
							(font
								(size 1.27 1.27)
							)
						)
					)
				)
			)
		)
	(symbol "antmicroPMICORControllersIdealDiodes:DZDH0401DW"
			(exclude_from_sim no)
			(in_bom yes)
			(on_board yes)
			(property "Reference" "Q"
				(at 30.48 -5.08 0)
				(effects
					(font
						(size 1.27 1.27)
						(thickness 0.15)
					)
					(justify left bottom)
				)
			)
			(property "Value" "DZDH0401DW"
				(at 30.48 -7.62 0)
				(effects
					(font
						(size 1.27 1.27)
						(thickness 0.15)
					)
					(justify left bottom)
					(hide yes)
				)
			)
			(property "Footprint" "antmicro-footprints:SOT-363"
				(at 30.48 -10.16 0)
				(effects
					(font
						(size 1.27 1.27)
						(thickness 0.15)
					)
					(justify left bottom)
					(hide yes)
				)
			)
			(property "Datasheet" "https://www.mouser.com/datasheet/2/115/DIOD_S_A0011803041_1-2543705.pdf"
				(at 30.48 -12.7 0)
				(effects
					(font
						(size 1.27 1.27)
						(thickness 0.15)
					)
					(justify left bottom)
					(hide yes)
				)
			)
			(property "Description" "OR Controller N+1 ORing Controller P-Channel 1:1 SOT-363"
				(at 0 0 0)
				(effects
					(font
						(size 1.27 1.27)
					)
					(hide yes)
				)
			)
			(property "MPN" "DZDH0401DW"
				(at 30.48 -15.24 0)
				(effects
					(font
						(size 1.27 1.27)
						(thickness 0.15)
					)
					(justify left bottom)
				)
			)
			(property "Manufacturer" "Diodes Incorporated"
				(at 30.48 -17.78 0)
				(effects
					(font
						(size 1.27 1.27)
						(thickness 0.15)
					)
					(justify left bottom)
					(hide yes)
				)
			)
			(property "Author" "Antmicro"
				(at 30.48 -20.32 0)
				(effects
					(font
						(size 1.27 1.27)
						(thickness 0.15)
					)
					(justify left bottom)
					(hide yes)
				)
			)
			(property "License" "Apache-2.0"
				(at 30.48 -22.86 0)
				(effects
					(font
						(size 1.27 1.27)
						(thickness 0.15)
					)
					(justify left bottom)
					(hide yes)
				)
			)
			(property "ki_keywords" "SMT, CONTROLLER, SEMICONDUCTOR, DIODE, PMOS"
				(at 0 0 0)
				(effects
					(font
						(size 1.27 1.27)
					)
					(hide yes)
				)
			)
			(symbol "DZDH0401DW_1_0"
				(pin no_connect line
					(at 2.54 -3.81 0)
					(length 2.54)
					(hide yes)
					(name "NC"
						(effects
							(font
								(size 1.27 1.27)
							)
						)
					)
					(number "1"
						(effects
							(font
								(size 1.27 1.27)
							)
						)
					)
				)
				(pin no_connect line
					(at 13.97 -3.81 180)
					(length 2.54)
					(hide yes)
					(name "NC"
						(effects
							(font
								(size 1.27 1.27)
							)
						)
					)
					(number "5"
						(effects
							(font
								(size 1.27 1.27)
							)
						)
					)
				)
			)
			(symbol "DZDH0401DW_1_1"
				(rectangle
					(start 2.54 2.54)
					(end 13.97 -5.08)
					(stroke
						(width 0.254)
						(type default)
					)
					(fill
						(type background)
					)
				)
				(pin power_in line
					(at 0 0 0)
					(length 2.54)
					(name "D"
						(effects
							(font
								(size 1.27 1.27)
							)
						)
					)
					(number "6"
						(effects
							(font
								(size 1.27 1.27)
							)
						)
					)
				)
				(pin input line
					(at 0 -2.54 0)
					(length 2.54)
					(name "REF"
						(effects
							(font
								(size 1.27 1.27)
							)
						)
					)
					(number "2"
						(effects
							(font
								(size 1.27 1.27)
							)
						)
					)
				)
				(pin power_in line
					(at 16.51 0 180)
					(length 2.54)
					(name "S"
						(effects
							(font
								(size 1.27 1.27)
							)
						)
					)
					(number "4"
						(effects
							(font
								(size 1.27 1.27)
							)
						)
					)
				)
				(pin output line
					(at 16.51 -2.54 180)
					(length 2.54)
					(name "BIAS"
						(effects
							(font
								(size 1.27 1.27)
							)
						)
					)
					(number "3"
						(effects
							(font
								(size 1.27 1.27)
							)
						)
					)
				)
			)
		)
	(symbol "antmicroPMICPowerDistributionSwitchesLoadDrivers:TPS2117DRLR"
			(exclude_from_sim no)
			(in_bom yes)
			(on_board yes)
			(property "Reference" "U"
				(at 33.02 -2.54 0)
				(effects
					(font
						(size 1.27 1.27)
						(thickness 0.15)
					)
					(justify left bottom)
				)
			)
			(property "Value" "TPS2117DRLR"
				(at 33.02 -7.62 0)
				(effects
					(font
						(size 1.27 1.27)
						(thickness 0.15)
					)
					(justify left bottom)
					(hide yes)
				)
			)
			(property "Footprint" "antmicro-footprints:SOT-583"
				(at 33.02 -10.16 0)
				(effects
					(font
						(size 1.27 1.27)
						(thickness 0.15)
					)
					(justify left bottom)
					(hide yes)
				)
			)
			(property "Datasheet" "https://www.ti.com/lit/ds/symlink/tps2117.pdf"
				(at 33.02 -12.7 0)
				(effects
					(font
						(size 1.27 1.27)
						(thickness 0.15)
					)
					(justify left bottom)
					(hide yes)
				)
			)
			(property "Description" "TPS2117 1.6-V to 5.5-V, 4-A Low IQ Power Mux With Manual and Priority Switchover"
				(at 0 0 0)
				(effects
					(font
						(size 1.27 1.27)
					)
					(hide yes)
				)
			)
			(property "Manufacturer" "Texas Instruments"
				(at 33.02 -15.24 0)
				(effects
					(font
						(size 1.27 1.27)
						(thickness 0.15)
					)
					(justify left bottom)
					(hide yes)
				)
			)
			(property "MPN" "TPS2117DRLR"
				(at 33.02 -5.08 0)
				(effects
					(font
						(size 1.27 1.27)
						(thickness 0.15)
					)
					(justify left bottom)
				)
			)
			(property "Author" "Antmicro"
				(at 33.02 -17.78 0)
				(effects
					(font
						(size 1.27 1.27)
						(thickness 0.15)
					)
					(justify left bottom)
					(hide yes)
				)
			)
			(property "License" "Apache-2.0"
				(at 33.02 -20.32 0)
				(effects
					(font
						(size 1.27 1.27)
						(thickness 0.15)
					)
					(justify left bottom)
					(hide yes)
				)
			)
			(property "ki_keywords" "SMT, SWITCH, IC, POWER, DRIVER"
				(at 0 0 0)
				(effects
					(font
						(size 1.27 1.27)
					)
					(hide yes)
				)
			)
			(property "ki_fp_filters" "DRL0008A-MFG"
				(at 0 0 0)
				(effects
					(font
						(size 1.27 1.27)
					)
					(hide yes)
				)
			)
			(symbol "TPS2117DRLR_1_1"
				(rectangle
					(start 2.54 2.54)
					(end 15.24 -10.16)
					(stroke
						(width 0.254)
						(type default)
					)
					(fill
						(type background)
					)
				)
				(pin power_in line
					(at 0 0 0)
					(length 2.54)
					(name "VIN1"
						(effects
							(font
								(size 1.27 1.27)
							)
						)
					)
					(number "3"
						(effects
							(font
								(size 1.27 1.27)
							)
						)
					)
				)
				(pin input line
					(at 0 -2.54 0)
					(length 2.54)
					(name "MODE"
						(effects
							(font
								(size 1.27 1.27)
							)
						)
					)
					(number "5"
						(effects
							(font
								(size 1.27 1.27)
							)
						)
					)
				)
				(pin input line
					(at 0 -5.08 0)
					(length 2.54)
					(name "PR1"
						(effects
							(font
								(size 1.27 1.27)
							)
						)
					)
					(number "4"
						(effects
							(font
								(size 1.27 1.27)
							)
						)
					)
				)
				(pin power_in line
					(at 0 -7.62 0)
					(length 2.54)
					(name "VIN2"
						(effects
							(font
								(size 1.27 1.27)
							)
						)
					)
					(number "6"
						(effects
							(font
								(size 1.27 1.27)
							)
						)
					)
				)
				(pin power_out line
					(at 17.78 0 180)
					(length 2.54)
					(name "VOUT"
						(effects
							(font
								(size 1.27 1.27)
							)
						)
					)
					(number "2"
						(effects
							(font
								(size 1.27 1.27)
							)
						)
					)
				)
				(pin passive line
					(at 17.78 0 180)
					(length 2.54)
					(hide yes)
					(name "VOUT"
						(effects
							(font
								(size 1.27 1.27)
							)
						)
					)
					(number "7"
						(effects
							(font
								(size 1.27 1.27)
							)
						)
					)
				)
				(pin output line
					(at 17.78 -2.54 180)
					(length 2.54)
					(name "ST"
						(effects
							(font
								(size 1.27 1.27)
							)
						)
					)
					(number "8"
						(effects
							(font
								(size 1.27 1.27)
							)
						)
					)
				)
				(pin power_in line
					(at 17.78 -7.62 180)
					(length 2.54)
					(name "GND"
						(effects
							(font
								(size 1.27 1.27)
							)
						)
					)
					(number "1"
						(effects
							(font
								(size 1.27 1.27)
							)
						)
					)
				)
			)
		)
	(symbol "antmicroPMICVoltageRegulatorsDCDCSwitchingRegulators:MP5424GRM"
			(exclude_from_sim no)
			(in_bom yes)
			(on_board yes)
			(property "Reference" "U"
				(at 41.91 -2.54 0)
				(effects
					(font
						(size 1.27 1.27)
						(thickness 0.15)
					)
					(justify left bottom)
				)
			)
			(property "Value" "MP5424GRM"
				(at 41.91 -7.62 0)
				(effects
					(font
						(size 1.27 1.27)
						(thickness 0.15)
					)
					(justify left bottom)
					(hide yes)
				)
			)
			(property "Footprint" "antmicro-footprints:QFN-26_3.5x4.5x1mm_P0.45mm"
				(at 41.91 -12.7 0)
				(effects
					(font
						(size 1.27 1.27)
						(thickness 0.15)
					)
					(justify left bottom)
					(hide yes)
				)
			)
			(property "Datasheet" "https://www.monolithicpower.com/en/documentview/productdocument/index/version/2/document_type/Datasheet/lang/en/sku/MP5424GRM/document_id/10311/"
				(at 41.91 -15.24 0)
				(effects
					(font
						(size 1.27 1.27)
						(thickness 0.15)
					)
					(justify left bottom)
					(hide yes)
				)
			)
			(property "Description" "5V PMIC with Four 4.5A/2.5A/4.5A/2A Buck Converters, 3 LDOs, 1 Load Switch and Flexible System Settings via I2C and MTP"
				(at 0 0 0)
				(effects
					(font
						(size 1.27 1.27)
					)
					(hide yes)
				)
			)
			(property "MPN" "MP5424GRM-0000-Z"
				(at 41.91 -5.08 0)
				(effects
					(font
						(size 1.27 1.27)
						(thickness 0.15)
					)
					(justify left bottom)
				)
			)
			(property "Manufacturer" "Monolithic Power Systems"
				(at 41.91 -10.16 0)
				(effects
					(font
						(size 1.27 1.27)
						(thickness 0.15)
					)
					(justify left bottom)
					(hide yes)
				)
			)
			(property "Author" "Antmicro"
				(at 41.91 -17.78 0)
				(effects
					(font
						(size 1.27 1.27)
						(thickness 0.15)
					)
					(justify left bottom)
					(hide yes)
				)
			)
			(property "License" "Apache-2.0"
				(at 41.91 -20.32 0)
				(effects
					(font
						(size 1.27 1.27)
						(thickness 0.15)
					)
					(justify left bottom)
					(hide yes)
				)
			)
			(property "ki_keywords" "SMT, PMIC, IC, VOLTAGE, REGULATOR, SWITCHING, DC-DC"
				(at 0 0 0)
				(effects
					(font
						(size 1.27 1.27)
					)
					(hide yes)
				)
			)
			(symbol "MP5424GRM_0_1"
				(polyline
					(pts
						(xy 7.62 -3.81) (xy 15.24 -3.81) (xy 15.24 -15.24) (xy 16.51 -15.24)
					)
					(stroke
						(width 0)
						(type default)
					)
					(fill
						(type none)
					)
				)
				(polyline
					(pts
						(xy 7.62 -11.43) (xy 12.7 -11.43) (xy 12.7 -29.21) (xy 16.51 -29.21)
					)
					(stroke
						(width 0)
						(type default)
					)
					(fill
						(type none)
					)
				)
				(polyline
					(pts
						(xy 7.62 -15.24) (xy 11.43 -15.24) (xy 11.43 -35.56) (xy 16.51 -35.56)
					)
					(stroke
						(width 0)
						(type default)
					)
					(fill
						(type none)
					)
				)
				(polyline
					(pts
						(xy 7.62 -19.05) (xy 10.16 -19.05) (xy 10.16 -45.72) (xy 16.51 -45.72)
					)
					(stroke
						(width 0)
						(type default)
					)
					(fill
						(type none)
					)
				)
				(polyline
					(pts
						(xy 16.51 0) (xy 7.62 0)
					)
					(stroke
						(width 0)
						(type default)
					)
					(fill
						(type none)
					)
				)
				(polyline
					(pts
						(xy 16.51 -8.89) (xy 15.24 -8.89)
					)
					(stroke
						(width 0)
						(type default)
					)
					(fill
						(type none)
					)
				)
				(polyline
					(pts
						(xy 16.51 -21.59) (xy 13.97 -21.59) (xy 13.97 -7.62) (xy 7.62 -7.62)
					)
					(stroke
						(width 0)
						(type default)
					)
					(fill
						(type none)
					)
				)
				(polyline
					(pts
						(xy 16.51 -40.64) (xy 11.43 -40.64) (xy 11.43 -35.56)
					)
					(stroke
						(width 0)
						(type default)
					)
					(fill
						(type none)
					)
				)
				(polyline
					(pts
						(xy 22.86 -3.81) (xy 16.51 -3.81) (xy 16.51 1.27) (xy 22.86 1.27)
					)
					(stroke
						(width 0)
						(type default)
					)
					(fill
						(type none)
					)
				)
				(polyline
					(pts
						(xy 22.86 -11.43) (xy 16.51 -11.43) (xy 16.51 -6.35) (xy 22.86 -6.35)
					)
					(stroke
						(width 0)
						(type default)
					)
					(fill
						(type none)
					)
				)
				(polyline
					(pts
						(xy 22.86 -13.97) (xy 16.51 -13.97) (xy 16.51 -16.51) (xy 22.86 -16.51)
					)
					(stroke
						(width 0)
						(type default)
					)
					(fill
						(type none)
					)
				)
				(polyline
					(pts
						(xy 22.86 -19.05) (xy 16.51 -19.05) (xy 16.51 -24.13) (xy 22.86 -24.13)
					)
					(stroke
						(width 0)
						(type default)
					)
					(fill
						(type none)
					)
				)
				(polyline
					(pts
						(xy 22.86 -26.67) (xy 16.51 -26.67) (xy 16.51 -31.75) (xy 22.86 -31.75)
					)
					(stroke
						(width 0)
						(type default)
					)
					(fill
						(type none)
					)
				)
				(polyline
					(pts
						(xy 22.86 -34.29) (xy 16.51 -34.29) (xy 16.51 -36.83) (xy 22.86 -36.83)
					)
					(stroke
						(width 0)
						(type default)
					)
					(fill
						(type none)
					)
				)
				(polyline
					(pts
						(xy 22.86 -39.37) (xy 16.51 -39.37) (xy 16.51 -41.91) (xy 22.86 -41.91)
					)
					(stroke
						(width 0)
						(type default)
					)
					(fill
						(type none)
					)
				)
				(polyline
					(pts
						(xy 22.86 -44.45) (xy 16.51 -44.45) (xy 16.51 -46.99) (xy 22.86 -46.99)
					)
					(stroke
						(width 0)
						(type default)
					)
					(fill
						(type none)
					)
				)
			)
			(symbol "MP5424GRM_1_1"
				(rectangle
					(start 2.54 2.54)
					(end 22.86 -48.26)
					(stroke
						(width 0.254)
						(type default)
					)
					(fill
						(type background)
					)
				)
				(pin power_in line
					(at 0 0 0)
					(length 2.54)
					(name "VIN1"
						(effects
							(font
								(size 1.27 1.27)
							)
						)
					)
					(number "3"
						(effects
							(font
								(size 1.27 1.27)
							)
						)
					)
				)
				(pin power_in line
					(at 0 -3.81 0)
					(length 2.54)
					(name "VIN2"
						(effects
							(font
								(size 1.27 1.27)
							)
						)
					)
					(number "20"
						(effects
							(font
								(size 1.27 1.27)
							)
						)
					)
				)
				(pin power_in line
					(at 0 -7.62 0)
					(length 2.54)
					(name "VIN3"
						(effects
							(font
								(size 1.27 1.27)
							)
						)
					)
					(number "7"
						(effects
							(font
								(size 1.27 1.27)
							)
						)
					)
				)
				(pin power_in line
					(at 0 -11.43 0)
					(length 2.54)
					(name "VIN4"
						(effects
							(font
								(size 1.27 1.27)
							)
						)
					)
					(number "16"
						(effects
							(font
								(size 1.27 1.27)
							)
						)
					)
				)
				(pin power_in line
					(at 0 -15.24 0)
					(length 2.54)
					(name "VIN5"
						(effects
							(font
								(size 1.27 1.27)
							)
						)
					)
					(number "13"
						(effects
							(font
								(size 1.27 1.27)
							)
						)
					)
				)
				(pin power_in line
					(at 0 -19.05 0)
					(length 2.54)
					(name "LSWI"
						(effects
							(font
								(size 1.27 1.27)
							)
						)
					)
					(number "23"
						(effects
							(font
								(size 1.27 1.27)
							)
						)
					)
				)
				(pin input line
					(at 0 -24.13 0)
					(length 2.54)
					(name "AVIN"
						(effects
							(font
								(size 1.27 1.27)
							)
						)
					)
					(number "26"
						(effects
							(font
								(size 1.27 1.27)
							)
						)
					)
				)
				(pin input line
					(at 0 -27.94 0)
					(length 2.54)
					(name "PWRON"
						(effects
							(font
								(size 1.27 1.27)
							)
						)
					)
					(number "2"
						(effects
							(font
								(size 1.27 1.27)
							)
						)
					)
				)
				(pin input line
					(at 0 -33.02 0)
					(length 2.54)
					(name "RSTO"
						(effects
							(font
								(size 1.27 1.27)
							)
						)
					)
					(number "9"
						(effects
							(font
								(size 1.27 1.27)
							)
						)
					)
				)
				(pin input line
					(at 0 -36.83 0)
					(length 2.54)
					(name "SCL"
						(effects
							(font
								(size 1.27 1.27)
							)
						)
					)
					(number "10"
						(effects
							(font
								(size 1.27 1.27)
							)
						)
					)
				)
				(pin bidirectional line
					(at 0 -39.37 0)
					(length 2.54)
					(name "SDA"
						(effects
							(font
								(size 1.27 1.27)
							)
						)
					)
					(number "11"
						(effects
							(font
								(size 1.27 1.27)
							)
						)
					)
				)
				(pin power_in line
					(at 0 -43.18 0)
					(length 2.54)
					(name "AGND"
						(effects
							(font
								(size 1.27 1.27)
							)
						)
					)
					(number "25"
						(effects
							(font
								(size 1.27 1.27)
							)
						)
					)
				)
				(pin passive line
					(at 0 -45.72 0)
					(length 2.54)
					(hide yes)
					(name "GND"
						(effects
							(font
								(size 1.27 1.27)
							)
						)
					)
					(number "18"
						(effects
							(font
								(size 1.27 1.27)
							)
						)
					)
				)
				(pin power_in line
					(at 0 -45.72 0)
					(length 2.54)
					(name "GND"
						(effects
							(font
								(size 1.27 1.27)
							)
						)
					)
					(number "5"
						(effects
							(font
								(size 1.27 1.27)
							)
						)
					)
				)
				(pin power_out line
					(at 25.4 0 180)
					(length 2.54)
					(name "SW1"
						(effects
							(font
								(size 1.27 1.27)
							)
						)
					)
					(number "4"
						(effects
							(font
								(size 1.27 1.27)
							)
						)
					)
				)
				(pin input line
					(at 25.4 -2.54 180)
					(length 2.54)
					(name "FB1"
						(effects
							(font
								(size 1.27 1.27)
							)
						)
					)
					(number "1"
						(effects
							(font
								(size 1.27 1.27)
							)
						)
					)
				)
				(pin power_out line
					(at 25.4 -7.62 180)
					(length 2.54)
					(name "SW2"
						(effects
							(font
								(size 1.27 1.27)
							)
						)
					)
					(number "19"
						(effects
							(font
								(size 1.27 1.27)
							)
						)
					)
				)
				(pin input line
					(at 25.4 -10.16 180)
					(length 2.54)
					(name "FB2"
						(effects
							(font
								(size 1.27 1.27)
							)
						)
					)
					(number "21"
						(effects
							(font
								(size 1.27 1.27)
							)
						)
					)
				)
				(pin power_out line
					(at 25.4 -15.24 180)
					(length 2.54)
					(name "OUT2"
						(effects
							(font
								(size 1.27 1.27)
							)
						)
					)
					(number "22"
						(effects
							(font
								(size 1.27 1.27)
							)
						)
					)
				)
				(pin power_out line
					(at 25.4 -20.32 180)
					(length 2.54)
					(name "SW3"
						(effects
							(font
								(size 1.27 1.27)
							)
						)
					)
					(number "6"
						(effects
							(font
								(size 1.27 1.27)
							)
						)
					)
				)
				(pin input line
					(at 25.4 -22.86 180)
					(length 2.54)
					(name "FB3"
						(effects
							(font
								(size 1.27 1.27)
							)
						)
					)
					(number "8"
						(effects
							(font
								(size 1.27 1.27)
							)
						)
					)
				)
				(pin power_out line
					(at 25.4 -27.94 180)
					(length 2.54)
					(name "SW4"
						(effects
							(font
								(size 1.27 1.27)
							)
						)
					)
					(number "17"
						(effects
							(font
								(size 1.27 1.27)
							)
						)
					)
				)
				(pin input line
					(at 25.4 -30.48 180)
					(length 2.54)
					(name "FB4"
						(effects
							(font
								(size 1.27 1.27)
							)
						)
					)
					(number "15"
						(effects
							(font
								(size 1.27 1.27)
							)
						)
					)
				)
				(pin power_out line
					(at 25.4 -35.56 180)
					(length 2.54)
					(name "OUT4"
						(effects
							(font
								(size 1.27 1.27)
							)
						)
					)
					(number "12"
						(effects
							(font
								(size 1.27 1.27)
							)
						)
					)
				)
				(pin power_out line
					(at 25.4 -40.64 180)
					(length 2.54)
					(name "OUT5"
						(effects
							(font
								(size 1.27 1.27)
							)
						)
					)
					(number "14"
						(effects
							(font
								(size 1.27 1.27)
							)
						)
					)
				)
				(pin power_out line
					(at 25.4 -45.72 180)
					(length 2.54)
					(name "LSWO"
						(effects
							(font
								(size 1.27 1.27)
							)
						)
					)
					(number "24"
						(effects
							(font
								(size 1.27 1.27)
							)
						)
					)
				)
			)
		)
	(symbol "antmicroPMICVoltageRegulatorsDCDCSwitchingRegulators:MP8869S"
			(exclude_from_sim no)
			(in_bom yes)
			(on_board yes)
			(property "Reference" "U"
				(at 25.4 -6.35 0)
				(effects
					(font
						(size 1.27 1.27)
						(thickness 0.15)
					)
					(justify left bottom)
				)
			)
			(property "Value" "MP8869S"
				(at 25.4 -8.89 0)
				(effects
					(font
						(size 1.27 1.27)
						(thickness 0.15)
					)
					(justify left bottom)
					(hide yes)
				)
			)
			(property "Footprint" "antmicro-footprints:MPS_QFN-14_MP8869S"
				(at 25.4 -11.43 0)
				(effects
					(font
						(size 1.27 1.27)
						(thickness 0.15)
					)
					(justify left bottom)
					(hide yes)
				)
			)
			(property "Datasheet" "https://www.mouser.com/datasheet/2/277/MP8869S-2946178.pdf"
				(at 25.4 -13.97 0)
				(effects
					(font
						(size 1.27 1.27)
						(thickness 0.15)
					)
					(justify left bottom)
					(hide yes)
				)
			)
			(property "Description" "DC-DC Switching Synchronous Buck Regulator, 2.85V-18V in, 600mV to 5.5V out, 12A, 500kHz, QFN-14"
				(at 0 0 0)
				(effects
					(font
						(size 1.27 1.27)
					)
					(hide yes)
				)
			)
			(property "MPN" "MP8869SGL-P"
				(at 25.4 -16.51 0)
				(effects
					(font
						(size 1.27 1.27)
						(thickness 0.15)
					)
					(justify left bottom)
				)
			)
			(property "Manufacturer" "Monolithic Power Systems"
				(at 25.4 -19.05 0)
				(effects
					(font
						(size 1.27 1.27)
						(thickness 0.15)
					)
					(justify left bottom)
					(hide yes)
				)
			)
			(property "Author" "Antmicro"
				(at 25.4 -21.59 0)
				(effects
					(font
						(size 1.27 1.27)
						(thickness 0.15)
					)
					(justify left bottom)
					(hide yes)
				)
			)
			(property "License" "Apache-2.0"
				(at 25.4 -24.13 0)
				(effects
					(font
						(size 1.27 1.27)
						(thickness 0.15)
					)
					(justify left bottom)
					(hide yes)
				)
			)
			(property "ki_keywords" "SMT, PMIC, IC, VOLTAGE, REGULATOR, SWITCHING, DC-DC"
				(at 0 0 0)
				(effects
					(font
						(size 1.27 1.27)
					)
					(hide yes)
				)
			)
			(property "ki_fp_filters" "QFN-14_MP8869S_MNP"
				(at 0 0 0)
				(effects
					(font
						(size 1.27 1.27)
					)
					(hide yes)
				)
			)
			(symbol "MP8869S_1_1"
				(rectangle
					(start -7.62 -2.54)
					(end 7.62 -30.48)
					(stroke
						(width 0.254)
						(type default)
					)
					(fill
						(type background)
					)
				)
				(pin power_in line
					(at -10.16 -5.08 0)
					(length 2.54)
					(name "VIN"
						(effects
							(font
								(size 1.27 1.27)
							)
						)
					)
					(number "9"
						(effects
							(font
								(size 1.27 1.27)
							)
						)
					)
				)
				(pin unspecified line
					(at -10.16 -10.16 0)
					(length 2.54)
					(name "EN"
						(effects
							(font
								(size 1.27 1.27)
							)
						)
					)
					(number "5"
						(effects
							(font
								(size 1.27 1.27)
							)
						)
					)
				)
				(pin power_out line
					(at -10.16 -12.7 0)
					(length 2.54)
					(name "VCC"
						(effects
							(font
								(size 1.27 1.27)
							)
						)
					)
					(number "13"
						(effects
							(font
								(size 1.27 1.27)
							)
						)
					)
				)
				(pin unspecified line
					(at -10.16 -19.05 0)
					(length 2.54)
					(name "PG"
						(effects
							(font
								(size 1.27 1.27)
							)
						)
					)
					(number "7"
						(effects
							(font
								(size 1.27 1.27)
							)
						)
					)
				)
				(pin unspecified line
					(at -10.16 -22.86 0)
					(length 2.54)
					(name "SDA"
						(effects
							(font
								(size 1.27 1.27)
							)
						)
					)
					(number "4"
						(effects
							(font
								(size 1.27 1.27)
							)
						)
					)
				)
				(pin unspecified line
					(at -10.16 -25.4 0)
					(length 2.54)
					(name "SCL"
						(effects
							(font
								(size 1.27 1.27)
							)
						)
					)
					(number "3"
						(effects
							(font
								(size 1.27 1.27)
							)
						)
					)
				)
				(pin unspecified line
					(at -10.16 -27.94 0)
					(length 2.54)
					(name "A0"
						(effects
							(font
								(size 1.27 1.27)
							)
						)
					)
					(number "6"
						(effects
							(font
								(size 1.27 1.27)
							)
						)
					)
				)
				(pin power_in line
					(at -1.27 -33.02 90)
					(length 2.54)
					(name "AGND"
						(effects
							(font
								(size 1.27 1.27)
							)
						)
					)
					(number "14"
						(effects
							(font
								(size 1.27 1.27)
							)
						)
					)
				)
				(pin unspecified line
					(at 0 0 270)
					(length 2.54)
					(name "BST"
						(effects
							(font
								(size 1.27 1.27)
							)
						)
					)
					(number "1"
						(effects
							(font
								(size 1.27 1.27)
							)
						)
					)
				)
				(pin power_in line
					(at 1.27 -33.02 90)
					(length 2.54)
					(name "PGND"
						(effects
							(font
								(size 1.27 1.27)
							)
						)
					)
					(number "8"
						(effects
							(font
								(size 1.27 1.27)
							)
						)
					)
				)
				(pin output line
					(at 10.16 -5.08 180)
					(length 2.54)
					(name "SW"
						(effects
							(font
								(size 1.27 1.27)
							)
						)
					)
					(number "2"
						(effects
							(font
								(size 1.27 1.27)
							)
						)
					)
				)
				(pin unspecified line
					(at 10.16 -12.7 180)
					(length 2.54)
					(name "VOUT"
						(effects
							(font
								(size 1.27 1.27)
							)
						)
					)
					(number "10"
						(effects
							(font
								(size 1.27 1.27)
							)
						)
					)
				)
				(pin unspecified line
					(at 10.16 -20.32 180)
					(length 2.54)
					(name "FB"
						(effects
							(font
								(size 1.27 1.27)
							)
						)
					)
					(number "11"
						(effects
							(font
								(size 1.27 1.27)
							)
						)
					)
				)
				(pin unspecified line
					(at 10.16 -27.94 180)
					(length 2.54)
					(name "SS"
						(effects
							(font
								(size 1.27 1.27)
							)
						)
					)
					(number "12"
						(effects
							(font
								(size 1.27 1.27)
							)
						)
					)
				)
			)
		)
	(symbol "antmicroPowerMeasurement:PAC1934T_WLCSP"
			(exclude_from_sim no)
			(in_bom yes)
			(on_board yes)
			(property "Reference" "U"
				(at 50.8 -2.54 0)
				(effects
					(font
						(size 1.27 1.27)
						(thickness 0.15)
					)
					(justify left bottom)
				)
			)
			(property "Value" "PAC1934T_WLCSP"
				(at 50.8 -7.62 0)
				(effects
					(font
						(size 1.27 1.27)
						(thickness 0.15)
					)
					(justify left bottom)
					(hide yes)
				)
			)
			(property "Footprint" "antmicro-footprints:WLCSP-16_2.25x2.17x0.68mm_Layout4x4_P0.5x0.5mm"
				(at 50.8 -10.16 0)
				(effects
					(font
						(size 1.27 1.27)
						(thickness 0.15)
					)
					(justify left bottom)
					(hide yes)
				)
			)
			(property "Datasheet" "https://www.mouser.com/datasheet/2/268/PAC1931_Family_Data_Sheet_DS20005850E-1519053.pdf"
				(at 50.8 -12.7 0)
				(effects
					(font
						(size 1.27 1.27)
						(thickness 0.15)
					)
					(justify left bottom)
					(hide yes)
				)
			)
			(property "Description" "DC Power/Energy Monitor With Accumulator, Quad High-side current Sensor, 2.7V to 5.5V, WLCSP-16"
				(at 0 0 0)
				(effects
					(font
						(size 1.27 1.27)
					)
					(hide yes)
				)
			)
			(property "Manufacturer" "Microchip Technology"
				(at 50.8 -15.24 0)
				(effects
					(font
						(size 1.27 1.27)
						(thickness 0.15)
					)
					(justify left bottom)
					(hide yes)
				)
			)
			(property "MPN" "PAC1934T-I/J6CX"
				(at 50.8 -5.08 0)
				(effects
					(font
						(size 1.27 1.27)
						(thickness 0.15)
					)
					(justify left bottom)
				)
			)
			(property "Author" "Antmicro"
				(at 50.8 -17.78 0)
				(effects
					(font
						(size 1.27 1.27)
						(thickness 0.15)
					)
					(justify left bottom)
					(hide yes)
				)
			)
			(property "License" "Apache-2.0"
				(at 50.8 -20.32 0)
				(effects
					(font
						(size 1.27 1.27)
						(thickness 0.15)
					)
					(justify left bottom)
					(hide yes)
				)
			)
			(property "ki_keywords" "IC, PMIC, SMT, MONITOR"
				(at 0 0 0)
				(effects
					(font
						(size 1.27 1.27)
					)
					(hide yes)
				)
			)
			(symbol "PAC1934T_WLCSP_1_1"
				(rectangle
					(start 2.54 2.54)
					(end 25.4 -20.32)
					(stroke
						(width 0.254)
						(type default)
					)
					(fill
						(type background)
					)
				)
				(pin power_in line
					(at 0 0 0)
					(length 2.54)
					(name "VDD_I/O"
						(effects
							(font
								(size 1.27 1.27)
							)
						)
					)
					(number "B2"
						(effects
							(font
								(size 1.27 1.27)
							)
						)
					)
				)
				(pin power_in line
					(at 0 -2.54 0)
					(length 2.54)
					(name "VDD"
						(effects
							(font
								(size 1.27 1.27)
							)
						)
					)
					(number "A4"
						(effects
							(font
								(size 1.27 1.27)
							)
						)
					)
				)
				(pin input clock
					(at 0 -5.08 0)
					(length 2.54)
					(name "SM_CLK"
						(effects
							(font
								(size 1.27 1.27)
							)
						)
					)
					(number "C4"
						(effects
							(font
								(size 1.27 1.27)
							)
						)
					)
				)
				(pin bidirectional line
					(at 0 -7.62 0)
					(length 2.54)
					(name "SM_DATA"
						(effects
							(font
								(size 1.27 1.27)
							)
						)
					)
					(number "D4"
						(effects
							(font
								(size 1.27 1.27)
							)
						)
					)
				)
				(pin bidirectional line
					(at 0 -10.16 0)
					(length 2.54)
					(name "SLOW/~{ALERT}"
						(effects
							(font
								(size 1.27 1.27)
							)
						)
					)
					(number "C3"
						(effects
							(font
								(size 1.27 1.27)
							)
						)
					)
				)
				(pin input line
					(at 0 -12.7 0)
					(length 2.54)
					(name "~{PWRDN}"
						(effects
							(font
								(size 1.27 1.27)
							)
						)
					)
					(number "B3"
						(effects
							(font
								(size 1.27 1.27)
							)
						)
					)
				)
				(pin bidirectional line
					(at 0 -15.24 0)
					(length 2.54)
					(name "ADDRSEL"
						(effects
							(font
								(size 1.27 1.27)
							)
						)
					)
					(number "C2"
						(effects
							(font
								(size 1.27 1.27)
							)
						)
					)
				)
				(pin power_in line
					(at 0 -17.78 0)
					(length 2.54)
					(name "GND"
						(effects
							(font
								(size 1.27 1.27)
							)
						)
					)
					(number "B4"
						(effects
							(font
								(size 1.27 1.27)
							)
						)
					)
				)
				(pin input line
					(at 27.94 0 180)
					(length 2.54)
					(name "SENSE1+"
						(effects
							(font
								(size 1.27 1.27)
							)
						)
					)
					(number "A3"
						(effects
							(font
								(size 1.27 1.27)
							)
						)
					)
				)
				(pin input line
					(at 27.94 -2.54 180)
					(length 2.54)
					(name "SENSE1-"
						(effects
							(font
								(size 1.27 1.27)
							)
						)
					)
					(number "A2"
						(effects
							(font
								(size 1.27 1.27)
							)
						)
					)
				)
				(pin input line
					(at 27.94 -5.08 180)
					(length 2.54)
					(name "SENSE2+"
						(effects
							(font
								(size 1.27 1.27)
							)
						)
					)
					(number "A1"
						(effects
							(font
								(size 1.27 1.27)
							)
						)
					)
				)
				(pin input line
					(at 27.94 -7.62 180)
					(length 2.54)
					(name "SENSE2-"
						(effects
							(font
								(size 1.27 1.27)
							)
						)
					)
					(number "B1"
						(effects
							(font
								(size 1.27 1.27)
							)
						)
					)
				)
				(pin input line
					(at 27.94 -10.16 180)
					(length 2.54)
					(name "SENSE3+"
						(effects
							(font
								(size 1.27 1.27)
							)
						)
					)
					(number "D1"
						(effects
							(font
								(size 1.27 1.27)
							)
						)
					)
				)
				(pin input line
					(at 27.94 -12.7 180)
					(length 2.54)
					(name "SENSE3-"
						(effects
							(font
								(size 1.27 1.27)
							)
						)
					)
					(number "C1"
						(effects
							(font
								(size 1.27 1.27)
							)
						)
					)
				)
				(pin input line
					(at 27.94 -15.24 180)
					(length 2.54)
					(name "SENSE4+"
						(effects
							(font
								(size 1.27 1.27)
							)
						)
					)
					(number "D3"
						(effects
							(font
								(size 1.27 1.27)
							)
						)
					)
				)
				(pin input line
					(at 27.94 -17.78 180)
					(length 2.54)
					(name "SENSE4-"
						(effects
							(font
								(size 1.27 1.27)
							)
						)
					)
					(number "D2"
						(effects
							(font
								(size 1.27 1.27)
							)
						)
					)
				)
			)
		)
	(symbol "antmicroRFTransceiverModules:WiFi_Bluetooth_LBEE5PK2AE"
			(exclude_from_sim no)
			(in_bom no)
			(on_board yes)
			(property "Reference" "U"
				(at 55.88 -2.54 0)
				(effects
					(font
						(size 1.27 1.27)
						(thickness 0.15)
					)
					(justify left bottom)
				)
			)
			(property "Value" "WiFi_Bluetooth_LBEE5PK2AE"
				(at 55.88 -7.62 0)
				(effects
					(font
						(size 1.27 1.27)
						(thickness 0.15)
					)
					(justify left bottom)
					(hide yes)
				)
			)
			(property "Footprint" "antmicro-footprints:WiFi_Bluetooth_Module_LBEE5PK2AE"
				(at 55.88 -10.16 0)
				(effects
					(font
						(size 1.27 1.27)
						(thickness 0.15)
					)
					(justify left bottom)
					(hide yes)
				)
			)
			(property "Datasheet" "https://www.murata.com/products/productdata/8816428220446/type2ae.pdf"
				(at 55.88 -12.7 0)
				(effects
					(font
						(size 1.27 1.27)
						(thickness 0.15)
					)
					(justify left bottom)
					(hide yes)
				)
			)
			(property "Description" "WiFi and Bluetooth Module"
				(at 0 0 0)
				(effects
					(font
						(size 1.27 1.27)
					)
					(hide yes)
				)
			)
			(property "Manufacturer" "Murata"
				(at 55.88 -15.24 0)
				(effects
					(font
						(size 1.27 1.27)
						(thickness 0.15)
					)
					(justify left bottom)
					(hide yes)
				)
			)
			(property "MPN" "LBEE5PK2AE"
				(at 55.88 -5.08 0)
				(effects
					(font
						(size 1.27 1.27)
						(thickness 0.15)
					)
					(justify left bottom)
				)
			)
			(property "Author" "Antmicro"
				(at 55.88 -17.78 0)
				(effects
					(font
						(size 1.27 1.27)
						(thickness 0.15)
					)
					(justify left bottom)
					(hide yes)
				)
			)
			(property "License" "Apache-2.0"
				(at 55.88 -20.32 0)
				(effects
					(font
						(size 1.27 1.27)
						(thickness 0.15)
					)
					(justify left bottom)
					(hide yes)
				)
			)
			(property "ki_locked" ""
				(at 0 0 0)
				(effects
					(font
						(size 1.27 1.27)
					)
				)
			)
			(property "ki_keywords" "MODULE, WIFI, BLUETOOTH"
				(at 0 0 0)
				(effects
					(font
						(size 1.27 1.27)
					)
					(hide yes)
				)
			)
			(symbol "WiFi_Bluetooth_LBEE5PK2AE_1_1"
				(rectangle
					(start 2.54 2.54)
					(end 35.56 -69.85)
					(stroke
						(width 0.254)
						(type default)
					)
					(fill
						(type background)
					)
				)
				(pin power_in line
					(at 0 0 0)
					(length 2.54)
					(name "VDDIO"
						(effects
							(font
								(size 1.27 1.27)
							)
						)
					)
					(number "42"
						(effects
							(font
								(size 1.27 1.27)
							)
						)
					)
				)
				(pin power_in line
					(at 0 -2.54 0)
					(length 2.54)
					(name "VBAT"
						(effects
							(font
								(size 1.27 1.27)
							)
						)
					)
					(number "3"
						(effects
							(font
								(size 1.27 1.27)
							)
						)
					)
				)
				(pin power_out line
					(at 0 -5.08 0)
					(length 2.54)
					(name "SR_VLX"
						(effects
							(font
								(size 1.27 1.27)
							)
						)
					)
					(number "2"
						(effects
							(font
								(size 1.27 1.27)
							)
						)
					)
				)
				(pin power_in line
					(at 0 -7.62 0)
					(length 2.54)
					(name "VIN_LDO"
						(effects
							(font
								(size 1.27 1.27)
							)
						)
					)
					(number "43"
						(effects
							(font
								(size 1.27 1.27)
							)
						)
					)
				)
				(pin power_in line
					(at 0 -10.16 0)
					(length 2.54)
					(name "USB2_AVDD33"
						(effects
							(font
								(size 1.27 1.27)
							)
						)
					)
					(number "49"
						(effects
							(font
								(size 1.27 1.27)
							)
						)
					)
				)
				(pin input line
					(at 0 -13.97 0)
					(length 2.54)
					(name "BT_REG_EN"
						(effects
							(font
								(size 1.27 1.27)
							)
						)
					)
					(number "68"
						(effects
							(font
								(size 1.27 1.27)
							)
						)
					)
				)
				(pin input line
					(at 0 -16.51 0)
					(length 2.54)
					(name "WL_REG_EN"
						(effects
							(font
								(size 1.27 1.27)
							)
						)
					)
					(number "4"
						(effects
							(font
								(size 1.27 1.27)
							)
						)
					)
				)
				(pin input line
					(at 0 -19.05 0)
					(length 2.54)
					(name "BT_DEV_WAKE"
						(effects
							(font
								(size 1.27 1.27)
							)
						)
					)
					(number "51"
						(effects
							(font
								(size 1.27 1.27)
							)
						)
					)
				)
				(pin input line
					(at 0 -21.59 0)
					(length 2.54)
					(name "LPO_IN"
						(effects
							(font
								(size 1.27 1.27)
							)
						)
					)
					(number "5"
						(effects
							(font
								(size 1.27 1.27)
							)
						)
					)
				)
				(pin output line
					(at 0 -25.4 0)
					(length 2.54)
					(name "RF_SW_CTRL_0"
						(effects
							(font
								(size 1.27 1.27)
							)
						)
					)
					(number "26"
						(effects
							(font
								(size 1.27 1.27)
							)
						)
					)
				)
				(pin output line
					(at 0 -27.94 0)
					(length 2.54)
					(name "RF_SW_CTRL_5"
						(effects
							(font
								(size 1.27 1.27)
							)
						)
					)
					(number "25"
						(effects
							(font
								(size 1.27 1.27)
							)
						)
					)
				)
				(pin input line
					(at 0 -31.75 0)
					(length 2.54)
					(name "BT_PCM_IN"
						(effects
							(font
								(size 1.27 1.27)
							)
						)
					)
					(number "6"
						(effects
							(font
								(size 1.27 1.27)
							)
						)
					)
				)
				(pin bidirectional line
					(at 0 -34.29 0)
					(length 2.54)
					(name "BT_PCM_CLK"
						(effects
							(font
								(size 1.27 1.27)
							)
						)
					)
					(number "7"
						(effects
							(font
								(size 1.27 1.27)
							)
						)
					)
				)
				(pin bidirectional line
					(at 0 -36.83 0)
					(length 2.54)
					(name "BT_PCM_SYNC"
						(effects
							(font
								(size 1.27 1.27)
							)
						)
					)
					(number "8"
						(effects
							(font
								(size 1.27 1.27)
							)
						)
					)
				)
				(pin output line
					(at 0 -39.37 0)
					(length 2.54)
					(name "BT_PCM_OUT"
						(effects
							(font
								(size 1.27 1.27)
							)
						)
					)
					(number "9"
						(effects
							(font
								(size 1.27 1.27)
							)
						)
					)
				)
				(pin output line
					(at 0 -43.18 0)
					(length 2.54)
					(name "BT_UART_TXD"
						(effects
							(font
								(size 1.27 1.27)
							)
						)
					)
					(number "10"
						(effects
							(font
								(size 1.27 1.27)
							)
						)
					)
				)
				(pin input line
					(at 0 -45.72 0)
					(length 2.54)
					(name "BT_UART_CTS_N"
						(effects
							(font
								(size 1.27 1.27)
							)
						)
					)
					(number "11"
						(effects
							(font
								(size 1.27 1.27)
							)
						)
					)
				)
				(pin input line
					(at 0 -48.26 0)
					(length 2.54)
					(name "BT_UART_RXD"
						(effects
							(font
								(size 1.27 1.27)
							)
						)
					)
					(number "12"
						(effects
							(font
								(size 1.27 1.27)
							)
						)
					)
				)
				(pin output line
					(at 0 -50.8 0)
					(length 2.54)
					(name "BT_UART_RTS_N"
						(effects
							(font
								(size 1.27 1.27)
							)
						)
					)
					(number "13"
						(effects
							(font
								(size 1.27 1.27)
							)
						)
					)
				)
				(pin bidirectional line
					(at 0 -54.61 0)
					(length 2.54)
					(name "SDIO_CMD"
						(effects
							(font
								(size 1.27 1.27)
							)
						)
					)
					(number "28"
						(effects
							(font
								(size 1.27 1.27)
							)
						)
					)
				)
				(pin bidirectional line
					(at 0 -57.15 0)
					(length 2.54)
					(name "SDIO_DATA_0"
						(effects
							(font
								(size 1.27 1.27)
							)
						)
					)
					(number "30"
						(effects
							(font
								(size 1.27 1.27)
							)
						)
					)
				)
				(pin bidirectional line
					(at 0 -59.69 0)
					(length 2.54)
					(name "SDIO_DATA_1"
						(effects
							(font
								(size 1.27 1.27)
							)
						)
					)
					(number "29"
						(effects
							(font
								(size 1.27 1.27)
							)
						)
					)
				)
				(pin bidirectional line
					(at 0 -62.23 0)
					(length 2.54)
					(name "SDIO_DATA_2"
						(effects
							(font
								(size 1.27 1.27)
							)
						)
					)
					(number "32"
						(effects
							(font
								(size 1.27 1.27)
							)
						)
					)
				)
				(pin bidirectional line
					(at 0 -64.77 0)
					(length 2.54)
					(name "SDIO_DATA_3"
						(effects
							(font
								(size 1.27 1.27)
							)
						)
					)
					(number "31"
						(effects
							(font
								(size 1.27 1.27)
							)
						)
					)
				)
				(pin input line
					(at 0 -67.31 0)
					(length 2.54)
					(name "SDIO_CLK"
						(effects
							(font
								(size 1.27 1.27)
							)
						)
					)
					(number "33"
						(effects
							(font
								(size 1.27 1.27)
							)
						)
					)
				)
				(pin bidirectional line
					(at 38.1 0 180)
					(length 2.54)
					(name "WL_ANT"
						(effects
							(font
								(size 1.27 1.27)
							)
						)
					)
					(number "22"
						(effects
							(font
								(size 1.27 1.27)
							)
						)
					)
				)
				(pin output line
					(at 38.1 -10.16 180)
					(length 2.54)
					(name "WL_HOST_WAKE"
						(effects
							(font
								(size 1.27 1.27)
							)
						)
					)
					(number "52"
						(effects
							(font
								(size 1.27 1.27)
							)
						)
					)
				)
				(pin input line
					(at 38.1 -15.24 180)
					(length 2.54)
					(name "JTAG_SEL"
						(effects
							(font
								(size 1.27 1.27)
							)
						)
					)
					(number "53"
						(effects
							(font
								(size 1.27 1.27)
							)
						)
					)
				)
				(pin bidirectional line
					(at 38.1 -17.78 180)
					(length 2.54)
					(name "TRST_L"
						(effects
							(font
								(size 1.27 1.27)
							)
						)
					)
					(number "63"
						(effects
							(font
								(size 1.27 1.27)
							)
						)
					)
				)
				(pin bidirectional line
					(at 38.1 -20.32 180)
					(length 2.54)
					(name "JTAG_TDI"
						(effects
							(font
								(size 1.27 1.27)
							)
						)
					)
					(number "64"
						(effects
							(font
								(size 1.27 1.27)
							)
						)
					)
				)
				(pin bidirectional line
					(at 38.1 -22.86 180)
					(length 2.54)
					(name "JTAG_TDO"
						(effects
							(font
								(size 1.27 1.27)
							)
						)
					)
					(number "65"
						(effects
							(font
								(size 1.27 1.27)
							)
						)
					)
				)
				(pin bidirectional line
					(at 38.1 -25.4 180)
					(length 2.54)
					(name "JTAG_TCK/SWCLK"
						(effects
							(font
								(size 1.27 1.27)
							)
						)
					)
					(number "66"
						(effects
							(font
								(size 1.27 1.27)
							)
						)
					)
				)
				(pin bidirectional line
					(at 38.1 -27.94 180)
					(length 2.54)
					(name "JTAG_TMS/SWDIO"
						(effects
							(font
								(size 1.27 1.27)
							)
						)
					)
					(number "67"
						(effects
							(font
								(size 1.27 1.27)
							)
						)
					)
				)
				(pin bidirectional line
					(at 38.1 -31.75 180)
					(length 2.54)
					(name "BT_HOST_WAKE"
						(effects
							(font
								(size 1.27 1.27)
							)
						)
					)
					(number "17"
						(effects
							(font
								(size 1.27 1.27)
							)
						)
					)
				)
				(pin bidirectional line
					(at 38.1 -34.29 180)
					(length 2.54)
					(name "BT_GPIO_2"
						(effects
							(font
								(size 1.27 1.27)
							)
						)
					)
					(number "18"
						(effects
							(font
								(size 1.27 1.27)
							)
						)
					)
				)
				(pin bidirectional line
					(at 38.1 -36.83 180)
					(length 2.54)
					(name "BT_GPIO_3"
						(effects
							(font
								(size 1.27 1.27)
							)
						)
					)
					(number "19"
						(effects
							(font
								(size 1.27 1.27)
							)
						)
					)
				)
				(pin bidirectional line
					(at 38.1 -39.37 180)
					(length 2.54)
					(name "BT_GPIO_5"
						(effects
							(font
								(size 1.27 1.27)
							)
						)
					)
					(number "20"
						(effects
							(font
								(size 1.27 1.27)
							)
						)
					)
				)
				(pin bidirectional line
					(at 38.1 -41.91 180)
					(length 2.54)
					(name "GPIO_1"
						(effects
							(font
								(size 1.27 1.27)
							)
						)
					)
					(number "45"
						(effects
							(font
								(size 1.27 1.27)
							)
						)
					)
				)
				(pin bidirectional line
					(at 38.1 -45.72 180)
					(length 2.54)
					(name "USB2_DP"
						(effects
							(font
								(size 1.27 1.27)
							)
						)
					)
					(number "47"
						(effects
							(font
								(size 1.27 1.27)
							)
						)
					)
				)
				(pin bidirectional line
					(at 38.1 -48.26 180)
					(length 2.54)
					(name "USB2_DM"
						(effects
							(font
								(size 1.27 1.27)
							)
						)
					)
					(number "46"
						(effects
							(font
								(size 1.27 1.27)
							)
						)
					)
				)
				(pin output line
					(at 38.1 -50.8 180)
					(length 2.54)
					(name "USB2_MONCDR"
						(effects
							(font
								(size 1.27 1.27)
							)
						)
					)
					(number "48"
						(effects
							(font
								(size 1.27 1.27)
							)
						)
					)
				)
				(pin bidirectional line
					(at 38.1 -53.34 180)
					(length 2.54)
					(name "USB2_RREF"
						(effects
							(font
								(size 1.27 1.27)
							)
						)
					)
					(number "50"
						(effects
							(font
								(size 1.27 1.27)
							)
						)
					)
				)
				(pin input line
					(at 38.1 -57.15 180)
					(length 2.54)
					(name "STRAP_0"
						(effects
							(font
								(size 1.27 1.27)
							)
						)
					)
					(number "56"
						(effects
							(font
								(size 1.27 1.27)
							)
						)
					)
				)
				(pin input line
					(at 38.1 -59.69 180)
					(length 2.54)
					(name "STRAP_1"
						(effects
							(font
								(size 1.27 1.27)
							)
						)
					)
					(number "54"
						(effects
							(font
								(size 1.27 1.27)
							)
						)
					)
				)
				(pin input line
					(at 38.1 -62.23 180)
					(length 2.54)
					(name "STRAP_2"
						(effects
							(font
								(size 1.27 1.27)
							)
						)
					)
					(number "55"
						(effects
							(font
								(size 1.27 1.27)
							)
						)
					)
				)
				(pin power_in line
					(at 38.1 -67.31 180)
					(length 2.54)
					(name "GND"
						(effects
							(font
								(size 1.27 1.27)
							)
						)
					)
					(number "1"
						(effects
							(font
								(size 1.27 1.27)
							)
						)
					)
				)
				(pin passive line
					(at 38.1 -67.31 180)
					(length 2.54)
					(hide yes)
					(name "GND"
						(effects
							(font
								(size 1.27 1.27)
							)
						)
					)
					(number "14"
						(effects
							(font
								(size 1.27 1.27)
							)
						)
					)
				)
				(pin passive line
					(at 38.1 -67.31 180)
					(length 2.54)
					(hide yes)
					(name "GND"
						(effects
							(font
								(size 1.27 1.27)
							)
						)
					)
					(number "16"
						(effects
							(font
								(size 1.27 1.27)
							)
						)
					)
				)
				(pin passive line
					(at 38.1 -67.31 180)
					(length 2.54)
					(hide yes)
					(name "GND"
						(effects
							(font
								(size 1.27 1.27)
							)
						)
					)
					(number "21"
						(effects
							(font
								(size 1.27 1.27)
							)
						)
					)
				)
				(pin passive line
					(at 38.1 -67.31 180)
					(length 2.54)
					(hide yes)
					(name "GND"
						(effects
							(font
								(size 1.27 1.27)
							)
						)
					)
					(number "23"
						(effects
							(font
								(size 1.27 1.27)
							)
						)
					)
				)
				(pin passive line
					(at 38.1 -67.31 180)
					(length 2.54)
					(hide yes)
					(name "GND"
						(effects
							(font
								(size 1.27 1.27)
							)
						)
					)
					(number "24"
						(effects
							(font
								(size 1.27 1.27)
							)
						)
					)
				)
				(pin passive line
					(at 38.1 -67.31 180)
					(length 2.54)
					(hide yes)
					(name "GND"
						(effects
							(font
								(size 1.27 1.27)
							)
						)
					)
					(number "27"
						(effects
							(font
								(size 1.27 1.27)
							)
						)
					)
				)
				(pin passive line
					(at 38.1 -67.31 180)
					(length 2.54)
					(hide yes)
					(name "GND"
						(effects
							(font
								(size 1.27 1.27)
							)
						)
					)
					(number "34"
						(effects
							(font
								(size 1.27 1.27)
							)
						)
					)
				)
				(pin passive line
					(at 38.1 -67.31 180)
					(length 2.54)
					(hide yes)
					(name "GND"
						(effects
							(font
								(size 1.27 1.27)
							)
						)
					)
					(number "41"
						(effects
							(font
								(size 1.27 1.27)
							)
						)
					)
				)
				(pin passive line
					(at 38.1 -67.31 180)
					(length 2.54)
					(hide yes)
					(name "GND"
						(effects
							(font
								(size 1.27 1.27)
							)
						)
					)
					(number "57"
						(effects
							(font
								(size 1.27 1.27)
							)
						)
					)
				)
				(pin passive line
					(at 38.1 -67.31 180)
					(length 2.54)
					(hide yes)
					(name "GND"
						(effects
							(font
								(size 1.27 1.27)
							)
						)
					)
					(number "69"
						(effects
							(font
								(size 1.27 1.27)
							)
						)
					)
				)
				(pin passive line
					(at 38.1 -67.31 180)
					(length 2.54)
					(hide yes)
					(name "GND"
						(effects
							(font
								(size 1.27 1.27)
							)
						)
					)
					(number "70"
						(effects
							(font
								(size 1.27 1.27)
							)
						)
					)
				)
				(pin passive line
					(at 38.1 -67.31 180)
					(length 2.54)
					(hide yes)
					(name "GND"
						(effects
							(font
								(size 1.27 1.27)
							)
						)
					)
					(number "71"
						(effects
							(font
								(size 1.27 1.27)
							)
						)
					)
				)
				(pin passive line
					(at 38.1 -67.31 180)
					(length 2.54)
					(hide yes)
					(name "GND"
						(effects
							(font
								(size 1.27 1.27)
							)
						)
					)
					(number "72"
						(effects
							(font
								(size 1.27 1.27)
							)
						)
					)
				)
				(pin passive line
					(at 38.1 -67.31 180)
					(length 2.54)
					(hide yes)
					(name "GND"
						(effects
							(font
								(size 1.27 1.27)
							)
						)
					)
					(number "73"
						(effects
							(font
								(size 1.27 1.27)
							)
						)
					)
				)
				(pin passive line
					(at 38.1 -67.31 180)
					(length 2.54)
					(hide yes)
					(name "GND"
						(effects
							(font
								(size 1.27 1.27)
							)
						)
					)
					(number "74"
						(effects
							(font
								(size 1.27 1.27)
							)
						)
					)
				)
				(pin passive line
					(at 38.1 -67.31 180)
					(length 2.54)
					(hide yes)
					(name "GND"
						(effects
							(font
								(size 1.27 1.27)
							)
						)
					)
					(number "75"
						(effects
							(font
								(size 1.27 1.27)
							)
						)
					)
				)
				(pin passive line
					(at 38.1 -67.31 180)
					(length 2.54)
					(hide yes)
					(name "GND"
						(effects
							(font
								(size 1.27 1.27)
							)
						)
					)
					(number "76"
						(effects
							(font
								(size 1.27 1.27)
							)
						)
					)
				)
				(pin passive line
					(at 38.1 -67.31 180)
					(length 2.54)
					(hide yes)
					(name "GND"
						(effects
							(font
								(size 1.27 1.27)
							)
						)
					)
					(number "77"
						(effects
							(font
								(size 1.27 1.27)
							)
						)
					)
				)
			)
			(symbol "WiFi_Bluetooth_LBEE5PK2AE_2_1"
				(rectangle
					(start 0 2.54)
					(end 11.43 -10.16)
					(stroke
						(width 0.254)
						(type default)
					)
					(fill
						(type background)
					)
				)
				(pin no_connect line
					(at 0 0 0)
					(length 2.54)
					(hide yes)
					(name "NC"
						(effects
							(font
								(size 1.27 1.27)
							)
						)
					)
					(number "62"
						(effects
							(font
								(size 1.27 1.27)
							)
						)
					)
				)
				(pin no_connect line
					(at 0 -1.27 0)
					(length 2.54)
					(hide yes)
					(name "NC"
						(effects
							(font
								(size 1.27 1.27)
							)
						)
					)
					(number "35"
						(effects
							(font
								(size 1.27 1.27)
							)
						)
					)
				)
				(pin no_connect line
					(at 0 -2.54 0)
					(length 2.54)
					(hide yes)
					(name "NC"
						(effects
							(font
								(size 1.27 1.27)
							)
						)
					)
					(number "36"
						(effects
							(font
								(size 1.27 1.27)
							)
						)
					)
				)
				(pin no_connect line
					(at 0 -3.81 0)
					(length 2.54)
					(hide yes)
					(name "NC"
						(effects
							(font
								(size 1.27 1.27)
							)
						)
					)
					(number "37"
						(effects
							(font
								(size 1.27 1.27)
							)
						)
					)
				)
				(pin no_connect line
					(at 0 -5.08 0)
					(length 2.54)
					(hide yes)
					(name "NC"
						(effects
							(font
								(size 1.27 1.27)
							)
						)
					)
					(number "15"
						(effects
							(font
								(size 1.27 1.27)
							)
						)
					)
				)
				(pin no_connect line
					(at 0 -6.35 0)
					(length 2.54)
					(hide yes)
					(name "NC"
						(effects
							(font
								(size 1.27 1.27)
							)
						)
					)
					(number "38"
						(effects
							(font
								(size 1.27 1.27)
							)
						)
					)
				)
				(pin no_connect line
					(at 0 -7.62 0)
					(length 2.54)
					(hide yes)
					(name "NC"
						(effects
							(font
								(size 1.27 1.27)
							)
						)
					)
					(number "39"
						(effects
							(font
								(size 1.27 1.27)
							)
						)
					)
				)
				(pin no_connect line
					(at 11.43 0 180)
					(length 2.54)
					(hide yes)
					(name "NC"
						(effects
							(font
								(size 1.27 1.27)
							)
						)
					)
					(number "40"
						(effects
							(font
								(size 1.27 1.27)
							)
						)
					)
				)
				(pin no_connect line
					(at 11.43 -1.27 180)
					(length 2.54)
					(hide yes)
					(name "NC"
						(effects
							(font
								(size 1.27 1.27)
							)
						)
					)
					(number "44"
						(effects
							(font
								(size 1.27 1.27)
							)
						)
					)
				)
				(pin no_connect line
					(at 11.43 -2.54 180)
					(length 2.54)
					(hide yes)
					(name "NC"
						(effects
							(font
								(size 1.27 1.27)
							)
						)
					)
					(number "58"
						(effects
							(font
								(size 1.27 1.27)
							)
						)
					)
				)
				(pin no_connect line
					(at 11.43 -3.81 180)
					(length 2.54)
					(hide yes)
					(name "NC"
						(effects
							(font
								(size 1.27 1.27)
							)
						)
					)
					(number "59"
						(effects
							(font
								(size 1.27 1.27)
							)
						)
					)
				)
				(pin no_connect line
					(at 11.43 -5.08 180)
					(length 2.54)
					(hide yes)
					(name "NC"
						(effects
							(font
								(size 1.27 1.27)
							)
						)
					)
					(number "60"
						(effects
							(font
								(size 1.27 1.27)
							)
						)
					)
				)
				(pin no_connect line
					(at 11.43 -6.35 180)
					(length 2.54)
					(hide yes)
					(name "NC"
						(effects
							(font
								(size 1.27 1.27)
							)
						)
					)
					(number "61"
						(effects
							(font
								(size 1.27 1.27)
							)
						)
					)
				)
			)
		)
	(symbol "antmicroResistorNetworksArrays:4x0R_0402_array"
			(pin_names
				(hide yes)
			)
			(exclude_from_sim no)
			(in_bom yes)
			(on_board yes)
			(property "Reference" "R"
				(at 25.4 -3.81 0)
				(effects
					(font
						(size 1.27 1.27)
						(thickness 0.15)
					)
					(justify left bottom)
				)
			)
			(property "Value" "4x0R_0402_array"
				(at 25.4 -6.35 0)
				(effects
					(font
						(size 1.27 1.27)
						(thickness 0.15)
					)
					(justify left bottom)
					(hide yes)
				)
			)
			(property "Footprint" "antmicro-footprints:4x0R_0402_array_EXB28V"
				(at 25.4 -11.43 0)
				(effects
					(font
						(size 1.27 1.27)
						(thickness 0.15)
					)
					(justify left bottom)
					(hide yes)
				)
			)
			(property "Datasheet" "https://industrial.panasonic.com/cdbs/www-data/pdf/AOC0000/AOC0000C14.pdf"
				(at 25.4 -13.97 0)
				(effects
					(font
						(size 1.27 1.27)
						(thickness 0.15)
					)
					(justify left bottom)
					(hide yes)
				)
			)
			(property "Description" "Zero Ohm Network Resistor, Jumper, 0402 [1005 Metric], Thick Film, Isolated, Convex, 4 Resistors"
				(at 0 0 0)
				(effects
					(font
						(size 1.27 1.27)
					)
					(hide yes)
				)
			)
			(property "MPN" "EXB28VR000X"
				(at 25.4 -16.51 0)
				(effects
					(font
						(size 1.27 1.27)
						(thickness 0.15)
					)
					(justify left bottom)
					(hide yes)
				)
			)
			(property "Manufacturer" "Panasonic"
				(at 25.4 -19.05 0)
				(effects
					(font
						(size 1.27 1.27)
						(thickness 0.15)
					)
					(justify left bottom)
					(hide yes)
				)
			)
			(property "Author" "Antmicro"
				(at 25.4 -21.59 0)
				(effects
					(font
						(size 1.27 1.27)
						(thickness 0.15)
					)
					(justify left bottom)
					(hide yes)
				)
			)
			(property "License" "Apache-2.0"
				(at 25.4 -24.13 0)
				(effects
					(font
						(size 1.27 1.27)
						(thickness 0.15)
					)
					(justify left bottom)
					(hide yes)
				)
			)
			(property "Val" "4x0R_0402"
				(at 25.4 -8.89 0)
				(effects
					(font
						(size 1.27 1.27)
					)
					(justify left bottom)
				)
			)
			(property "ki_keywords" "0201, SMT, RESISTOR, PASSIVE, ARRAY"
				(at 0 0 0)
				(effects
					(font
						(size 1.27 1.27)
					)
					(hide yes)
				)
			)
			(symbol "4x0R_0402_array_0_1"
				(polyline
					(pts
						(xy 2.54 0) (xy 3.175 0)
					)
					(stroke
						(width 0)
						(type default)
					)
					(fill
						(type none)
					)
				)
				(polyline
					(pts
						(xy 2.54 -2.54) (xy 3.175 -2.54)
					)
					(stroke
						(width 0)
						(type default)
					)
					(fill
						(type none)
					)
				)
				(polyline
					(pts
						(xy 2.54 -5.08) (xy 3.175 -5.08)
					)
					(stroke
						(width 0)
						(type default)
					)
					(fill
						(type none)
					)
				)
				(polyline
					(pts
						(xy 2.54 -7.62) (xy 3.175 -7.62)
					)
					(stroke
						(width 0)
						(type default)
					)
					(fill
						(type none)
					)
				)
				(rectangle
					(start 2.667 1.27)
					(end 7.493 -8.89)
					(stroke
						(width 0.254)
						(type default)
					)
					(fill
						(type background)
					)
				)
				(rectangle
					(start 6.985 0.635)
					(end 3.175 -0.635)
					(stroke
						(width 0.254)
						(type default)
					)
					(fill
						(type none)
					)
				)
				(polyline
					(pts
						(xy 6.985 0) (xy 7.62 0)
					)
					(stroke
						(width 0)
						(type default)
					)
					(fill
						(type none)
					)
				)
				(rectangle
					(start 6.985 -1.905)
					(end 3.175 -3.175)
					(stroke
						(width 0.254)
						(type default)
					)
					(fill
						(type none)
					)
				)
				(polyline
					(pts
						(xy 6.985 -2.54) (xy 7.62 -2.54)
					)
					(stroke
						(width 0)
						(type default)
					)
					(fill
						(type none)
					)
				)
				(rectangle
					(start 6.985 -4.445)
					(end 3.175 -5.715)
					(stroke
						(width 0.254)
						(type default)
					)
					(fill
						(type none)
					)
				)
				(polyline
					(pts
						(xy 6.985 -5.08) (xy 7.62 -5.08)
					)
					(stroke
						(width 0)
						(type default)
					)
					(fill
						(type none)
					)
				)
				(rectangle
					(start 6.985 -6.985)
					(end 3.175 -8.255)
					(stroke
						(width 0.254)
						(type default)
					)
					(fill
						(type none)
					)
				)
				(polyline
					(pts
						(xy 6.985 -7.62) (xy 7.62 -7.62)
					)
					(stroke
						(width 0)
						(type default)
					)
					(fill
						(type none)
					)
				)
			)
			(symbol "4x0R_0402_array_1_1"
				(pin passive line
					(at 0 0 0)
					(length 2.54)
					(name "R1.1"
						(effects
							(font
								(size 1.27 1.27)
							)
						)
					)
					(number "1"
						(effects
							(font
								(size 1.27 1.27)
							)
						)
					)
				)
				(pin passive line
					(at 0 -2.54 0)
					(length 2.54)
					(name "R2.1"
						(effects
							(font
								(size 1.27 1.27)
							)
						)
					)
					(number "2"
						(effects
							(font
								(size 1.27 1.27)
							)
						)
					)
				)
				(pin passive line
					(at 0 -5.08 0)
					(length 2.54)
					(name "R3.1"
						(effects
							(font
								(size 1.27 1.27)
							)
						)
					)
					(number "3"
						(effects
							(font
								(size 1.27 1.27)
							)
						)
					)
				)
				(pin passive line
					(at 0 -7.62 0)
					(length 2.54)
					(name "R4.1"
						(effects
							(font
								(size 1.27 1.27)
							)
						)
					)
					(number "4"
						(effects
							(font
								(size 1.27 1.27)
							)
						)
					)
				)
				(pin passive line
					(at 10.16 0 180)
					(length 2.54)
					(name "R1.2"
						(effects
							(font
								(size 1.27 1.27)
							)
						)
					)
					(number "8"
						(effects
							(font
								(size 1.27 1.27)
							)
						)
					)
				)
				(pin passive line
					(at 10.16 -2.54 180)
					(length 2.54)
					(name "R2.2"
						(effects
							(font
								(size 1.27 1.27)
							)
						)
					)
					(number "7"
						(effects
							(font
								(size 1.27 1.27)
							)
						)
					)
				)
				(pin passive line
					(at 10.16 -5.08 180)
					(length 2.54)
					(name "R3.2"
						(effects
							(font
								(size 1.27 1.27)
							)
						)
					)
					(number "6"
						(effects
							(font
								(size 1.27 1.27)
							)
						)
					)
				)
				(pin passive line
					(at 10.16 -7.62 180)
					(length 2.54)
					(name "R4.2"
						(effects
							(font
								(size 1.27 1.27)
							)
						)
					)
					(number "5"
						(effects
							(font
								(size 1.27 1.27)
							)
						)
					)
				)
			)
		)
	(symbol "antmicroResistorNetworksArrays:R_4x0R_0201_array"
			(pin_names
				(hide yes)
			)
			(exclude_from_sim no)
			(in_bom yes)
			(on_board yes)
			(property "Reference" "R"
				(at 26.67 -5.08 0)
				(effects
					(font
						(size 1.27 1.27)
						(thickness 0.15)
					)
					(justify left bottom)
				)
			)
			(property "Value" "R_4x0R_0201_array"
				(at 26.67 -7.62 0)
				(effects
					(font
						(size 1.27 1.27)
						(thickness 0.15)
					)
					(justify left bottom)
					(hide yes)
				)
			)
			(property "Footprint" "antmicro-footprints:R_Array_4x0201_Panasonic_EXB18V"
				(at 26.67 -12.7 0)
				(effects
					(font
						(size 1.27 1.27)
						(thickness 0.15)
					)
					(justify left bottom)
					(hide yes)
				)
			)
			(property "Datasheet" "http://industrial.panasonic.com/cdbs/www-data/pdf/AOC0000/AOC0000C14.pdf"
				(at 26.67 -15.24 0)
				(effects
					(font
						(size 1.27 1.27)
						(thickness 0.15)
					)
					(justify left bottom)
					(hide yes)
				)
			)
			(property "Description" "Zero Ohm Network Resistor, Jumper, 0201 [0603 Metric], Thick Film, Isolated, Flat, 4 Resistors"
				(at 0 0 0)
				(effects
					(font
						(size 1.27 1.27)
					)
					(hide yes)
				)
			)
			(property "MPN" "EXB-18VR000X"
				(at 26.67 -17.78 0)
				(effects
					(font
						(size 1.27 1.27)
						(thickness 0.15)
					)
					(justify left bottom)
					(hide yes)
				)
			)
			(property "Manufacturer" "Panasonic"
				(at 26.67 -20.32 0)
				(effects
					(font
						(size 1.27 1.27)
						(thickness 0.15)
					)
					(justify left bottom)
					(hide yes)
				)
			)
			(property "Val" "4x0R_0201"
				(at 26.67 -10.16 0)
				(effects
					(font
						(size 1.27 1.27)
						(thickness 0.15)
					)
					(justify left bottom)
				)
			)
			(property "Author" "Antmicro"
				(at 26.67 -22.86 0)
				(effects
					(font
						(size 1.27 1.27)
						(thickness 0.15)
					)
					(justify left bottom)
					(hide yes)
				)
			)
			(property "License" "Apache-2.0"
				(at 26.67 -25.4 0)
				(effects
					(font
						(size 1.27 1.27)
						(thickness 0.15)
					)
					(justify left bottom)
					(hide yes)
				)
			)
			(property "ki_keywords" "0201, SMT, RESISTOR, PASSIVE"
				(at 0 0 0)
				(effects
					(font
						(size 1.27 1.27)
					)
					(hide yes)
				)
			)
			(symbol "R_4x0R_0201_array_0_1"
				(polyline
					(pts
						(xy 2.54 0) (xy 3.175 0)
					)
					(stroke
						(width 0)
						(type default)
					)
					(fill
						(type none)
					)
				)
				(polyline
					(pts
						(xy 2.54 -2.54) (xy 3.175 -2.54)
					)
					(stroke
						(width 0)
						(type default)
					)
					(fill
						(type none)
					)
				)
				(polyline
					(pts
						(xy 2.54 -5.08) (xy 3.175 -5.08)
					)
					(stroke
						(width 0)
						(type default)
					)
					(fill
						(type none)
					)
				)
				(polyline
					(pts
						(xy 2.54 -7.62) (xy 3.175 -7.62)
					)
					(stroke
						(width 0)
						(type default)
					)
					(fill
						(type none)
					)
				)
				(rectangle
					(start 2.667 1.27)
					(end 7.493 -8.89)
					(stroke
						(width 0.254)
						(type default)
					)
					(fill
						(type background)
					)
				)
				(rectangle
					(start 6.985 0.635)
					(end 3.175 -0.635)
					(stroke
						(width 0.254)
						(type default)
					)
					(fill
						(type none)
					)
				)
				(polyline
					(pts
						(xy 6.985 0) (xy 7.62 0)
					)
					(stroke
						(width 0)
						(type default)
					)
					(fill
						(type none)
					)
				)
				(rectangle
					(start 6.985 -1.905)
					(end 3.175 -3.175)
					(stroke
						(width 0.254)
						(type default)
					)
					(fill
						(type none)
					)
				)
				(polyline
					(pts
						(xy 6.985 -2.54) (xy 7.62 -2.54)
					)
					(stroke
						(width 0)
						(type default)
					)
					(fill
						(type none)
					)
				)
				(rectangle
					(start 6.985 -4.445)
					(end 3.175 -5.715)
					(stroke
						(width 0.254)
						(type default)
					)
					(fill
						(type none)
					)
				)
				(polyline
					(pts
						(xy 6.985 -5.08) (xy 7.62 -5.08)
					)
					(stroke
						(width 0)
						(type default)
					)
					(fill
						(type none)
					)
				)
				(rectangle
					(start 6.985 -6.985)
					(end 3.175 -8.255)
					(stroke
						(width 0.254)
						(type default)
					)
					(fill
						(type none)
					)
				)
				(polyline
					(pts
						(xy 6.985 -7.62) (xy 7.62 -7.62)
					)
					(stroke
						(width 0)
						(type default)
					)
					(fill
						(type none)
					)
				)
			)
			(symbol "R_4x0R_0201_array_1_1"
				(pin passive line
					(at 0 0 0)
					(length 2.54)
					(name "R1.1"
						(effects
							(font
								(size 1.27 1.27)
							)
						)
					)
					(number "1"
						(effects
							(font
								(size 1.27 1.27)
							)
						)
					)
				)
				(pin passive line
					(at 0 -2.54 0)
					(length 2.54)
					(name "R2.1"
						(effects
							(font
								(size 1.27 1.27)
							)
						)
					)
					(number "2"
						(effects
							(font
								(size 1.27 1.27)
							)
						)
					)
				)
				(pin passive line
					(at 0 -5.08 0)
					(length 2.54)
					(name "R3.1"
						(effects
							(font
								(size 1.27 1.27)
							)
						)
					)
					(number "3"
						(effects
							(font
								(size 1.27 1.27)
							)
						)
					)
				)
				(pin passive line
					(at 0 -7.62 0)
					(length 2.54)
					(name "R4.1"
						(effects
							(font
								(size 1.27 1.27)
							)
						)
					)
					(number "4"
						(effects
							(font
								(size 1.27 1.27)
							)
						)
					)
				)
				(pin passive line
					(at 10.16 0 180)
					(length 2.54)
					(name "R1.2"
						(effects
							(font
								(size 1.27 1.27)
							)
						)
					)
					(number "8"
						(effects
							(font
								(size 1.27 1.27)
							)
						)
					)
				)
				(pin passive line
					(at 10.16 -2.54 180)
					(length 2.54)
					(name "R2.2"
						(effects
							(font
								(size 1.27 1.27)
							)
						)
					)
					(number "7"
						(effects
							(font
								(size 1.27 1.27)
							)
						)
					)
				)
				(pin passive line
					(at 10.16 -5.08 180)
					(length 2.54)
					(name "R3.2"
						(effects
							(font
								(size 1.27 1.27)
							)
						)
					)
					(number "6"
						(effects
							(font
								(size 1.27 1.27)
							)
						)
					)
				)
				(pin passive line
					(at 10.16 -7.62 180)
					(length 2.54)
					(name "R4.2"
						(effects
							(font
								(size 1.27 1.27)
							)
						)
					)
					(number "5"
						(effects
							(font
								(size 1.27 1.27)
							)
						)
					)
				)
			)
		)
	(symbol "antmicroResistors0402:R_0R_0402"
			(pin_numbers
				(hide yes)
			)
			(pin_names
				(hide yes)
			)
			(exclude_from_sim no)
			(in_bom yes)
			(on_board yes)
			(property "Reference" "R"
				(at 20.32 -5.08 0)
				(effects
					(font
						(size 1.27 1.27)
						(thickness 0.15)
					)
					(justify left bottom)
				)
			)
			(property "Value" "R_0R_0402"
				(at 20.32 -12.7 0)
				(effects
					(font
						(size 1.27 1.27)
						(thickness 0.15)
					)
					(justify left bottom)
					(hide yes)
				)
			)
			(property "Footprint" "antmicro-footprints:R_0402_1005Metric"
				(at 20.32 -15.24 0)
				(effects
					(font
						(size 1.27 1.27)
						(thickness 0.15)
					)
					(justify left bottom)
					(hide yes)
				)
			)
			(property "Datasheet" "https://industrial.panasonic.com/cdbs/www-data/pdf/RDA0000/AOA0000C301.pdf"
				(at 20.32 -17.78 0)
				(effects
					(font
						(size 1.27 1.27)
						(thickness 0.15)
					)
					(justify left bottom)
					(hide yes)
				)
			)
			(property "Description" "SMD Chip Resistor, Jumper, 0 ohm, 100 mW, 0402 [1005 Metric], Thick Film, General Purpose"
				(at 0 0 0)
				(effects
					(font
						(size 1.27 1.27)
					)
					(hide yes)
				)
			)
			(property "MPN" "ERJ2GE0R00X"
				(at 20.32 -20.32 0)
				(effects
					(font
						(size 1.27 1.27)
						(thickness 0.15)
					)
					(justify left bottom)
					(hide yes)
				)
			)
			(property "Manufacturer" "Panasonic"
				(at 20.32 -22.86 0)
				(effects
					(font
						(size 1.27 1.27)
						(thickness 0.15)
					)
					(justify left bottom)
					(hide yes)
				)
			)
			(property "License" "Apache-2.0"
				(at 20.32 -25.4 0)
				(effects
					(font
						(size 1.27 1.27)
						(thickness 0.15)
					)
					(justify left bottom)
					(hide yes)
				)
			)
			(property "Author" "Antmicro"
				(at 20.32 -27.94 0)
				(effects
					(font
						(size 1.27 1.27)
						(thickness 0.15)
					)
					(justify left bottom)
					(hide yes)
				)
			)
			(property "Val" "0R"
				(at 20.32 -7.62 0)
				(effects
					(font
						(size 1.27 1.27)
						(thickness 0.15)
					)
					(justify left bottom)
				)
			)
			(property "Tolerance" "~"
				(at 20.32 -10.16 0)
				(effects
					(font
						(size 1.27 1.27)
					)
					(justify left bottom)
					(hide yes)
				)
			)
			(property "Current" "1A"
				(at 20.32 -30.48 0)
				(effects
					(font
						(size 1.27 1.27)
						(thickness 0.15)
					)
					(justify left bottom)
					(hide yes)
				)
			)
			(property "ki_keywords" "0402, SMT, RESISTOR, PASSIVE"
				(at 0 0 0)
				(effects
					(font
						(size 1.27 1.27)
					)
					(hide yes)
				)
			)
			(symbol "R_0R_0402_0_1"
				(rectangle
					(start 0.635 0.889)
					(end 4.445 -0.889)
					(stroke
						(width 0.254)
						(type default)
					)
					(fill
						(type none)
					)
				)
			)
			(symbol "R_0R_0402_1_1"
				(pin passive line
					(at 0 0 0)
					(length 0.635)
					(name "~"
						(effects
							(font
								(size 1.27 1.27)
							)
						)
					)
					(number "1"
						(effects
							(font
								(size 1.27 1.27)
							)
						)
					)
				)
				(pin passive line
					(at 5.08 0 180)
					(length 0.635)
					(name "~"
						(effects
							(font
								(size 1.27 1.27)
							)
						)
					)
					(number "2"
						(effects
							(font
								(size 1.27 1.27)
							)
						)
					)
				)
			)
		)
	(symbol "antmicroResistors0402:R_100k_0402"
			(pin_numbers
				(hide yes)
			)
			(pin_names
				(hide yes)
			)
			(exclude_from_sim no)
			(in_bom yes)
			(on_board yes)
			(property "Reference" "R"
				(at 20.32 -5.08 0)
				(effects
					(font
						(size 1.27 1.27)
						(thickness 0.15)
					)
					(justify left bottom)
				)
			)
			(property "Value" "R_100k_0402"
				(at 20.32 -12.7 0)
				(effects
					(font
						(size 1.27 1.27)
						(thickness 0.15)
					)
					(justify left bottom)
					(hide yes)
				)
			)
			(property "Footprint" "antmicro-footprints:R_0402_1005Metric"
				(at 20.32 -15.24 0)
				(effects
					(font
						(size 1.27 1.27)
						(thickness 0.15)
					)
					(justify left bottom)
					(hide yes)
				)
			)
			(property "Datasheet" "https://www.bourns.com/docs/product-datasheets/cr.pdf"
				(at 20.32 -17.78 0)
				(effects
					(font
						(size 1.27 1.27)
						(thickness 0.15)
					)
					(justify left bottom)
					(hide yes)
				)
			)
			(property "Description" "SMD Chip Resistor, 100 kohm, ± 1%, 62.5 mW, 0402 [1005 Metric], Thick Film, General Purpose"
				(at 0 0 0)
				(effects
					(font
						(size 1.27 1.27)
					)
					(hide yes)
				)
			)
			(property "MPN" "CR0402-FX-1003GLF"
				(at 20.32 -20.32 0)
				(effects
					(font
						(size 1.27 1.27)
						(thickness 0.15)
					)
					(justify left bottom)
					(hide yes)
				)
			)
			(property "Manufacturer" "Bourns"
				(at 20.32 -22.86 0)
				(effects
					(font
						(size 1.27 1.27)
						(thickness 0.15)
					)
					(justify left bottom)
					(hide yes)
				)
			)
			(property "License" "Apache-2.0"
				(at 20.32 -25.4 0)
				(effects
					(font
						(size 1.27 1.27)
						(thickness 0.15)
					)
					(justify left bottom)
					(hide yes)
				)
			)
			(property "Author" "Antmicro"
				(at 20.32 -27.94 0)
				(effects
					(font
						(size 1.27 1.27)
						(thickness 0.15)
					)
					(justify left bottom)
					(hide yes)
				)
			)
			(property "Val" "100k"
				(at 20.32 -7.62 0)
				(effects
					(font
						(size 1.27 1.27)
						(thickness 0.15)
					)
					(justify left bottom)
				)
			)
			(property "Tolerance" "1%"
				(at 20.32 -10.16 0)
				(effects
					(font
						(size 1.27 1.27)
					)
					(justify left bottom)
					(hide yes)
				)
			)
			(property "ki_keywords" "0402, SMT, RESISTOR, PASSIVE"
				(at 0 0 0)
				(effects
					(font
						(size 1.27 1.27)
					)
					(hide yes)
				)
			)
			(symbol "R_100k_0402_0_1"
				(rectangle
					(start 0.635 0.889)
					(end 4.445 -0.889)
					(stroke
						(width 0.254)
						(type default)
					)
					(fill
						(type none)
					)
				)
			)
			(symbol "R_100k_0402_1_1"
				(pin passive line
					(at 0 0 0)
					(length 0.635)
					(name "~"
						(effects
							(font
								(size 1.27 1.27)
							)
						)
					)
					(number "1"
						(effects
							(font
								(size 1.27 1.27)
							)
						)
					)
				)
				(pin passive line
					(at 5.08 0 180)
					(length 0.635)
					(name "~"
						(effects
							(font
								(size 1.27 1.27)
							)
						)
					)
					(number "2"
						(effects
							(font
								(size 1.27 1.27)
							)
						)
					)
				)
			)
		)
	(symbol "antmicroResistors0402:R_10k_0402"
			(pin_numbers
				(hide yes)
			)
			(pin_names
				(hide yes)
			)
			(exclude_from_sim no)
			(in_bom yes)
			(on_board yes)
			(property "Reference" "R"
				(at 20.32 -5.08 0)
				(effects
					(font
						(size 1.27 1.27)
						(thickness 0.15)
					)
					(justify left bottom)
				)
			)
			(property "Value" "R_10k_0402"
				(at 20.32 -12.7 0)
				(effects
					(font
						(size 1.27 1.27)
						(thickness 0.15)
					)
					(justify left bottom)
					(hide yes)
				)
			)
			(property "Footprint" "antmicro-footprints:R_0402_1005Metric"
				(at 20.32 -15.24 0)
				(effects
					(font
						(size 1.27 1.27)
						(thickness 0.15)
					)
					(justify left bottom)
					(hide yes)
				)
			)
			(property "Datasheet" "https://www.bourns.com/docs/product-datasheets/cr.pdf"
				(at 20.32 -17.78 0)
				(effects
					(font
						(size 1.27 1.27)
						(thickness 0.15)
					)
					(justify left bottom)
					(hide yes)
				)
			)
			(property "Description" "SMD Chip Resistor, 10 kohm, ± 1%, 62.5 mW, 0402 [1005 Metric], Thick Film, General Purpose"
				(at 0 0 0)
				(effects
					(font
						(size 1.27 1.27)
					)
					(hide yes)
				)
			)
			(property "MPN" "CR0402-FX-1002GLF"
				(at 20.32 -20.32 0)
				(effects
					(font
						(size 1.27 1.27)
						(thickness 0.15)
					)
					(justify left bottom)
					(hide yes)
				)
			)
			(property "Manufacturer" "Bourns"
				(at 20.32 -22.86 0)
				(effects
					(font
						(size 1.27 1.27)
						(thickness 0.15)
					)
					(justify left bottom)
					(hide yes)
				)
			)
			(property "License" "Apache-2.0"
				(at 20.32 -25.4 0)
				(effects
					(font
						(size 1.27 1.27)
						(thickness 0.15)
					)
					(justify left bottom)
					(hide yes)
				)
			)
			(property "Author" "Antmicro"
				(at 20.32 -27.94 0)
				(effects
					(font
						(size 1.27 1.27)
						(thickness 0.15)
					)
					(justify left bottom)
					(hide yes)
				)
			)
			(property "Val" "10k"
				(at 20.32 -7.62 0)
				(effects
					(font
						(size 1.27 1.27)
						(thickness 0.15)
					)
					(justify left bottom)
				)
			)
			(property "Tolerance" "1%"
				(at 20.32 -10.16 0)
				(effects
					(font
						(size 1.27 1.27)
					)
					(justify left bottom)
					(hide yes)
				)
			)
			(property "ki_keywords" "0402, SMT, RESISTOR, PASSIVE"
				(at 0 0 0)
				(effects
					(font
						(size 1.27 1.27)
					)
					(hide yes)
				)
			)
			(symbol "R_10k_0402_0_1"
				(rectangle
					(start 0.635 0.889)
					(end 4.445 -0.889)
					(stroke
						(width 0.254)
						(type default)
					)
					(fill
						(type none)
					)
				)
			)
			(symbol "R_10k_0402_1_1"
				(pin passive line
					(at 0 0 0)
					(length 0.635)
					(name "~"
						(effects
							(font
								(size 1.27 1.27)
							)
						)
					)
					(number "1"
						(effects
							(font
								(size 1.27 1.27)
							)
						)
					)
				)
				(pin passive line
					(at 5.08 0 180)
					(length 0.635)
					(name "~"
						(effects
							(font
								(size 1.27 1.27)
							)
						)
					)
					(number "2"
						(effects
							(font
								(size 1.27 1.27)
							)
						)
					)
				)
			)
		)
	(symbol "antmicroResistors0402:R_11k_0402"
			(pin_numbers
				(hide yes)
			)
			(pin_names
				(hide yes)
			)
			(exclude_from_sim no)
			(in_bom yes)
			(on_board yes)
			(property "Reference" "R"
				(at 20.32 -5.08 0)
				(effects
					(font
						(size 1.27 1.27)
						(thickness 0.15)
					)
					(justify left bottom)
				)
			)
			(property "Value" "R_11k_0402"
				(at 20.32 -12.7 0)
				(effects
					(font
						(size 1.27 1.27)
						(thickness 0.15)
					)
					(justify left bottom)
					(hide yes)
				)
			)
			(property "Footprint" "antmicro-footprints:R_0402_1005Metric"
				(at 20.32 -15.24 0)
				(effects
					(font
						(size 1.27 1.27)
						(thickness 0.15)
					)
					(justify left bottom)
					(hide yes)
				)
			)
			(property "Datasheet" "https://www.bourns.com/docs/product-datasheets/cr.pdf"
				(at 20.32 -17.78 0)
				(effects
					(font
						(size 1.27 1.27)
						(thickness 0.15)
					)
					(justify left bottom)
					(hide yes)
				)
			)
			(property "Description" "SMD Chip Resistor, 11 kohm, ± 1%, 62.5 mW, 0402 [1005 Metric], Thick Film, General Purpose"
				(at 0 0 0)
				(effects
					(font
						(size 1.27 1.27)
					)
					(hide yes)
				)
			)
			(property "MPN" "CR0402-FX-1102GLF"
				(at 20.32 -20.32 0)
				(effects
					(font
						(size 1.27 1.27)
						(thickness 0.15)
					)
					(justify left bottom)
					(hide yes)
				)
			)
			(property "Manufacturer" "Bourns"
				(at 20.32 -22.86 0)
				(effects
					(font
						(size 1.27 1.27)
						(thickness 0.15)
					)
					(justify left bottom)
					(hide yes)
				)
			)
			(property "License" "Apache-2.0"
				(at 20.32 -25.4 0)
				(effects
					(font
						(size 1.27 1.27)
						(thickness 0.15)
					)
					(justify left bottom)
					(hide yes)
				)
			)
			(property "Author" "Antmicro"
				(at 20.32 -27.94 0)
				(effects
					(font
						(size 1.27 1.27)
						(thickness 0.15)
					)
					(justify left bottom)
					(hide yes)
				)
			)
			(property "Val" "11k"
				(at 20.32 -7.62 0)
				(effects
					(font
						(size 1.27 1.27)
						(thickness 0.15)
					)
					(justify left bottom)
				)
			)
			(property "Tolerance" "1%"
				(at 20.32 -10.16 0)
				(effects
					(font
						(size 1.27 1.27)
					)
					(justify left bottom)
					(hide yes)
				)
			)
			(property "ki_keywords" "0402, SMT, RESISTOR, PASSIVE"
				(at 0 0 0)
				(effects
					(font
						(size 1.27 1.27)
					)
					(hide yes)
				)
			)
			(symbol "R_11k_0402_0_1"
				(rectangle
					(start 0.635 0.889)
					(end 4.445 -0.889)
					(stroke
						(width 0.254)
						(type default)
					)
					(fill
						(type none)
					)
				)
			)
			(symbol "R_11k_0402_1_1"
				(pin passive line
					(at 0 0 0)
					(length 0.635)
					(name "~"
						(effects
							(font
								(size 1.27 1.27)
							)
						)
					)
					(number "1"
						(effects
							(font
								(size 1.27 1.27)
							)
						)
					)
				)
				(pin passive line
					(at 5.08 0 180)
					(length 0.635)
					(name "~"
						(effects
							(font
								(size 1.27 1.27)
							)
						)
					)
					(number "2"
						(effects
							(font
								(size 1.27 1.27)
							)
						)
					)
				)
			)
		)
	(symbol "antmicroResistors0402:R_12k_0402"
			(pin_numbers
				(hide yes)
			)
			(pin_names
				(hide yes)
			)
			(exclude_from_sim no)
			(in_bom yes)
			(on_board yes)
			(property "Reference" "R"
				(at 20.32 -5.08 0)
				(effects
					(font
						(size 1.27 1.27)
						(thickness 0.15)
					)
					(justify left bottom)
				)
			)
			(property "Value" "R_12k_0402"
				(at 20.32 -12.7 0)
				(effects
					(font
						(size 1.27 1.27)
						(thickness 0.15)
					)
					(justify left bottom)
					(hide yes)
				)
			)
			(property "Footprint" "antmicro-footprints:R_0402_1005Metric"
				(at 20.32 -15.24 0)
				(effects
					(font
						(size 1.27 1.27)
						(thickness 0.15)
					)
					(justify left bottom)
					(hide yes)
				)
			)
			(property "Datasheet" "https://www.bourns.com/docs/product-datasheets/cr.pdf"
				(at 20.32 -17.78 0)
				(effects
					(font
						(size 1.27 1.27)
						(thickness 0.15)
					)
					(justify left bottom)
					(hide yes)
				)
			)
			(property "Description" "SMD Chip Resistor, 12 kohm, ± 1%, 62.5 mW, 0402 [1005 Metric], Thick Film, General Purpose"
				(at 0 0 0)
				(effects
					(font
						(size 1.27 1.27)
					)
					(hide yes)
				)
			)
			(property "MPN" "CR0402-FX-1202GLF"
				(at 20.32 -20.32 0)
				(effects
					(font
						(size 1.27 1.27)
						(thickness 0.15)
					)
					(justify left bottom)
					(hide yes)
				)
			)
			(property "Manufacturer" "Bourns"
				(at 20.32 -22.86 0)
				(effects
					(font
						(size 1.27 1.27)
						(thickness 0.15)
					)
					(justify left bottom)
					(hide yes)
				)
			)
			(property "License" "Apache-2.0"
				(at 20.32 -25.4 0)
				(effects
					(font
						(size 1.27 1.27)
						(thickness 0.15)
					)
					(justify left bottom)
					(hide yes)
				)
			)
			(property "Author" "Antmicro"
				(at 20.32 -27.94 0)
				(effects
					(font
						(size 1.27 1.27)
						(thickness 0.15)
					)
					(justify left bottom)
					(hide yes)
				)
			)
			(property "Val" "12k"
				(at 20.32 -7.62 0)
				(effects
					(font
						(size 1.27 1.27)
						(thickness 0.15)
					)
					(justify left bottom)
				)
			)
			(property "Tolerance" "1%"
				(at 20.32 -10.16 0)
				(effects
					(font
						(size 1.27 1.27)
					)
					(justify left bottom)
					(hide yes)
				)
			)
			(property "ki_keywords" "0402, SMT, RESISTOR, PASSIVE"
				(at 0 0 0)
				(effects
					(font
						(size 1.27 1.27)
					)
					(hide yes)
				)
			)
			(symbol "R_12k_0402_0_1"
				(rectangle
					(start 0.635 0.889)
					(end 4.445 -0.889)
					(stroke
						(width 0.254)
						(type default)
					)
					(fill
						(type none)
					)
				)
			)
			(symbol "R_12k_0402_1_1"
				(pin passive line
					(at 0 0 0)
					(length 0.635)
					(name "~"
						(effects
							(font
								(size 1.27 1.27)
							)
						)
					)
					(number "1"
						(effects
							(font
								(size 1.27 1.27)
							)
						)
					)
				)
				(pin passive line
					(at 5.08 0 180)
					(length 0.635)
					(name "~"
						(effects
							(font
								(size 1.27 1.27)
							)
						)
					)
					(number "2"
						(effects
							(font
								(size 1.27 1.27)
							)
						)
					)
				)
			)
		)
	(symbol "antmicroResistors0402:R_1M_0402"
			(pin_numbers
				(hide yes)
			)
			(pin_names
				(hide yes)
			)
			(exclude_from_sim no)
			(in_bom yes)
			(on_board yes)
			(property "Reference" "R"
				(at 20.32 -5.08 0)
				(effects
					(font
						(size 1.27 1.27)
						(thickness 0.15)
					)
					(justify left bottom)
				)
			)
			(property "Value" "R_1M_0402"
				(at 20.32 -12.7 0)
				(effects
					(font
						(size 1.27 1.27)
						(thickness 0.15)
					)
					(justify left bottom)
					(hide yes)
				)
			)
			(property "Footprint" "antmicro-footprints:R_0402_1005Metric"
				(at 20.32 -15.24 0)
				(effects
					(font
						(size 1.27 1.27)
						(thickness 0.15)
					)
					(justify left bottom)
					(hide yes)
				)
			)
			(property "Datasheet" "https://www.bourns.com/docs/product-datasheets/cr.pdf"
				(at 20.32 -17.78 0)
				(effects
					(font
						(size 1.27 1.27)
						(thickness 0.15)
					)
					(justify left bottom)
					(hide yes)
				)
			)
			(property "Description" "SMD Chip Resistor, 1 Mohm, ± 1%, 62.5 mW, 0402 [1005 Metric], Thick Film, General Purpose"
				(at 0 0 0)
				(effects
					(font
						(size 1.27 1.27)
					)
					(hide yes)
				)
			)
			(property "MPN" "CR0402-FX-1004GLF"
				(at 20.32 -20.32 0)
				(effects
					(font
						(size 1.27 1.27)
						(thickness 0.15)
					)
					(justify left bottom)
					(hide yes)
				)
			)
			(property "Manufacturer" "Bourns"
				(at 20.32 -22.86 0)
				(effects
					(font
						(size 1.27 1.27)
						(thickness 0.15)
					)
					(justify left bottom)
					(hide yes)
				)
			)
			(property "License" "Apache-2.0"
				(at 20.32 -25.4 0)
				(effects
					(font
						(size 1.27 1.27)
						(thickness 0.15)
					)
					(justify left bottom)
					(hide yes)
				)
			)
			(property "Author" "Antmicro"
				(at 20.32 -27.94 0)
				(effects
					(font
						(size 1.27 1.27)
						(thickness 0.15)
					)
					(justify left bottom)
					(hide yes)
				)
			)
			(property "Val" "1M"
				(at 20.32 -7.62 0)
				(effects
					(font
						(size 1.27 1.27)
						(thickness 0.15)
					)
					(justify left bottom)
				)
			)
			(property "Tolerance" "1%"
				(at 20.32 -10.16 0)
				(effects
					(font
						(size 1.27 1.27)
					)
					(justify left bottom)
					(hide yes)
				)
			)
			(property "ki_keywords" "0402, SMT, RESISTOR, PASSIVE"
				(at 0 0 0)
				(effects
					(font
						(size 1.27 1.27)
					)
					(hide yes)
				)
			)
			(symbol "R_1M_0402_0_1"
				(rectangle
					(start 0.635 0.889)
					(end 4.445 -0.889)
					(stroke
						(width 0.254)
						(type default)
					)
					(fill
						(type none)
					)
				)
			)
			(symbol "R_1M_0402_1_1"
				(pin passive line
					(at 0 0 0)
					(length 0.635)
					(name "~"
						(effects
							(font
								(size 1.27 1.27)
							)
						)
					)
					(number "1"
						(effects
							(font
								(size 1.27 1.27)
							)
						)
					)
				)
				(pin passive line
					(at 5.08 0 180)
					(length 0.635)
					(name "~"
						(effects
							(font
								(size 1.27 1.27)
							)
						)
					)
					(number "2"
						(effects
							(font
								(size 1.27 1.27)
							)
						)
					)
				)
			)
		)
	(symbol "antmicroResistors0402:R_1k5_0402"
			(pin_numbers
				(hide yes)
			)
			(pin_names
				(hide yes)
			)
			(exclude_from_sim no)
			(in_bom yes)
			(on_board yes)
			(property "Reference" "R"
				(at 20.32 -5.08 0)
				(effects
					(font
						(size 1.27 1.27)
						(thickness 0.15)
					)
					(justify left bottom)
				)
			)
			(property "Value" "R_1k5_0402"
				(at 20.32 -12.7 0)
				(effects
					(font
						(size 1.27 1.27)
						(thickness 0.15)
					)
					(justify left bottom)
					(hide yes)
				)
			)
			(property "Footprint" "antmicro-footprints:R_0402_1005Metric"
				(at 20.32 -15.24 0)
				(effects
					(font
						(size 1.27 1.27)
						(thickness 0.15)
					)
					(justify left bottom)
					(hide yes)
				)
			)
			(property "Datasheet" "https://www.bourns.com/docs/product-datasheets/cr.pdf"
				(at 20.32 -17.78 0)
				(effects
					(font
						(size 1.27 1.27)
						(thickness 0.15)
					)
					(justify left bottom)
					(hide yes)
				)
			)
			(property "Description" "SMD Chip Resistor, 1.5 kohm, ± 1%, 62.5 mW, 0402 [1005 Metric], Thick Film, General Purpose"
				(at 0 0 0)
				(effects
					(font
						(size 1.27 1.27)
					)
					(hide yes)
				)
			)
			(property "MPN" "CR0402-FX-1501GLF"
				(at 20.32 -20.32 0)
				(effects
					(font
						(size 1.27 1.27)
						(thickness 0.15)
					)
					(justify left bottom)
					(hide yes)
				)
			)
			(property "Manufacturer" "Bourns"
				(at 20.32 -22.86 0)
				(effects
					(font
						(size 1.27 1.27)
						(thickness 0.15)
					)
					(justify left bottom)
					(hide yes)
				)
			)
			(property "License" "Apache-2.0"
				(at 20.32 -25.4 0)
				(effects
					(font
						(size 1.27 1.27)
						(thickness 0.15)
					)
					(justify left bottom)
					(hide yes)
				)
			)
			(property "Author" "Antmicro"
				(at 20.32 -27.94 0)
				(effects
					(font
						(size 1.27 1.27)
						(thickness 0.15)
					)
					(justify left bottom)
					(hide yes)
				)
			)
			(property "Val" "1k5"
				(at 20.32 -7.62 0)
				(effects
					(font
						(size 1.27 1.27)
						(thickness 0.15)
					)
					(justify left bottom)
				)
			)
			(property "Tolerance" "1%"
				(at 20.32 -10.16 0)
				(effects
					(font
						(size 1.27 1.27)
					)
					(justify left bottom)
					(hide yes)
				)
			)
			(property "ki_keywords" "0402, SMT, RESISTOR, PASSIVE"
				(at 0 0 0)
				(effects
					(font
						(size 1.27 1.27)
					)
					(hide yes)
				)
			)
			(symbol "R_1k5_0402_0_1"
				(rectangle
					(start 0.635 0.889)
					(end 4.445 -0.889)
					(stroke
						(width 0.254)
						(type default)
					)
					(fill
						(type none)
					)
				)
			)
			(symbol "R_1k5_0402_1_1"
				(pin passive line
					(at 0 0 0)
					(length 0.635)
					(name "~"
						(effects
							(font
								(size 1.27 1.27)
							)
						)
					)
					(number "1"
						(effects
							(font
								(size 1.27 1.27)
							)
						)
					)
				)
				(pin passive line
					(at 5.08 0 180)
					(length 0.635)
					(name "~"
						(effects
							(font
								(size 1.27 1.27)
							)
						)
					)
					(number "2"
						(effects
							(font
								(size 1.27 1.27)
							)
						)
					)
				)
			)
		)
	(symbol "antmicroResistors0402:R_1k_0402"
			(pin_numbers
				(hide yes)
			)
			(pin_names
				(hide yes)
			)
			(exclude_from_sim no)
			(in_bom yes)
			(on_board yes)
			(property "Reference" "R"
				(at 20.32 -5.08 0)
				(effects
					(font
						(size 1.27 1.27)
						(thickness 0.15)
					)
					(justify left bottom)
				)
			)
			(property "Value" "R_1k_0402"
				(at 20.32 -12.7 0)
				(effects
					(font
						(size 1.27 1.27)
						(thickness 0.15)
					)
					(justify left bottom)
					(hide yes)
				)
			)
			(property "Footprint" "antmicro-footprints:R_0402_1005Metric"
				(at 20.32 -15.24 0)
				(effects
					(font
						(size 1.27 1.27)
						(thickness 0.15)
					)
					(justify left bottom)
					(hide yes)
				)
			)
			(property "Datasheet" "https://www.bourns.com/docs/product-datasheets/cr.pdf"
				(at 20.32 -17.78 0)
				(effects
					(font
						(size 1.27 1.27)
						(thickness 0.15)
					)
					(justify left bottom)
					(hide yes)
				)
			)
			(property "Description" "SMD Chip Resistor, 1 kohm, ± 1%, 63 mW, 0402 [1005 Metric], Thick Film, General Purpose"
				(at 0 0 0)
				(effects
					(font
						(size 1.27 1.27)
					)
					(hide yes)
				)
			)
			(property "MPN" "CR0402-FX-1001GLF"
				(at 20.32 -20.32 0)
				(effects
					(font
						(size 1.27 1.27)
						(thickness 0.15)
					)
					(justify left bottom)
					(hide yes)
				)
			)
			(property "Manufacturer" "Bourns"
				(at 20.32 -22.86 0)
				(effects
					(font
						(size 1.27 1.27)
						(thickness 0.15)
					)
					(justify left bottom)
					(hide yes)
				)
			)
			(property "License" "Apache-2.0"
				(at 20.32 -25.4 0)
				(effects
					(font
						(size 1.27 1.27)
						(thickness 0.15)
					)
					(justify left bottom)
					(hide yes)
				)
			)
			(property "Author" "Antmicro"
				(at 20.32 -27.94 0)
				(effects
					(font
						(size 1.27 1.27)
						(thickness 0.15)
					)
					(justify left bottom)
					(hide yes)
				)
			)
			(property "Val" "1k"
				(at 20.32 -7.62 0)
				(effects
					(font
						(size 1.27 1.27)
						(thickness 0.15)
					)
					(justify left bottom)
				)
			)
			(property "Tolerance" "1%"
				(at 20.32 -10.16 0)
				(effects
					(font
						(size 1.27 1.27)
					)
					(justify left bottom)
					(hide yes)
				)
			)
			(property "ki_keywords" "0402, SMT, RESISTOR, PASSIVE"
				(at 0 0 0)
				(effects
					(font
						(size 1.27 1.27)
					)
					(hide yes)
				)
			)
			(symbol "R_1k_0402_0_1"
				(rectangle
					(start 0.635 0.889)
					(end 4.445 -0.889)
					(stroke
						(width 0.254)
						(type default)
					)
					(fill
						(type none)
					)
				)
			)
			(symbol "R_1k_0402_1_1"
				(pin passive line
					(at 0 0 0)
					(length 0.635)
					(name "~"
						(effects
							(font
								(size 1.27 1.27)
							)
						)
					)
					(number "1"
						(effects
							(font
								(size 1.27 1.27)
							)
						)
					)
				)
				(pin passive line
					(at 5.08 0 180)
					(length 0.635)
					(name "~"
						(effects
							(font
								(size 1.27 1.27)
							)
						)
					)
					(number "2"
						(effects
							(font
								(size 1.27 1.27)
							)
						)
					)
				)
			)
		)
	(symbol "antmicroResistors0402:R_205k_0402"
			(pin_numbers
				(hide yes)
			)
			(pin_names
				(hide yes)
			)
			(exclude_from_sim no)
			(in_bom yes)
			(on_board yes)
			(property "Reference" "R"
				(at 20.32 -5.08 0)
				(effects
					(font
						(size 1.27 1.27)
						(thickness 0.15)
					)
					(justify left bottom)
				)
			)
			(property "Value" "R_205k_0402"
				(at 20.32 -12.7 0)
				(effects
					(font
						(size 1.27 1.27)
						(thickness 0.15)
					)
					(justify left bottom)
					(hide yes)
				)
			)
			(property "Footprint" "antmicro-footprints:R_0402_1005Metric"
				(at 20.32 -15.24 0)
				(effects
					(font
						(size 1.27 1.27)
						(thickness 0.15)
					)
					(justify left bottom)
					(hide yes)
				)
			)
			(property "Datasheet" "https://www.bourns.com/docs/product-datasheets/cr.pdf"
				(at 20.32 -17.78 0)
				(effects
					(font
						(size 1.27 1.27)
						(thickness 0.15)
					)
					(justify left bottom)
					(hide yes)
				)
			)
			(property "Description" "SMD Chip Resistor"
				(at 0 0 0)
				(effects
					(font
						(size 1.27 1.27)
					)
					(hide yes)
				)
			)
			(property "MPN" "CR0402-FX-2053GLF"
				(at 20.32 -20.32 0)
				(effects
					(font
						(size 1.27 1.27)
						(thickness 0.15)
					)
					(justify left bottom)
					(hide yes)
				)
			)
			(property "Manufacturer" "Bourns"
				(at 20.32 -22.86 0)
				(effects
					(font
						(size 1.27 1.27)
						(thickness 0.15)
					)
					(justify left bottom)
					(hide yes)
				)
			)
			(property "License" "Apache-2.0"
				(at 20.32 -25.4 0)
				(effects
					(font
						(size 1.27 1.27)
						(thickness 0.15)
					)
					(justify left bottom)
					(hide yes)
				)
			)
			(property "Author" "Antmicro"
				(at 20.32 -27.94 0)
				(effects
					(font
						(size 1.27 1.27)
						(thickness 0.15)
					)
					(justify left bottom)
					(hide yes)
				)
			)
			(property "Val" "205k"
				(at 20.32 -7.62 0)
				(effects
					(font
						(size 1.27 1.27)
						(thickness 0.15)
					)
					(justify left bottom)
				)
			)
			(property "Tolerance" "1%"
				(at 20.32 -10.16 0)
				(effects
					(font
						(size 1.27 1.27)
					)
					(justify left bottom)
					(hide yes)
				)
			)
			(property "ki_keywords" "0402, SMT, RESISTOR, PASSIVE"
				(at 0 0 0)
				(effects
					(font
						(size 1.27 1.27)
					)
					(hide yes)
				)
			)
			(symbol "R_205k_0402_0_1"
				(rectangle
					(start 0.635 0.889)
					(end 4.445 -0.889)
					(stroke
						(width 0.254)
						(type default)
					)
					(fill
						(type none)
					)
				)
			)
			(symbol "R_205k_0402_1_1"
				(pin passive line
					(at 0 0 0)
					(length 0.635)
					(name "~"
						(effects
							(font
								(size 1.27 1.27)
							)
						)
					)
					(number "1"
						(effects
							(font
								(size 1.27 1.27)
							)
						)
					)
				)
				(pin passive line
					(at 5.08 0 180)
					(length 0.635)
					(name "~"
						(effects
							(font
								(size 1.27 1.27)
							)
						)
					)
					(number "2"
						(effects
							(font
								(size 1.27 1.27)
							)
						)
					)
				)
			)
		)
	(symbol "antmicroResistors0402:R_20k_0402"
			(pin_numbers
				(hide yes)
			)
			(pin_names
				(hide yes)
			)
			(exclude_from_sim no)
			(in_bom yes)
			(on_board yes)
			(property "Reference" "R"
				(at 20.32 -5.08 0)
				(effects
					(font
						(size 1.27 1.27)
						(thickness 0.15)
					)
					(justify left bottom)
				)
			)
			(property "Value" "R_20k_0402"
				(at 20.32 -12.7 0)
				(effects
					(font
						(size 1.27 1.27)
						(thickness 0.15)
					)
					(justify left bottom)
					(hide yes)
				)
			)
			(property "Footprint" "antmicro-footprints:R_0402_1005Metric"
				(at 20.32 -15.24 0)
				(effects
					(font
						(size 1.27 1.27)
						(thickness 0.15)
					)
					(justify left bottom)
					(hide yes)
				)
			)
			(property "Datasheet" "https://www.bourns.com/docs/product-datasheets/cr.pdf"
				(at 20.32 -17.78 0)
				(effects
					(font
						(size 1.27 1.27)
						(thickness 0.15)
					)
					(justify left bottom)
					(hide yes)
				)
			)
			(property "Description" "SMD Chip Resistor, 20 kohm, ± 1%, 62.5 mW, 0402 [1005 Metric], Thick Film, General Purpose"
				(at 0 0 0)
				(effects
					(font
						(size 1.27 1.27)
					)
					(hide yes)
				)
			)
			(property "MPN" "CR0402-FX-2002GLF"
				(at 20.32 -20.32 0)
				(effects
					(font
						(size 1.27 1.27)
						(thickness 0.15)
					)
					(justify left bottom)
					(hide yes)
				)
			)
			(property "Manufacturer" "Bourns"
				(at 20.32 -22.86 0)
				(effects
					(font
						(size 1.27 1.27)
						(thickness 0.15)
					)
					(justify left bottom)
					(hide yes)
				)
			)
			(property "License" "Apache-2.0"
				(at 20.32 -25.4 0)
				(effects
					(font
						(size 1.27 1.27)
						(thickness 0.15)
					)
					(justify left bottom)
					(hide yes)
				)
			)
			(property "Author" "Antmicro"
				(at 20.32 -27.94 0)
				(effects
					(font
						(size 1.27 1.27)
						(thickness 0.15)
					)
					(justify left bottom)
					(hide yes)
				)
			)
			(property "Val" "20k"
				(at 20.32 -7.62 0)
				(effects
					(font
						(size 1.27 1.27)
						(thickness 0.15)
					)
					(justify left bottom)
				)
			)
			(property "Tolerance" "1%"
				(at 20.32 -10.16 0)
				(effects
					(font
						(size 1.27 1.27)
					)
					(justify left bottom)
					(hide yes)
				)
			)
			(property "ki_keywords" "0402, SMT, RESISTOR, PASSIVE"
				(at 0 0 0)
				(effects
					(font
						(size 1.27 1.27)
					)
					(hide yes)
				)
			)
			(symbol "R_20k_0402_0_1"
				(rectangle
					(start 0.635 0.889)
					(end 4.445 -0.889)
					(stroke
						(width 0.254)
						(type default)
					)
					(fill
						(type none)
					)
				)
			)
			(symbol "R_20k_0402_1_1"
				(pin passive line
					(at 0 0 0)
					(length 0.635)
					(name "~"
						(effects
							(font
								(size 1.27 1.27)
							)
						)
					)
					(number "1"
						(effects
							(font
								(size 1.27 1.27)
							)
						)
					)
				)
				(pin passive line
					(at 5.08 0 180)
					(length 0.635)
					(name "~"
						(effects
							(font
								(size 1.27 1.27)
							)
						)
					)
					(number "2"
						(effects
							(font
								(size 1.27 1.27)
							)
						)
					)
				)
			)
		)
	(symbol "antmicroResistors0402:R_240R_0402"
			(pin_numbers
				(hide yes)
			)
			(pin_names
				(hide yes)
			)
			(exclude_from_sim no)
			(in_bom yes)
			(on_board yes)
			(property "Reference" "R"
				(at 20.32 -5.08 0)
				(effects
					(font
						(size 1.27 1.27)
						(thickness 0.15)
					)
					(justify left bottom)
				)
			)
			(property "Value" "R_240R_0402"
				(at 20.32 -12.7 0)
				(effects
					(font
						(size 1.27 1.27)
						(thickness 0.15)
					)
					(justify left bottom)
					(hide yes)
				)
			)
			(property "Footprint" "antmicro-footprints:R_0402_1005Metric"
				(at 20.32 -15.24 0)
				(effects
					(font
						(size 1.27 1.27)
						(thickness 0.15)
					)
					(justify left bottom)
					(hide yes)
				)
			)
			(property "Datasheet" "https://www.bourns.com/docs/product-datasheets/cr.pdf"
				(at 20.32 -17.78 0)
				(effects
					(font
						(size 1.27 1.27)
						(thickness 0.15)
					)
					(justify left bottom)
					(hide yes)
				)
			)
			(property "Description" "SMD Chip Resistor, 240 ohm, ± 1%, 63 mW, 0402 [1005 Metric], Thick Film, General Purpose"
				(at 0 0 0)
				(effects
					(font
						(size 1.27 1.27)
					)
					(hide yes)
				)
			)
			(property "MPN" "CR0402-FX-2400GLF"
				(at 20.32 -20.32 0)
				(effects
					(font
						(size 1.27 1.27)
						(thickness 0.15)
					)
					(justify left bottom)
					(hide yes)
				)
			)
			(property "Manufacturer" "Bourns"
				(at 20.32 -22.86 0)
				(effects
					(font
						(size 1.27 1.27)
						(thickness 0.15)
					)
					(justify left bottom)
					(hide yes)
				)
			)
			(property "License" "Apache-2.0"
				(at 20.32 -25.4 0)
				(effects
					(font
						(size 1.27 1.27)
						(thickness 0.15)
					)
					(justify left bottom)
					(hide yes)
				)
			)
			(property "Author" "Antmicro"
				(at 20.32 -27.94 0)
				(effects
					(font
						(size 1.27 1.27)
						(thickness 0.15)
					)
					(justify left bottom)
					(hide yes)
				)
			)
			(property "Val" "240R"
				(at 20.32 -7.62 0)
				(effects
					(font
						(size 1.27 1.27)
						(thickness 0.15)
					)
					(justify left bottom)
				)
			)
			(property "Tolerance" "1%"
				(at 20.32 -10.16 0)
				(effects
					(font
						(size 1.27 1.27)
					)
					(justify left bottom)
					(hide yes)
				)
			)
			(property "ki_keywords" "0402, SMT, RESISTOR, PASSIVE"
				(at 0 0 0)
				(effects
					(font
						(size 1.27 1.27)
					)
					(hide yes)
				)
			)
			(symbol "R_240R_0402_0_1"
				(rectangle
					(start 0.635 0.889)
					(end 4.445 -0.889)
					(stroke
						(width 0.254)
						(type default)
					)
					(fill
						(type none)
					)
				)
			)
			(symbol "R_240R_0402_1_1"
				(pin passive line
					(at 0 0 0)
					(length 0.635)
					(name "~"
						(effects
							(font
								(size 1.27 1.27)
							)
						)
					)
					(number "1"
						(effects
							(font
								(size 1.27 1.27)
							)
						)
					)
				)
				(pin passive line
					(at 5.08 0 180)
					(length 0.635)
					(name "~"
						(effects
							(font
								(size 1.27 1.27)
							)
						)
					)
					(number "2"
						(effects
							(font
								(size 1.27 1.27)
							)
						)
					)
				)
			)
		)
	(symbol "antmicroResistors0402:R_270k_0402"
			(pin_numbers
				(hide yes)
			)
			(pin_names
				(hide yes)
			)
			(exclude_from_sim no)
			(in_bom yes)
			(on_board yes)
			(property "Reference" "R"
				(at 20.32 -5.08 0)
				(effects
					(font
						(size 1.27 1.27)
						(thickness 0.15)
					)
					(justify left bottom)
				)
			)
			(property "Value" "R_270k_0402"
				(at 20.32 -12.7 0)
				(effects
					(font
						(size 1.27 1.27)
						(thickness 0.15)
					)
					(justify left bottom)
					(hide yes)
				)
			)
			(property "Footprint" "antmicro-footprints:R_0402_1005Metric"
				(at 20.32 -15.24 0)
				(effects
					(font
						(size 1.27 1.27)
						(thickness 0.15)
					)
					(justify left bottom)
					(hide yes)
				)
			)
			(property "Datasheet" "https://www.bourns.com/docs/product-datasheets/cr.pdf"
				(at 20.32 -17.78 0)
				(effects
					(font
						(size 1.27 1.27)
						(thickness 0.15)
					)
					(justify left bottom)
					(hide yes)
				)
			)
			(property "Description" "SMD Chip Resistor"
				(at 0 0 0)
				(effects
					(font
						(size 1.27 1.27)
					)
					(hide yes)
				)
			)
			(property "MPN" "CR0402-FX-2703GLF"
				(at 20.32 -20.32 0)
				(effects
					(font
						(size 1.27 1.27)
						(thickness 0.15)
					)
					(justify left bottom)
					(hide yes)
				)
			)
			(property "Manufacturer" "Bourns"
				(at 20.32 -22.86 0)
				(effects
					(font
						(size 1.27 1.27)
						(thickness 0.15)
					)
					(justify left bottom)
					(hide yes)
				)
			)
			(property "License" "Apache-2.0"
				(at 20.32 -25.4 0)
				(effects
					(font
						(size 1.27 1.27)
						(thickness 0.15)
					)
					(justify left bottom)
					(hide yes)
				)
			)
			(property "Author" "Antmicro"
				(at 20.32 -27.94 0)
				(effects
					(font
						(size 1.27 1.27)
						(thickness 0.15)
					)
					(justify left bottom)
					(hide yes)
				)
			)
			(property "Val" "270k"
				(at 20.32 -7.62 0)
				(effects
					(font
						(size 1.27 1.27)
						(thickness 0.15)
					)
					(justify left bottom)
				)
			)
			(property "Tolerance" "1%"
				(at 20.32 -10.16 0)
				(effects
					(font
						(size 1.27 1.27)
					)
					(justify left bottom)
					(hide yes)
				)
			)
			(property "ki_keywords" "0402, SMT, RESISTOR, PASSIVE"
				(at 0 0 0)
				(effects
					(font
						(size 1.27 1.27)
					)
					(hide yes)
				)
			)
			(symbol "R_270k_0402_0_1"
				(rectangle
					(start 0.635 0.889)
					(end 4.445 -0.889)
					(stroke
						(width 0.254)
						(type default)
					)
					(fill
						(type none)
					)
				)
			)
			(symbol "R_270k_0402_1_1"
				(pin passive line
					(at 0 0 0)
					(length 0.635)
					(name "~"
						(effects
							(font
								(size 1.27 1.27)
							)
						)
					)
					(number "1"
						(effects
							(font
								(size 1.27 1.27)
							)
						)
					)
				)
				(pin passive line
					(at 5.08 0 180)
					(length 0.635)
					(name "~"
						(effects
							(font
								(size 1.27 1.27)
							)
						)
					)
					(number "2"
						(effects
							(font
								(size 1.27 1.27)
							)
						)
					)
				)
			)
		)
	(symbol "antmicroResistors0402:R_27R_0402"
			(pin_numbers
				(hide yes)
			)
			(pin_names
				(hide yes)
			)
			(exclude_from_sim no)
			(in_bom yes)
			(on_board yes)
			(property "Reference" "R"
				(at 20.32 -5.08 0)
				(effects
					(font
						(size 1.27 1.27)
						(thickness 0.15)
					)
					(justify left bottom)
				)
			)
			(property "Value" "R_27R_0402"
				(at 20.32 -12.7 0)
				(effects
					(font
						(size 1.27 1.27)
						(thickness 0.15)
					)
					(justify left bottom)
					(hide yes)
				)
			)
			(property "Footprint" "antmicro-footprints:R_0402_1005Metric"
				(at 20.32 -15.24 0)
				(effects
					(font
						(size 1.27 1.27)
						(thickness 0.15)
					)
					(justify left bottom)
					(hide yes)
				)
			)
			(property "Datasheet" "https://www.bourns.com/docs/product-datasheets/cr.pdf"
				(at 20.32 -17.78 0)
				(effects
					(font
						(size 1.27 1.27)
						(thickness 0.15)
					)
					(justify left bottom)
					(hide yes)
				)
			)
			(property "Description" "SMD Chip Resistor, 27 ohm, ± 1%, 63 mW, 0402 [1005 Metric], Thick Film, General Purpose"
				(at 0 0 0)
				(effects
					(font
						(size 1.27 1.27)
					)
					(hide yes)
				)
			)
			(property "MPN" "CR0402-FX-27R0GLF"
				(at 20.32 -20.32 0)
				(effects
					(font
						(size 1.27 1.27)
						(thickness 0.15)
					)
					(justify left bottom)
					(hide yes)
				)
			)
			(property "Manufacturer" "Bourns"
				(at 20.32 -22.86 0)
				(effects
					(font
						(size 1.27 1.27)
						(thickness 0.15)
					)
					(justify left bottom)
					(hide yes)
				)
			)
			(property "License" "Apache-2.0"
				(at 20.32 -25.4 0)
				(effects
					(font
						(size 1.27 1.27)
						(thickness 0.15)
					)
					(justify left bottom)
					(hide yes)
				)
			)
			(property "Author" "Antmicro"
				(at 20.32 -27.94 0)
				(effects
					(font
						(size 1.27 1.27)
						(thickness 0.15)
					)
					(justify left bottom)
					(hide yes)
				)
			)
			(property "Val" "27R"
				(at 20.32 -7.62 0)
				(effects
					(font
						(size 1.27 1.27)
						(thickness 0.15)
					)
					(justify left bottom)
				)
			)
			(property "Tolerance" "1%"
				(at 20.32 -10.16 0)
				(effects
					(font
						(size 1.27 1.27)
					)
					(justify left bottom)
					(hide yes)
				)
			)
			(property "ki_keywords" "0402, SMT, RESISTOR, PASSIVE"
				(at 0 0 0)
				(effects
					(font
						(size 1.27 1.27)
					)
					(hide yes)
				)
			)
			(symbol "R_27R_0402_0_1"
				(rectangle
					(start 0.635 0.889)
					(end 4.445 -0.889)
					(stroke
						(width 0.254)
						(type default)
					)
					(fill
						(type none)
					)
				)
			)
			(symbol "R_27R_0402_1_1"
				(pin passive line
					(at 0 0 0)
					(length 0.635)
					(name "~"
						(effects
							(font
								(size 1.27 1.27)
							)
						)
					)
					(number "1"
						(effects
							(font
								(size 1.27 1.27)
							)
						)
					)
				)
				(pin passive line
					(at 5.08 0 180)
					(length 0.635)
					(name "~"
						(effects
							(font
								(size 1.27 1.27)
							)
						)
					)
					(number "2"
						(effects
							(font
								(size 1.27 1.27)
							)
						)
					)
				)
			)
		)
	(symbol "antmicroResistors0402:R_2k2_0402"
			(pin_numbers
				(hide yes)
			)
			(pin_names
				(hide yes)
			)
			(exclude_from_sim no)
			(in_bom yes)
			(on_board yes)
			(property "Reference" "R"
				(at 20.32 -5.08 0)
				(effects
					(font
						(size 1.27 1.27)
						(thickness 0.15)
					)
					(justify left bottom)
				)
			)
			(property "Value" "R_2k2_0402"
				(at 20.32 -12.7 0)
				(effects
					(font
						(size 1.27 1.27)
						(thickness 0.15)
					)
					(justify left bottom)
					(hide yes)
				)
			)
			(property "Footprint" "antmicro-footprints:R_0402_1005Metric"
				(at 20.32 -15.24 0)
				(effects
					(font
						(size 1.27 1.27)
						(thickness 0.15)
					)
					(justify left bottom)
					(hide yes)
				)
			)
			(property "Datasheet" "https://www.bourns.com/docs/product-datasheets/cr.pdf"
				(at 20.32 -17.78 0)
				(effects
					(font
						(size 1.27 1.27)
						(thickness 0.15)
					)
					(justify left bottom)
					(hide yes)
				)
			)
			(property "Description" "SMD Chip Resistor, 2.2 kohm, ± 1%, 62.5 mW, 0402 [1005 Metric], Thick Film, General Purpose"
				(at 0 0 0)
				(effects
					(font
						(size 1.27 1.27)
					)
					(hide yes)
				)
			)
			(property "MPN" "CR0402-FX-2201GLF"
				(at 20.32 -20.32 0)
				(effects
					(font
						(size 1.27 1.27)
						(thickness 0.15)
					)
					(justify left bottom)
					(hide yes)
				)
			)
			(property "Manufacturer" "Bourns"
				(at 20.32 -22.86 0)
				(effects
					(font
						(size 1.27 1.27)
						(thickness 0.15)
					)
					(justify left bottom)
					(hide yes)
				)
			)
			(property "License" "Apache-2.0"
				(at 20.32 -25.4 0)
				(effects
					(font
						(size 1.27 1.27)
						(thickness 0.15)
					)
					(justify left bottom)
					(hide yes)
				)
			)
			(property "Author" "Antmicro"
				(at 20.32 -27.94 0)
				(effects
					(font
						(size 1.27 1.27)
						(thickness 0.15)
					)
					(justify left bottom)
					(hide yes)
				)
			)
			(property "Val" "2k2"
				(at 20.32 -7.62 0)
				(effects
					(font
						(size 1.27 1.27)
						(thickness 0.15)
					)
					(justify left bottom)
				)
			)
			(property "Tolerance" "1%"
				(at 20.32 -10.16 0)
				(effects
					(font
						(size 1.27 1.27)
					)
					(justify left bottom)
					(hide yes)
				)
			)
			(property "ki_keywords" "0402, SMT, RESISTOR, PASSIVE"
				(at 0 0 0)
				(effects
					(font
						(size 1.27 1.27)
					)
					(hide yes)
				)
			)
			(symbol "R_2k2_0402_0_1"
				(rectangle
					(start 0.635 0.889)
					(end 4.445 -0.889)
					(stroke
						(width 0.254)
						(type default)
					)
					(fill
						(type none)
					)
				)
			)
			(symbol "R_2k2_0402_1_1"
				(pin passive line
					(at 0 0 0)
					(length 0.635)
					(name "~"
						(effects
							(font
								(size 1.27 1.27)
							)
						)
					)
					(number "1"
						(effects
							(font
								(size 1.27 1.27)
							)
						)
					)
				)
				(pin passive line
					(at 5.08 0 180)
					(length 0.635)
					(name "~"
						(effects
							(font
								(size 1.27 1.27)
							)
						)
					)
					(number "2"
						(effects
							(font
								(size 1.27 1.27)
							)
						)
					)
				)
			)
		)
	(symbol "antmicroResistors0402:R_30k9_0402"
			(pin_numbers
				(hide yes)
			)
			(pin_names
				(hide yes)
			)
			(exclude_from_sim no)
			(in_bom yes)
			(on_board yes)
			(property "Reference" "R"
				(at 20.32 -5.08 0)
				(effects
					(font
						(size 1.27 1.27)
						(thickness 0.15)
					)
					(justify left bottom)
				)
			)
			(property "Value" "R_30k9_0402"
				(at 20.32 -12.7 0)
				(effects
					(font
						(size 1.27 1.27)
						(thickness 0.15)
					)
					(justify left bottom)
					(hide yes)
				)
			)
			(property "Footprint" "antmicro-footprints:R_0402_1005Metric"
				(at 20.32 -15.24 0)
				(effects
					(font
						(size 1.27 1.27)
						(thickness 0.15)
					)
					(justify left bottom)
					(hide yes)
				)
			)
			(property "Datasheet" "https://www.bourns.com/docs/product-datasheets/cr.pdf"
				(at 20.32 -17.78 0)
				(effects
					(font
						(size 1.27 1.27)
						(thickness 0.15)
					)
					(justify left bottom)
					(hide yes)
				)
			)
			(property "Description" "SMD Chip Resistor"
				(at 0 0 0)
				(effects
					(font
						(size 1.27 1.27)
					)
					(hide yes)
				)
			)
			(property "MPN" "CR0402-FX-3092GLF"
				(at 20.32 -20.32 0)
				(effects
					(font
						(size 1.27 1.27)
						(thickness 0.15)
					)
					(justify left bottom)
					(hide yes)
				)
			)
			(property "Manufacturer" "Bourns"
				(at 20.32 -22.86 0)
				(effects
					(font
						(size 1.27 1.27)
						(thickness 0.15)
					)
					(justify left bottom)
					(hide yes)
				)
			)
			(property "License" "Apache-2.0"
				(at 20.32 -25.4 0)
				(effects
					(font
						(size 1.27 1.27)
						(thickness 0.15)
					)
					(justify left bottom)
					(hide yes)
				)
			)
			(property "Author" "Antmicro"
				(at 20.32 -27.94 0)
				(effects
					(font
						(size 1.27 1.27)
						(thickness 0.15)
					)
					(justify left bottom)
					(hide yes)
				)
			)
			(property "Val" "30k9"
				(at 20.32 -7.62 0)
				(effects
					(font
						(size 1.27 1.27)
						(thickness 0.15)
					)
					(justify left bottom)
				)
			)
			(property "Tolerance" "1%"
				(at 20.32 -10.16 0)
				(effects
					(font
						(size 1.27 1.27)
					)
					(justify left bottom)
					(hide yes)
				)
			)
			(property "ki_keywords" "0402, SMT, RESISTOR, PASSIVE"
				(at 0 0 0)
				(effects
					(font
						(size 1.27 1.27)
					)
					(hide yes)
				)
			)
			(symbol "R_30k9_0402_0_1"
				(rectangle
					(start 0.635 0.889)
					(end 4.445 -0.889)
					(stroke
						(width 0.254)
						(type default)
					)
					(fill
						(type none)
					)
				)
			)
			(symbol "R_30k9_0402_1_1"
				(pin passive line
					(at 0 0 0)
					(length 0.635)
					(name "~"
						(effects
							(font
								(size 1.27 1.27)
							)
						)
					)
					(number "1"
						(effects
							(font
								(size 1.27 1.27)
							)
						)
					)
				)
				(pin passive line
					(at 5.08 0 180)
					(length 0.635)
					(name "~"
						(effects
							(font
								(size 1.27 1.27)
							)
						)
					)
					(number "2"
						(effects
							(font
								(size 1.27 1.27)
							)
						)
					)
				)
			)
		)
	(symbol "antmicroResistors0402:R_470R_0402"
			(pin_numbers
				(hide yes)
			)
			(pin_names
				(hide yes)
			)
			(exclude_from_sim no)
			(in_bom yes)
			(on_board yes)
			(property "Reference" "R"
				(at 20.32 -5.08 0)
				(effects
					(font
						(size 1.27 1.27)
						(thickness 0.15)
					)
					(justify left bottom)
				)
			)
			(property "Value" "R_470R_0402"
				(at 20.32 -12.7 0)
				(effects
					(font
						(size 1.27 1.27)
						(thickness 0.15)
					)
					(justify left bottom)
					(hide yes)
				)
			)
			(property "Footprint" "antmicro-footprints:R_0402_1005Metric"
				(at 20.32 -15.24 0)
				(effects
					(font
						(size 1.27 1.27)
						(thickness 0.15)
					)
					(justify left bottom)
					(hide yes)
				)
			)
			(property "Datasheet" "https://www.bourns.com/docs/product-datasheets/cr.pdf"
				(at 20.32 -17.78 0)
				(effects
					(font
						(size 1.27 1.27)
						(thickness 0.15)
					)
					(justify left bottom)
					(hide yes)
				)
			)
			(property "Description" "SMD Chip Resistor, 470 ohm, ± 1%, 62.5 mW, 0402 [1005 Metric], Thick Film, General Purpose"
				(at 0 0 0)
				(effects
					(font
						(size 1.27 1.27)
					)
					(hide yes)
				)
			)
			(property "MPN" "CR0402-FX-4700GLF"
				(at 20.32 -20.32 0)
				(effects
					(font
						(size 1.27 1.27)
						(thickness 0.15)
					)
					(justify left bottom)
					(hide yes)
				)
			)
			(property "Manufacturer" "Bourns"
				(at 20.32 -22.86 0)
				(effects
					(font
						(size 1.27 1.27)
						(thickness 0.15)
					)
					(justify left bottom)
					(hide yes)
				)
			)
			(property "License" "Apache-2.0"
				(at 20.32 -25.4 0)
				(effects
					(font
						(size 1.27 1.27)
						(thickness 0.15)
					)
					(justify left bottom)
					(hide yes)
				)
			)
			(property "Author" "Antmicro"
				(at 20.32 -27.94 0)
				(effects
					(font
						(size 1.27 1.27)
						(thickness 0.15)
					)
					(justify left bottom)
					(hide yes)
				)
			)
			(property "Val" "470R"
				(at 20.32 -7.62 0)
				(effects
					(font
						(size 1.27 1.27)
						(thickness 0.15)
					)
					(justify left bottom)
				)
			)
			(property "Tolerance" "1%"
				(at 20.32 -10.16 0)
				(effects
					(font
						(size 1.27 1.27)
					)
					(justify left bottom)
					(hide yes)
				)
			)
			(property "ki_keywords" "0402, SMT, RESISTOR, PASSIVE"
				(at 0 0 0)
				(effects
					(font
						(size 1.27 1.27)
					)
					(hide yes)
				)
			)
			(symbol "R_470R_0402_0_1"
				(rectangle
					(start 0.635 0.889)
					(end 4.445 -0.889)
					(stroke
						(width 0.254)
						(type default)
					)
					(fill
						(type none)
					)
				)
			)
			(symbol "R_470R_0402_1_1"
				(pin passive line
					(at 0 0 0)
					(length 0.635)
					(name "~"
						(effects
							(font
								(size 1.27 1.27)
							)
						)
					)
					(number "1"
						(effects
							(font
								(size 1.27 1.27)
							)
						)
					)
				)
				(pin passive line
					(at 5.08 0 180)
					(length 0.635)
					(name "~"
						(effects
							(font
								(size 1.27 1.27)
							)
						)
					)
					(number "2"
						(effects
							(font
								(size 1.27 1.27)
							)
						)
					)
				)
			)
		)
	(symbol "antmicroResistors0402:R_49k9_0402"
			(pin_numbers
				(hide yes)
			)
			(pin_names
				(hide yes)
			)
			(exclude_from_sim no)
			(in_bom yes)
			(on_board yes)
			(property "Reference" "R"
				(at 20.32 -5.08 0)
				(effects
					(font
						(size 1.27 1.27)
						(thickness 0.15)
					)
					(justify left bottom)
				)
			)
			(property "Value" "R_49k9_0402"
				(at 20.32 -12.7 0)
				(effects
					(font
						(size 1.27 1.27)
						(thickness 0.15)
					)
					(justify left bottom)
					(hide yes)
				)
			)
			(property "Footprint" "antmicro-footprints:R_0402_1005Metric"
				(at 20.32 -15.24 0)
				(effects
					(font
						(size 1.27 1.27)
						(thickness 0.15)
					)
					(justify left bottom)
					(hide yes)
				)
			)
			(property "Datasheet" "https://www.bourns.com/docs/product-datasheets/cr.pdf"
				(at 20.32 -17.78 0)
				(effects
					(font
						(size 1.27 1.27)
						(thickness 0.15)
					)
					(justify left bottom)
					(hide yes)
				)
			)
			(property "Description" "SMD Chip Resistor, 49.9 kohm, ± 1%, 63 mW, 0402 [1005 Metric], Thick Film, General Purpose"
				(at 0 0 0)
				(effects
					(font
						(size 1.27 1.27)
					)
					(hide yes)
				)
			)
			(property "MPN" "CR0402-FX-4992GLF"
				(at 20.32 -20.32 0)
				(effects
					(font
						(size 1.27 1.27)
						(thickness 0.15)
					)
					(justify left bottom)
					(hide yes)
				)
			)
			(property "Manufacturer" "Bourns"
				(at 20.32 -22.86 0)
				(effects
					(font
						(size 1.27 1.27)
						(thickness 0.15)
					)
					(justify left bottom)
					(hide yes)
				)
			)
			(property "License" "Apache-2.0"
				(at 20.32 -25.4 0)
				(effects
					(font
						(size 1.27 1.27)
						(thickness 0.15)
					)
					(justify left bottom)
					(hide yes)
				)
			)
			(property "Author" "Antmicro"
				(at 20.32 -27.94 0)
				(effects
					(font
						(size 1.27 1.27)
						(thickness 0.15)
					)
					(justify left bottom)
					(hide yes)
				)
			)
			(property "Val" "49k9"
				(at 20.32 -7.62 0)
				(effects
					(font
						(size 1.27 1.27)
						(thickness 0.15)
					)
					(justify left bottom)
				)
			)
			(property "Tolerance" "1%"
				(at 20.32 -10.16 0)
				(effects
					(font
						(size 1.27 1.27)
					)
					(justify left bottom)
					(hide yes)
				)
			)
			(property "ki_keywords" "0402, SMT, RESISTOR, PASSIVE"
				(at 0 0 0)
				(effects
					(font
						(size 1.27 1.27)
					)
					(hide yes)
				)
			)
			(symbol "R_49k9_0402_0_1"
				(rectangle
					(start 0.635 0.889)
					(end 4.445 -0.889)
					(stroke
						(width 0.254)
						(type default)
					)
					(fill
						(type none)
					)
				)
			)
			(symbol "R_49k9_0402_1_1"
				(pin passive line
					(at 0 0 0)
					(length 0.635)
					(name "~"
						(effects
							(font
								(size 1.27 1.27)
							)
						)
					)
					(number "1"
						(effects
							(font
								(size 1.27 1.27)
							)
						)
					)
				)
				(pin passive line
					(at 5.08 0 180)
					(length 0.635)
					(name "~"
						(effects
							(font
								(size 1.27 1.27)
							)
						)
					)
					(number "2"
						(effects
							(font
								(size 1.27 1.27)
							)
						)
					)
				)
			)
		)
	(symbol "antmicroResistors0402:R_4R7_0402"
			(pin_numbers
				(hide yes)
			)
			(pin_names
				(hide yes)
			)
			(exclude_from_sim no)
			(in_bom yes)
			(on_board yes)
			(property "Reference" "R"
				(at 20.32 -5.08 0)
				(effects
					(font
						(size 1.27 1.27)
						(thickness 0.15)
					)
					(justify left bottom)
				)
			)
			(property "Value" "R_4R7_0402"
				(at 20.32 -12.7 0)
				(effects
					(font
						(size 1.27 1.27)
						(thickness 0.15)
					)
					(justify left bottom)
					(hide yes)
				)
			)
			(property "Footprint" "antmicro-footprints:R_0402_1005Metric"
				(at 20.32 -15.24 0)
				(effects
					(font
						(size 1.27 1.27)
						(thickness 0.15)
					)
					(justify left bottom)
					(hide yes)
				)
			)
			(property "Datasheet" "https://www.bourns.com/docs/product-datasheets/cr.pdf"
				(at 20.32 -17.78 0)
				(effects
					(font
						(size 1.27 1.27)
						(thickness 0.15)
					)
					(justify left bottom)
					(hide yes)
				)
			)
			(property "Description" "SMD Chip Resistor, 4.7 ohm, ± 1%, 62.5 mW, 0402 [1005 Metric], Thick Film, General Purpose"
				(at 0 0 0)
				(effects
					(font
						(size 1.27 1.27)
					)
					(hide yes)
				)
			)
			(property "MPN" "CR0402-FX-4R70GLF"
				(at 20.32 -20.32 0)
				(effects
					(font
						(size 1.27 1.27)
						(thickness 0.15)
					)
					(justify left bottom)
					(hide yes)
				)
			)
			(property "Manufacturer" "Bourns"
				(at 20.32 -22.86 0)
				(effects
					(font
						(size 1.27 1.27)
						(thickness 0.15)
					)
					(justify left bottom)
					(hide yes)
				)
			)
			(property "License" "Apache-2.0"
				(at 20.32 -25.4 0)
				(effects
					(font
						(size 1.27 1.27)
						(thickness 0.15)
					)
					(justify left bottom)
					(hide yes)
				)
			)
			(property "Author" "Antmicro"
				(at 20.32 -27.94 0)
				(effects
					(font
						(size 1.27 1.27)
						(thickness 0.15)
					)
					(justify left bottom)
					(hide yes)
				)
			)
			(property "Val" "4R7"
				(at 20.32 -7.62 0)
				(effects
					(font
						(size 1.27 1.27)
						(thickness 0.15)
					)
					(justify left bottom)
				)
			)
			(property "Tolerance" "1%"
				(at 20.32 -10.16 0)
				(effects
					(font
						(size 1.27 1.27)
					)
					(justify left bottom)
					(hide yes)
				)
			)
			(property "ki_keywords" "0402, SMT, RESISTOR, PASSIVE"
				(at 0 0 0)
				(effects
					(font
						(size 1.27 1.27)
					)
					(hide yes)
				)
			)
			(symbol "R_4R7_0402_0_1"
				(rectangle
					(start 0.635 0.889)
					(end 4.445 -0.889)
					(stroke
						(width 0.254)
						(type default)
					)
					(fill
						(type none)
					)
				)
			)
			(symbol "R_4R7_0402_1_1"
				(pin passive line
					(at 0 0 0)
					(length 0.635)
					(name "~"
						(effects
							(font
								(size 1.27 1.27)
							)
						)
					)
					(number "1"
						(effects
							(font
								(size 1.27 1.27)
							)
						)
					)
				)
				(pin passive line
					(at 5.08 0 180)
					(length 0.635)
					(name "~"
						(effects
							(font
								(size 1.27 1.27)
							)
						)
					)
					(number "2"
						(effects
							(font
								(size 1.27 1.27)
							)
						)
					)
				)
			)
		)
	(symbol "antmicroResistors0402:R_4k75_0.5%_0402"
			(pin_numbers
				(hide yes)
			)
			(pin_names
				(hide yes)
			)
			(exclude_from_sim no)
			(in_bom yes)
			(on_board yes)
			(property "Reference" "R"
				(at 20.32 -5.08 0)
				(effects
					(font
						(size 1.27 1.27)
						(thickness 0.15)
					)
					(justify left bottom)
				)
			)
			(property "Value" "R_4k75_0.5%_0402"
				(at 20.32 -12.7 0)
				(effects
					(font
						(size 1.27 1.27)
						(thickness 0.15)
					)
					(justify left bottom)
					(hide yes)
				)
			)
			(property "Footprint" "antmicro-footprints:R_0402_1005Metric"
				(at 20.32 -15.24 0)
				(effects
					(font
						(size 1.27 1.27)
						(thickness 0.15)
					)
					(justify left bottom)
					(hide yes)
				)
			)
			(property "Datasheet" "https://industrial.panasonic.com/cdbs/www-data/pdf/RDQ0000/ast-ind-151033.pdf"
				(at 20.32 -17.78 0)
				(effects
					(font
						(size 1.27 1.27)
						(thickness 0.15)
					)
					(justify left bottom)
					(hide yes)
				)
			)
			(property "Description" "SMD Chip Resistor, 4.75 kohm, ± 0.5%, 100 mW, 0402 [1005 Metric], Thick Film, High Temperature"
				(at 0 0 0)
				(effects
					(font
						(size 1.27 1.27)
					)
					(hide yes)
				)
			)
			(property "MPN" "ERJ-H2RD4751X"
				(at 20.32 -20.32 0)
				(effects
					(font
						(size 1.27 1.27)
						(thickness 0.15)
					)
					(justify left bottom)
					(hide yes)
				)
			)
			(property "Manufacturer" "Panasonic"
				(at 20.32 -22.86 0)
				(effects
					(font
						(size 1.27 1.27)
						(thickness 0.15)
					)
					(justify left bottom)
					(hide yes)
				)
			)
			(property "License" "Apache-2.0"
				(at 20.32 -25.4 0)
				(effects
					(font
						(size 1.27 1.27)
						(thickness 0.15)
					)
					(justify left bottom)
					(hide yes)
				)
			)
			(property "Author" "Antmicro"
				(at 20.32 -27.94 0)
				(effects
					(font
						(size 1.27 1.27)
						(thickness 0.15)
					)
					(justify left bottom)
					(hide yes)
				)
			)
			(property "Val" "4k75"
				(at 20.32 -7.62 0)
				(effects
					(font
						(size 1.27 1.27)
						(thickness 0.15)
					)
					(justify left bottom)
				)
			)
			(property "Tolerance" "0.5%"
				(at 20.32 -10.16 0)
				(effects
					(font
						(size 1.27 1.27)
					)
					(justify left bottom)
					(hide yes)
				)
			)
			(property "ki_keywords" "0402, SMT, RESISTOR, PASSIVE"
				(at 0 0 0)
				(effects
					(font
						(size 1.27 1.27)
					)
					(hide yes)
				)
			)
			(symbol "R_4k75_0.5%_0402_0_1"
				(rectangle
					(start 0.635 0.889)
					(end 4.445 -0.889)
					(stroke
						(width 0.254)
						(type default)
					)
					(fill
						(type none)
					)
				)
			)
			(symbol "R_4k75_0.5%_0402_1_1"
				(pin passive line
					(at 0 0 0)
					(length 0.635)
					(name "~"
						(effects
							(font
								(size 1.27 1.27)
							)
						)
					)
					(number "1"
						(effects
							(font
								(size 1.27 1.27)
							)
						)
					)
				)
				(pin passive line
					(at 5.08 0 180)
					(length 0.635)
					(name "~"
						(effects
							(font
								(size 1.27 1.27)
							)
						)
					)
					(number "2"
						(effects
							(font
								(size 1.27 1.27)
							)
						)
					)
				)
			)
		)
	(symbol "antmicroResistors0402:R_4k7_0402"
			(pin_numbers
				(hide yes)
			)
			(pin_names
				(hide yes)
			)
			(exclude_from_sim no)
			(in_bom yes)
			(on_board yes)
			(property "Reference" "R"
				(at 20.32 -5.08 0)
				(effects
					(font
						(size 1.27 1.27)
						(thickness 0.15)
					)
					(justify left bottom)
				)
			)
			(property "Value" "R_4k7_0402"
				(at 20.32 -12.7 0)
				(effects
					(font
						(size 1.27 1.27)
						(thickness 0.15)
					)
					(justify left bottom)
					(hide yes)
				)
			)
			(property "Footprint" "antmicro-footprints:R_0402_1005Metric"
				(at 20.32 -15.24 0)
				(effects
					(font
						(size 1.27 1.27)
						(thickness 0.15)
					)
					(justify left bottom)
					(hide yes)
				)
			)
			(property "Datasheet" "https://www.bourns.com/docs/product-datasheets/cr.pdf"
				(at 20.32 -17.78 0)
				(effects
					(font
						(size 1.27 1.27)
						(thickness 0.15)
					)
					(justify left bottom)
					(hide yes)
				)
			)
			(property "Description" "SMD Chip Resistor, 4.7 kohm, ± 1%, 62.5 mW, 0402 [1005 Metric], Thick Film, General Purpose"
				(at 0 0 0)
				(effects
					(font
						(size 1.27 1.27)
					)
					(hide yes)
				)
			)
			(property "MPN" "CR0402-FX-4701GLF"
				(at 20.32 -20.32 0)
				(effects
					(font
						(size 1.27 1.27)
						(thickness 0.15)
					)
					(justify left bottom)
					(hide yes)
				)
			)
			(property "Manufacturer" "Bourns"
				(at 20.32 -22.86 0)
				(effects
					(font
						(size 1.27 1.27)
						(thickness 0.15)
					)
					(justify left bottom)
					(hide yes)
				)
			)
			(property "License" "Apache-2.0"
				(at 20.32 -25.4 0)
				(effects
					(font
						(size 1.27 1.27)
						(thickness 0.15)
					)
					(justify left bottom)
					(hide yes)
				)
			)
			(property "Author" "Antmicro"
				(at 20.32 -27.94 0)
				(effects
					(font
						(size 1.27 1.27)
						(thickness 0.15)
					)
					(justify left bottom)
					(hide yes)
				)
			)
			(property "Val" "4k7"
				(at 20.32 -7.62 0)
				(effects
					(font
						(size 1.27 1.27)
						(thickness 0.15)
					)
					(justify left bottom)
				)
			)
			(property "Tolerance" "1%"
				(at 20.32 -10.16 0)
				(effects
					(font
						(size 1.27 1.27)
					)
					(justify left bottom)
					(hide yes)
				)
			)
			(property "ki_keywords" "0402, SMT, RESISTOR, PASSIVE"
				(at 0 0 0)
				(effects
					(font
						(size 1.27 1.27)
					)
					(hide yes)
				)
			)
			(symbol "R_4k7_0402_0_1"
				(rectangle
					(start 0.635 0.889)
					(end 4.445 -0.889)
					(stroke
						(width 0.254)
						(type default)
					)
					(fill
						(type none)
					)
				)
			)
			(symbol "R_4k7_0402_1_1"
				(pin passive line
					(at 0 0 0)
					(length 0.635)
					(name "~"
						(effects
							(font
								(size 1.27 1.27)
							)
						)
					)
					(number "1"
						(effects
							(font
								(size 1.27 1.27)
							)
						)
					)
				)
				(pin passive line
					(at 5.08 0 180)
					(length 0.635)
					(name "~"
						(effects
							(font
								(size 1.27 1.27)
							)
						)
					)
					(number "2"
						(effects
							(font
								(size 1.27 1.27)
							)
						)
					)
				)
			)
		)
	(symbol "antmicroResistors0402:R_50R_0402"
			(pin_numbers
				(hide yes)
			)
			(pin_names
				(hide yes)
			)
			(exclude_from_sim no)
			(in_bom yes)
			(on_board yes)
			(property "Reference" "R"
				(at 20.32 -5.08 0)
				(effects
					(font
						(size 1.27 1.27)
						(thickness 0.15)
					)
					(justify left bottom)
				)
			)
			(property "Value" "R_50R_0402"
				(at 20.32 -12.7 0)
				(effects
					(font
						(size 1.27 1.27)
						(thickness 0.15)
					)
					(justify left bottom)
					(hide yes)
				)
			)
			(property "Footprint" "antmicro-footprints:R_0402_1005Metric"
				(at 20.32 -15.24 0)
				(effects
					(font
						(size 1.27 1.27)
						(thickness 0.15)
					)
					(justify left bottom)
					(hide yes)
				)
			)
			(property "Datasheet" "https://www.bourns.com/docs/product-datasheets/cr.pdf"
				(at 20.32 -17.78 0)
				(effects
					(font
						(size 1.27 1.27)
						(thickness 0.15)
					)
					(justify left bottom)
					(hide yes)
				)
			)
			(property "Description" "SMD Chip Resistor"
				(at 0 0 0)
				(effects
					(font
						(size 1.27 1.27)
					)
					(hide yes)
				)
			)
			(property "MPN" "CR0402-FX-50R0GLF"
				(at 20.32 -20.32 0)
				(effects
					(font
						(size 1.27 1.27)
						(thickness 0.15)
					)
					(justify left bottom)
					(hide yes)
				)
			)
			(property "Manufacturer" "Bourns"
				(at 20.32 -22.86 0)
				(effects
					(font
						(size 1.27 1.27)
						(thickness 0.15)
					)
					(justify left bottom)
					(hide yes)
				)
			)
			(property "License" "Apache-2.0"
				(at 20.32 -25.4 0)
				(effects
					(font
						(size 1.27 1.27)
						(thickness 0.15)
					)
					(justify left bottom)
					(hide yes)
				)
			)
			(property "Author" "Antmicro"
				(at 20.32 -27.94 0)
				(effects
					(font
						(size 1.27 1.27)
						(thickness 0.15)
					)
					(justify left bottom)
					(hide yes)
				)
			)
			(property "Val" "50R"
				(at 20.32 -7.62 0)
				(effects
					(font
						(size 1.27 1.27)
						(thickness 0.15)
					)
					(justify left bottom)
				)
			)
			(property "Tolerance" "1%"
				(at 20.32 -10.16 0)
				(effects
					(font
						(size 1.27 1.27)
					)
					(justify left bottom)
					(hide yes)
				)
			)
			(property "ki_keywords" "0402, SMT, RESISTOR, PASSIVE"
				(at 0 0 0)
				(effects
					(font
						(size 1.27 1.27)
					)
					(hide yes)
				)
			)
			(symbol "R_50R_0402_0_1"
				(rectangle
					(start 0.635 0.889)
					(end 4.445 -0.889)
					(stroke
						(width 0.254)
						(type default)
					)
					(fill
						(type none)
					)
				)
			)
			(symbol "R_50R_0402_1_1"
				(pin passive line
					(at 0 0 0)
					(length 0.635)
					(name "~"
						(effects
							(font
								(size 1.27 1.27)
							)
						)
					)
					(number "1"
						(effects
							(font
								(size 1.27 1.27)
							)
						)
					)
				)
				(pin passive line
					(at 5.08 0 180)
					(length 0.635)
					(name "~"
						(effects
							(font
								(size 1.27 1.27)
							)
						)
					)
					(number "2"
						(effects
							(font
								(size 1.27 1.27)
							)
						)
					)
				)
			)
		)
	(symbol "antmicroResistors0402:R_590R_0402"
			(pin_numbers
				(hide yes)
			)
			(pin_names
				(hide yes)
			)
			(exclude_from_sim no)
			(in_bom yes)
			(on_board yes)
			(property "Reference" "R"
				(at 20.32 -5.08 0)
				(effects
					(font
						(size 1.27 1.27)
						(thickness 0.15)
					)
					(justify left bottom)
				)
			)
			(property "Value" "R_590R_0402"
				(at 20.32 -12.7 0)
				(effects
					(font
						(size 1.27 1.27)
						(thickness 0.15)
					)
					(justify left bottom)
					(hide yes)
				)
			)
			(property "Footprint" "antmicro-footprints:R_0402_1005Metric"
				(at 20.32 -15.24 0)
				(effects
					(font
						(size 1.27 1.27)
						(thickness 0.15)
					)
					(justify left bottom)
					(hide yes)
				)
			)
			(property "Datasheet" "https://www.bourns.com/docs/product-datasheets/cr.pdf"
				(at 20.32 -17.78 0)
				(effects
					(font
						(size 1.27 1.27)
						(thickness 0.15)
					)
					(justify left bottom)
					(hide yes)
				)
			)
			(property "Description" "SMD Chip Resistor, 590 ohm, ± 1%, 100 mW, 0402 [1005 Metric], Thick Film, Precision"
				(at 0 0 0)
				(effects
					(font
						(size 1.27 1.27)
					)
					(hide yes)
				)
			)
			(property "MPN" "CR0402-FX-5900GLF"
				(at 20.32 -20.32 0)
				(effects
					(font
						(size 1.27 1.27)
						(thickness 0.15)
					)
					(justify left bottom)
					(hide yes)
				)
			)
			(property "Manufacturer" "Bourns"
				(at 20.32 -22.86 0)
				(effects
					(font
						(size 1.27 1.27)
						(thickness 0.15)
					)
					(justify left bottom)
					(hide yes)
				)
			)
			(property "License" "Apache-2.0"
				(at 20.32 -25.4 0)
				(effects
					(font
						(size 1.27 1.27)
						(thickness 0.15)
					)
					(justify left bottom)
					(hide yes)
				)
			)
			(property "Author" "Antmicro"
				(at 20.32 -27.94 0)
				(effects
					(font
						(size 1.27 1.27)
						(thickness 0.15)
					)
					(justify left bottom)
					(hide yes)
				)
			)
			(property "Val" "590R"
				(at 20.32 -7.62 0)
				(effects
					(font
						(size 1.27 1.27)
						(thickness 0.15)
					)
					(justify left bottom)
				)
			)
			(property "Tolerance" "1%"
				(at 20.32 -10.16 0)
				(effects
					(font
						(size 1.27 1.27)
					)
					(justify left bottom)
					(hide yes)
				)
			)
			(property "ki_keywords" "0402, SMT, RESISTOR, PASSIVE"
				(at 0 0 0)
				(effects
					(font
						(size 1.27 1.27)
					)
					(hide yes)
				)
			)
			(symbol "R_590R_0402_0_1"
				(rectangle
					(start 0.635 0.889)
					(end 4.445 -0.889)
					(stroke
						(width 0.254)
						(type default)
					)
					(fill
						(type none)
					)
				)
			)
			(symbol "R_590R_0402_1_1"
				(pin passive line
					(at 0 0 0)
					(length 0.635)
					(name "~"
						(effects
							(font
								(size 1.27 1.27)
							)
						)
					)
					(number "1"
						(effects
							(font
								(size 1.27 1.27)
							)
						)
					)
				)
				(pin passive line
					(at 5.08 0 180)
					(length 0.635)
					(name "~"
						(effects
							(font
								(size 1.27 1.27)
							)
						)
					)
					(number "2"
						(effects
							(font
								(size 1.27 1.27)
							)
						)
					)
				)
			)
		)
	(symbol "antmicroResistors0402:R_8k06_0402"
			(pin_numbers
				(hide yes)
			)
			(pin_names
				(hide yes)
			)
			(exclude_from_sim no)
			(in_bom yes)
			(on_board yes)
			(property "Reference" "R"
				(at 20.32 -5.08 0)
				(effects
					(font
						(size 1.27 1.27)
						(thickness 0.15)
					)
					(justify left bottom)
				)
			)
			(property "Value" "R_8k06_0402"
				(at 20.32 -12.7 0)
				(effects
					(font
						(size 1.27 1.27)
						(thickness 0.15)
					)
					(justify left bottom)
					(hide yes)
				)
			)
			(property "Footprint" "antmicro-footprints:R_0402_1005Metric"
				(at 20.32 -15.24 0)
				(effects
					(font
						(size 1.27 1.27)
						(thickness 0.15)
					)
					(justify left bottom)
					(hide yes)
				)
			)
			(property "Datasheet" "https://www.bourns.com/docs/product-datasheets/cr.pdf"
				(at 20.32 -17.78 0)
				(effects
					(font
						(size 1.27 1.27)
						(thickness 0.15)
					)
					(justify left bottom)
					(hide yes)
				)
			)
			(property "Description" "SMD Chip Resistor, 8.06 kohm, ± 1%, 63 mW, 0402 [1005 Metric], Thick Film, General Purpose"
				(at 0 0 0)
				(effects
					(font
						(size 1.27 1.27)
					)
					(hide yes)
				)
			)
			(property "MPN" "CR0402-FX-8061GLF"
				(at 20.32 -20.32 0)
				(effects
					(font
						(size 1.27 1.27)
						(thickness 0.15)
					)
					(justify left bottom)
					(hide yes)
				)
			)
			(property "Manufacturer" "Bourns"
				(at 20.32 -22.86 0)
				(effects
					(font
						(size 1.27 1.27)
						(thickness 0.15)
					)
					(justify left bottom)
					(hide yes)
				)
			)
			(property "License" "Apache-2.0"
				(at 20.32 -25.4 0)
				(effects
					(font
						(size 1.27 1.27)
						(thickness 0.15)
					)
					(justify left bottom)
					(hide yes)
				)
			)
			(property "Author" "Antmicro"
				(at 20.32 -27.94 0)
				(effects
					(font
						(size 1.27 1.27)
						(thickness 0.15)
					)
					(justify left bottom)
					(hide yes)
				)
			)
			(property "Val" "8k06"
				(at 20.32 -7.62 0)
				(effects
					(font
						(size 1.27 1.27)
						(thickness 0.15)
					)
					(justify left bottom)
				)
			)
			(property "Tolerance" "1%"
				(at 20.32 -10.16 0)
				(effects
					(font
						(size 1.27 1.27)
					)
					(justify left bottom)
					(hide yes)
				)
			)
			(property "ki_keywords" "0402, SMT, RESISTOR, PASSIVE"
				(at 0 0 0)
				(effects
					(font
						(size 1.27 1.27)
					)
					(hide yes)
				)
			)
			(symbol "R_8k06_0402_0_1"
				(rectangle
					(start 0.635 0.889)
					(end 4.445 -0.889)
					(stroke
						(width 0.254)
						(type default)
					)
					(fill
						(type none)
					)
				)
			)
			(symbol "R_8k06_0402_1_1"
				(pin passive line
					(at 0 0 0)
					(length 0.635)
					(name "~"
						(effects
							(font
								(size 1.27 1.27)
							)
						)
					)
					(number "1"
						(effects
							(font
								(size 1.27 1.27)
							)
						)
					)
				)
				(pin passive line
					(at 5.08 0 180)
					(length 0.635)
					(name "~"
						(effects
							(font
								(size 1.27 1.27)
							)
						)
					)
					(number "2"
						(effects
							(font
								(size 1.27 1.27)
							)
						)
					)
				)
			)
		)
	(symbol "antmicroResistors0402:R_93k1_0402"
			(pin_numbers
				(hide yes)
			)
			(pin_names
				(hide yes)
			)
			(exclude_from_sim no)
			(in_bom yes)
			(on_board yes)
			(property "Reference" "R"
				(at 20.32 -5.08 0)
				(effects
					(font
						(size 1.27 1.27)
						(thickness 0.15)
					)
					(justify left bottom)
				)
			)
			(property "Value" "R_93k1_0402"
				(at 20.32 -12.7 0)
				(effects
					(font
						(size 1.27 1.27)
						(thickness 0.15)
					)
					(justify left bottom)
					(hide yes)
				)
			)
			(property "Footprint" "antmicro-footprints:R_0402_1005Metric"
				(at 20.32 -15.24 0)
				(effects
					(font
						(size 1.27 1.27)
						(thickness 0.15)
					)
					(justify left bottom)
					(hide yes)
				)
			)
			(property "Datasheet" "https://www.bourns.com/docs/product-datasheets/cr.pdf"
				(at 20.32 -17.78 0)
				(effects
					(font
						(size 1.27 1.27)
						(thickness 0.15)
					)
					(justify left bottom)
					(hide yes)
				)
			)
			(property "Description" "SMD Chip Resistor"
				(at 0 0 0)
				(effects
					(font
						(size 1.27 1.27)
					)
					(hide yes)
				)
			)
			(property "MPN" "CR0402-FX-9312GLF"
				(at 20.32 -20.32 0)
				(effects
					(font
						(size 1.27 1.27)
						(thickness 0.15)
					)
					(justify left bottom)
					(hide yes)
				)
			)
			(property "Manufacturer" "Bourns"
				(at 20.32 -22.86 0)
				(effects
					(font
						(size 1.27 1.27)
						(thickness 0.15)
					)
					(justify left bottom)
					(hide yes)
				)
			)
			(property "License" "Apache-2.0"
				(at 20.32 -25.4 0)
				(effects
					(font
						(size 1.27 1.27)
						(thickness 0.15)
					)
					(justify left bottom)
					(hide yes)
				)
			)
			(property "Author" "Antmicro"
				(at 20.32 -27.94 0)
				(effects
					(font
						(size 1.27 1.27)
						(thickness 0.15)
					)
					(justify left bottom)
					(hide yes)
				)
			)
			(property "Val" "93k1"
				(at 20.32 -7.62 0)
				(effects
					(font
						(size 1.27 1.27)
						(thickness 0.15)
					)
					(justify left bottom)
				)
			)
			(property "Tolerance" "1%"
				(at 20.32 -10.16 0)
				(effects
					(font
						(size 1.27 1.27)
					)
					(justify left bottom)
					(hide yes)
				)
			)
			(property "ki_keywords" "0402, SMT, RESISTOR, PASSIVE"
				(at 0 0 0)
				(effects
					(font
						(size 1.27 1.27)
					)
					(hide yes)
				)
			)
			(symbol "R_93k1_0402_0_1"
				(rectangle
					(start 0.635 0.889)
					(end 4.445 -0.889)
					(stroke
						(width 0.254)
						(type default)
					)
					(fill
						(type none)
					)
				)
			)
			(symbol "R_93k1_0402_1_1"
				(pin passive line
					(at 0 0 0)
					(length 0.635)
					(name "~"
						(effects
							(font
								(size 1.27 1.27)
							)
						)
					)
					(number "1"
						(effects
							(font
								(size 1.27 1.27)
							)
						)
					)
				)
				(pin passive line
					(at 5.08 0 180)
					(length 0.635)
					(name "~"
						(effects
							(font
								(size 1.27 1.27)
							)
						)
					)
					(number "2"
						(effects
							(font
								(size 1.27 1.27)
							)
						)
					)
				)
			)
		)
	(symbol "antmicroResistors0603:R_0R01_0603"
			(pin_numbers
				(hide yes)
			)
			(pin_names
				(hide yes)
			)
			(exclude_from_sim no)
			(in_bom yes)
			(on_board yes)
			(property "Reference" "R"
				(at 20.32 -5.08 0)
				(effects
					(font
						(size 1.27 1.27)
						(thickness 0.15)
					)
					(justify left bottom)
				)
			)
			(property "Value" "R_0R01_0603"
				(at 20.32 -12.7 0)
				(effects
					(font
						(size 1.27 1.27)
						(thickness 0.15)
					)
					(justify left bottom)
					(hide yes)
				)
			)
			(property "Footprint" "antmicro-footprints:R_0603_1608Metric"
				(at 20.32 -15.24 0)
				(effects
					(font
						(size 1.27 1.27)
						(thickness 0.15)
					)
					(justify left bottom)
					(hide yes)
				)
			)
			(property "Datasheet" "https://www.bourns.com/docs/product-datasheets/cfn-a.pdf"
				(at 20.32 -17.78 0)
				(effects
					(font
						(size 1.27 1.27)
						(thickness 0.15)
					)
					(justify left bottom)
					(hide yes)
				)
			)
			(property "Description" "SMD Chip Resistor, 10 mohm, ± 1%, 0.5 W, 0603 [1608 Metric], Metal Foil, Current Sensing"
				(at 0 0 0)
				(effects
					(font
						(size 1.27 1.27)
					)
					(hide yes)
				)
			)
			(property "MPN" "CFN0603AFZ-R010ELF"
				(at 20.32 -20.32 0)
				(effects
					(font
						(size 1.27 1.27)
						(thickness 0.15)
					)
					(justify left bottom)
					(hide yes)
				)
			)
			(property "Manufacturer" "Bourns"
				(at 20.32 -22.86 0)
				(effects
					(font
						(size 1.27 1.27)
						(thickness 0.15)
					)
					(justify left bottom)
					(hide yes)
				)
			)
			(property "License" "Apache-2.0"
				(at 20.32 -25.4 0)
				(effects
					(font
						(size 1.27 1.27)
						(thickness 0.15)
					)
					(justify left bottom)
					(hide yes)
				)
			)
			(property "Author" "Antmicro"
				(at 20.32 -27.94 0)
				(effects
					(font
						(size 1.27 1.27)
						(thickness 0.15)
					)
					(justify left bottom)
					(hide yes)
				)
			)
			(property "Val" "0R01"
				(at 20.32 -7.62 0)
				(effects
					(font
						(size 1.27 1.27)
						(thickness 0.15)
					)
					(justify left bottom)
				)
			)
			(property "Tolerance" "1%"
				(at 20.32 -10.16 0)
				(effects
					(font
						(size 1.27 1.27)
					)
					(justify left bottom)
					(hide yes)
				)
			)
			(property "ki_keywords" "0603, SMT, RESISTOR, PASSIVE"
				(at 0 0 0)
				(effects
					(font
						(size 1.27 1.27)
					)
					(hide yes)
				)
			)
			(symbol "R_0R01_0603_0_1"
				(rectangle
					(start 0.635 0.889)
					(end 4.445 -0.889)
					(stroke
						(width 0.254)
						(type default)
					)
					(fill
						(type none)
					)
				)
			)
			(symbol "R_0R01_0603_1_1"
				(pin passive line
					(at 0 0 0)
					(length 0.635)
					(name "~"
						(effects
							(font
								(size 1.27 1.27)
							)
						)
					)
					(number "1"
						(effects
							(font
								(size 1.27 1.27)
							)
						)
					)
				)
				(pin passive line
					(at 5.08 0 180)
					(length 0.635)
					(name "~"
						(effects
							(font
								(size 1.27 1.27)
							)
						)
					)
					(number "2"
						(effects
							(font
								(size 1.27 1.27)
							)
						)
					)
				)
			)
		)
	(symbol "antmicroResistors0603:R_0R_22.4A_0603"
			(pin_numbers
				(hide yes)
			)
			(pin_names
				(hide yes)
			)
			(exclude_from_sim no)
			(in_bom yes)
			(on_board yes)
			(property "Reference" "R"
				(at 15.24 -2.54 0)
				(effects
					(font
						(size 1.27 1.27)
						(thickness 0.15)
					)
					(justify left bottom)
				)
			)
			(property "Value" "R_0R_22.4A_0603"
				(at 15.24 -5.08 0)
				(effects
					(font
						(size 1.27 1.27)
						(thickness 0.15)
					)
					(justify left bottom)
				)
			)
			(property "Footprint" "antmicro-footprints:R_0603_1608Metric"
				(at 15.24 -10.16 0)
				(effects
					(font
						(size 1.27 1.27)
						(thickness 0.15)
					)
					(justify left bottom)
					(hide yes)
				)
			)
			(property "Datasheet" "https://fscdn.rohm.com/en/products/databook/datasheet/passive/resistor/chip_resistor/pmr-jpw-e.pdf"
				(at 15.24 -12.7 0)
				(effects
					(font
						(size 1.27 1.27)
						(thickness 0.15)
					)
					(justify left bottom)
					(hide yes)
				)
			)
			(property "Description" "SMD Chip Resistor"
				(at 0 0 0)
				(effects
					(font
						(size 1.27 1.27)
					)
					(hide yes)
				)
			)
			(property "MPN" "PMR03EZPJ000"
				(at 15.24 -15.24 0)
				(effects
					(font
						(size 1.27 1.27)
						(thickness 0.15)
					)
					(justify left bottom)
					(hide yes)
				)
			)
			(property "Manufacturer" "ROHM Semiconductor"
				(at 15.24 -17.78 0)
				(effects
					(font
						(size 1.27 1.27)
						(thickness 0.15)
					)
					(justify left bottom)
					(hide yes)
				)
			)
			(property "Val" "0R"
				(at 15.24 -7.62 0)
				(effects
					(font
						(size 1.27 1.27)
						(thickness 0.15)
					)
					(justify left bottom)
				)
			)
			(property "Max. Curr." "22.4A"
				(at 15.24 -20.32 0)
				(effects
					(font
						(size 1.27 1.27)
						(thickness 0.15)
					)
					(justify left bottom)
				)
			)
			(property "Author" "Antmicro"
				(at 15.24 -22.86 0)
				(effects
					(font
						(size 1.27 1.27)
						(thickness 0.15)
					)
					(justify left bottom)
					(hide yes)
				)
			)
			(property "License" "Apache-2.0"
				(at 15.24 -25.4 0)
				(effects
					(font
						(size 1.27 1.27)
						(thickness 0.15)
					)
					(justify left bottom)
					(hide yes)
				)
			)
			(property "Tolerance" "template_tolerance"
				(at 20.32 -10.16 0)
				(effects
					(font
						(size 1.27 1.27)
					)
					(justify left bottom)
					(hide yes)
				)
			)
			(property "ki_keywords" "0603, SMT, RESISTOR, PASSIVE"
				(at 0 0 0)
				(effects
					(font
						(size 1.27 1.27)
					)
					(hide yes)
				)
			)
			(symbol "R_0R_22.4A_0603_0_1"
				(rectangle
					(start 0.635 0.889)
					(end 4.445 -0.889)
					(stroke
						(width 0.254)
						(type default)
					)
					(fill
						(type none)
					)
				)
			)
			(symbol "R_0R_22.4A_0603_1_1"
				(pin passive line
					(at 0 0 0)
					(length 0.635)
					(name "~"
						(effects
							(font
								(size 1.27 1.27)
							)
						)
					)
					(number "1"
						(effects
							(font
								(size 1.27 1.27)
							)
						)
					)
				)
				(pin passive line
					(at 5.08 0 180)
					(length 0.635)
					(name "~"
						(effects
							(font
								(size 1.27 1.27)
							)
						)
					)
					(number "2"
						(effects
							(font
								(size 1.27 1.27)
							)
						)
					)
				)
			)
		)
	(symbol "antmicroTVSDiodes:AXGD10402KR"
			(pin_numbers
				(hide yes)
			)
			(pin_names
				(hide yes)
			)
			(exclude_from_sim no)
			(in_bom yes)
			(on_board yes)
			(property "Reference" "D"
				(at 25.4 -5.08 0)
				(effects
					(font
						(size 1.27 1.27)
						(thickness 0.15)
					)
					(justify left bottom)
				)
			)
			(property "Value" "AXGD10402KR"
				(at 25.4 -10.16 0)
				(effects
					(font
						(size 1.27 1.27)
						(thickness 0.15)
					)
					(justify left bottom)
					(hide yes)
				)
			)
			(property "Footprint" "antmicro-footprints:D_0402_1005Metric"
				(at 25.4 -12.7 0)
				(effects
					(font
						(size 1.27 1.27)
						(thickness 0.15)
					)
					(justify left bottom)
					(hide yes)
				)
			)
			(property "Datasheet" "https://www.littelfuse.com/media?resourcetype=datasheets&itemid=020b2bf2-064c-4ff1-a898-b4ec805b2fea&filename=littelfuse-xtremeguard-axgd-datasheet"
				(at 25.4 -15.24 0)
				(effects
					(font
						(size 1.27 1.27)
						(thickness 0.15)
					)
					(justify left bottom)
					(hide yes)
				)
			)
			(property "Description" "Bidirectional TVS, 30 kV,  0402, 24 V, 0.04 pF"
				(at 0 0 0)
				(effects
					(font
						(size 1.27 1.27)
					)
					(hide yes)
				)
			)
			(property "Manufacturer" "Littelfuse"
				(at 25.4 -17.78 0)
				(effects
					(font
						(size 1.27 1.27)
						(thickness 0.15)
					)
					(justify left bottom)
					(hide yes)
				)
			)
			(property "MPN" "AXGD10402KR"
				(at 25.4 -7.62 0)
				(effects
					(font
						(size 1.27 1.27)
						(thickness 0.15)
					)
					(justify left bottom)
				)
			)
			(property "Author" "Antmicro"
				(at 25.4 -20.32 0)
				(effects
					(font
						(size 1.27 1.27)
						(thickness 0.15)
					)
					(justify left bottom)
					(hide yes)
				)
			)
			(property "License" "Apache-2.0"
				(at 25.4 -22.86 0)
				(effects
					(font
						(size 1.27 1.27)
						(thickness 0.15)
					)
					(justify left bottom)
					(hide yes)
				)
			)
			(property "ki_keywords" "DIODE, SEMICONDUCTOR, TVS, ESD"
				(at 0 0 0)
				(effects
					(font
						(size 1.27 1.27)
					)
					(hide yes)
				)
			)
			(symbol "AXGD10402KR_0_0"
				(text ""
					(at 7.62 -1.27 0)
					(effects
						(font
							(size 1.27 1.27)
						)
					)
				)
			)
			(symbol "AXGD10402KR_0_1"
				(polyline
					(pts
						(xy 0.635 0) (xy 4.445 0)
					)
					(stroke
						(width 0)
						(type default)
					)
					(fill
						(type none)
					)
				)
			)
			(symbol "AXGD10402KR_1_1"
				(polyline
					(pts
						(xy 1.016 -1.016) (xy 1.016 1.016) (xy 2.54 0) (xy 1.016 -1.016)
					)
					(stroke
						(width 0.254)
						(type default)
					)
					(fill
						(type outline)
					)
				)
				(polyline
					(pts
						(xy 2.54 1.016) (xy 2.159 1.016)
					)
					(stroke
						(width 0.254)
						(type default)
					)
					(fill
						(type none)
					)
				)
				(polyline
					(pts
						(xy 2.54 1.016) (xy 2.54 -1.016)
					)
					(stroke
						(width 0.254)
						(type default)
					)
					(fill
						(type none)
					)
				)
				(polyline
					(pts
						(xy 2.921 -1.016) (xy 2.54 -1.016)
					)
					(stroke
						(width 0.254)
						(type default)
					)
					(fill
						(type none)
					)
				)
				(polyline
					(pts
						(xy 4.064 1.016) (xy 4.064 -1.016) (xy 2.54 0) (xy 4.064 1.016)
					)
					(stroke
						(width 0.254)
						(type default)
					)
					(fill
						(type outline)
					)
				)
				(pin passive line
					(at 0 0 0)
					(length 0.635)
					(name "C"
						(effects
							(font
								(size 1.27 1.27)
							)
						)
					)
					(number "1"
						(effects
							(font
								(size 1.27 1.27)
							)
						)
					)
				)
				(pin passive line
					(at 5.08 0 180)
					(length 0.635)
					(name "A"
						(effects
							(font
								(size 1.27 1.27)
							)
						)
					)
					(number "2"
						(effects
							(font
								(size 1.27 1.27)
							)
						)
					)
				)
			)
		)
	(symbol "antmicroTestPoints:TP_0.75mm_SMD"
			(pin_names
				(hide yes)
			)
			(exclude_from_sim no)
			(in_bom no)
			(on_board yes)
			(property "Reference" "TP"
				(at 10.16 -1.27 0)
				(effects
					(font
						(size 1.27 1.27)
						(thickness 0.15)
					)
					(justify left bottom)
				)
			)
			(property "Value" "TP_0.75mm_SMD"
				(at 10.16 -3.81 0)
				(effects
					(font
						(size 1.27 1.27)
						(thickness 0.15)
					)
					(justify left bottom)
					(hide yes)
				)
			)
			(property "Footprint" "antmicro-footprints:TP_SMD_0.75mm"
				(at 10.16 -6.35 0)
				(effects
					(font
						(size 1.27 1.27)
						(thickness 0.15)
					)
					(justify left bottom)
					(hide yes)
				)
			)
			(property "Datasheet" ""
				(at 17.78 -12.7 0)
				(effects
					(font
						(size 1.27 1.27)
						(thickness 0.15)
					)
					(justify left bottom)
					(hide yes)
				)
			)
			(property "Description" "SMT test point"
				(at 0 0 0)
				(effects
					(font
						(size 1.27 1.27)
					)
					(hide yes)
				)
			)
			(property "MPN" ""
				(at 10.795 -11.43 0)
				(effects
					(font
						(size 1.27 1.27)
						(thickness 0.15)
					)
					(justify left bottom)
					(hide yes)
				)
			)
			(property "Manufacturer" ""
				(at 10.795 -6.35 0)
				(effects
					(font
						(size 1.27 1.27)
						(thickness 0.15)
					)
					(justify left bottom)
					(hide yes)
				)
			)
			(property "Author" "Antmicro"
				(at 10.16 -8.89 0)
				(effects
					(font
						(size 1.27 1.27)
						(thickness 0.15)
					)
					(justify left bottom)
					(hide yes)
				)
			)
			(property "License" "Apache-2.0"
				(at 10.16 -11.43 0)
				(effects
					(font
						(size 1.27 1.27)
						(thickness 0.15)
					)
					(justify left bottom)
					(hide yes)
				)
			)
			(property "ki_keywords" "TESTPOINT"
				(at 0 0 0)
				(effects
					(font
						(size 1.27 1.27)
					)
					(hide yes)
				)
			)
			(symbol "TP_0.75mm_SMD_1_1"
				(circle
					(center 3.175 0)
					(radius 0.635)
					(stroke
						(width 0.254)
						(type default)
					)
					(fill
						(type none)
					)
				)
				(pin passive line
					(at 0 0 0)
					(length 2.54)
					(name "1"
						(effects
							(font
								(size 1.27 1.27)
							)
						)
					)
					(number "1"
						(effects
							(font
								(size 1.27 1.27)
							)
						)
					)
				)
			)
		)
	(symbol "antmicroTestPoints:Tag-Connect_TC2050-IDC-NL_2x5_P1.27mm"
			(exclude_from_sim no)
			(in_bom no)
			(on_board yes)
			(property "Reference" "J"
				(at 38.1 -1.27 0)
				(effects
					(font
						(size 1.27 1.27)
						(thickness 0.15)
					)
					(justify left bottom)
				)
			)
			(property "Value" "Tag-Connect_TC2050-IDC-NL_2x5_P1.27mm"
				(at 38.1 -3.81 0)
				(effects
					(font
						(size 1.27 1.27)
						(thickness 0.15)
					)
					(justify left bottom)
					(hide yes)
				)
			)
			(property "Footprint" "antmicro-footprints:Tag-Connect_TC2050-IDC-NL_2x5_P1.27mm"
				(at 38.1 -6.35 0)
				(effects
					(font
						(size 1.27 1.27)
						(thickness 0.15)
					)
					(justify left bottom)
					(hide yes)
				)
			)
			(property "Datasheet" "https://www.tag-connect.com/wp-content/uploads/bsk-pdf-manager/TC2050-IDC-NL_Datasheet_8.pdf"
				(at 38.1 -8.89 0)
				(effects
					(font
						(size 1.27 1.27)
						(thickness 0.15)
					)
					(justify left bottom)
					(hide yes)
				)
			)
			(property "Description" "Tag Connect 2x5 1.27mm terminal"
				(at 0 0 0)
				(effects
					(font
						(size 1.27 1.27)
					)
					(hide yes)
				)
			)
			(property "MPN" "TC2050-IDC-NL"
				(at 38.1 -11.43 0)
				(effects
					(font
						(size 1.27 1.27)
						(thickness 0.15)
					)
					(justify left bottom)
				)
			)
			(property "Manufacturer" "Tag Connect"
				(at 38.1 -13.97 0)
				(effects
					(font
						(size 1.27 1.27)
						(thickness 0.15)
					)
					(justify left bottom)
					(hide yes)
				)
			)
			(property "Author" "Antmicro"
				(at 38.1 -16.51 0)
				(effects
					(font
						(size 1.27 1.27)
						(thickness 0.15)
					)
					(justify left bottom)
					(hide yes)
				)
			)
			(property "License" "Apache-2.0"
				(at 38.1 -19.05 0)
				(effects
					(font
						(size 1.27 1.27)
						(thickness 0.15)
					)
					(justify left bottom)
					(hide yes)
				)
			)
			(property "ki_keywords" "POGO-PIN, CONNECTOR"
				(at 0 0 0)
				(effects
					(font
						(size 1.27 1.27)
					)
					(hide yes)
				)
			)
			(symbol "Tag-Connect_TC2050-IDC-NL_2x5_P1.27mm_1_1"
				(rectangle
					(start 2.54 2.54)
					(end 26.67 -12.7)
					(stroke
						(width 0)
						(type default)
					)
					(fill
						(type background)
					)
				)
				(circle
					(center 13.843 -7.5184)
					(radius 0.4572)
					(stroke
						(width 0)
						(type default)
					)
					(fill
						(type none)
					)
				)
				(polyline
					(pts
						(xy 13.97 -8.636) (xy 15.875 -8.636) (xy 16.51 -8.001) (xy 16.51 -2.921) (xy 15.24 -1.016) (xy 13.97 -1.016)
						(xy 12.7 -2.921) (xy 12.7 -8.001) (xy 13.335 -8.636) (xy 13.97 -8.636)
					)
					(stroke
						(width 0)
						(type default)
					)
					(fill
						(type none)
					)
				)
				(circle
					(center 14.097 -3.4544)
					(radius 0.2032)
					(stroke
						(width 0)
						(type default)
					)
					(fill
						(type outline)
					)
				)
				(circle
					(center 14.097 -4.1656)
					(radius 0.2032)
					(stroke
						(width 0)
						(type default)
					)
					(fill
						(type outline)
					)
				)
				(circle
					(center 14.097 -4.9276)
					(radius 0.2032)
					(stroke
						(width 0)
						(type default)
					)
					(fill
						(type outline)
					)
				)
				(circle
					(center 14.097 -5.6388)
					(radius 0.2032)
					(stroke
						(width 0)
						(type default)
					)
					(fill
						(type outline)
					)
				)
				(circle
					(center 14.097 -6.4008)
					(radius 0.2032)
					(stroke
						(width 0)
						(type default)
					)
					(fill
						(type outline)
					)
				)
				(circle
					(center 14.605 -2.1336)
					(radius 0.4572)
					(stroke
						(width 0)
						(type default)
					)
					(fill
						(type none)
					)
				)
				(circle
					(center 15.113 -3.4544)
					(radius 0.2032)
					(stroke
						(width 0)
						(type default)
					)
					(fill
						(type outline)
					)
				)
				(circle
					(center 15.113 -4.1656)
					(radius 0.2032)
					(stroke
						(width 0)
						(type default)
					)
					(fill
						(type outline)
					)
				)
				(circle
					(center 15.113 -4.9276)
					(radius 0.2032)
					(stroke
						(width 0)
						(type default)
					)
					(fill
						(type outline)
					)
				)
				(circle
					(center 15.113 -5.6388)
					(radius 0.2032)
					(stroke
						(width 0)
						(type default)
					)
					(fill
						(type outline)
					)
				)
				(circle
					(center 15.113 -6.4008)
					(radius 0.2032)
					(stroke
						(width 0)
						(type default)
					)
					(fill
						(type outline)
					)
				)
				(circle
					(center 15.4686 -7.5184)
					(radius 0.4572)
					(stroke
						(width 0)
						(type default)
					)
					(fill
						(type none)
					)
				)
				(text "Tag-Connect"
					(at 14.605 1.651 0)
					(effects
						(font
							(size 0.7 0.7)
						)
					)
				)
				(text "ALT: 3.3V I2C/JTAG/SPI/SWD/FTDI"
					(at 14.732 -11.938 0)
					(effects
						(font
							(size 0.7 0.7)
						)
					)
				)
				(pin passive line
					(at 0 0 0)
					(length 2.54)
					(name "1"
						(effects
							(font
								(size 1.27 1.27)
							)
						)
					)
					(number "1"
						(effects
							(font
								(size 1.27 1.27)
							)
						)
					)
					(alternate "3V3" passive line)
				)
				(pin passive line
					(at 0 -2.54 0)
					(length 2.54)
					(name "2"
						(effects
							(font
								(size 1.27 1.27)
							)
						)
					)
					(number "2"
						(effects
							(font
								(size 1.27 1.27)
							)
						)
					)
					(alternate "ADBUS3" passive line)
					(alternate "I2C_NC" passive line)
					(alternate "JTAG_TMS" passive line)
					(alternate "SPI_CS" passive line)
					(alternate "SWD_NC" passive line)
				)
				(pin passive line
					(at 0 -5.08 0)
					(length 2.54)
					(name "3"
						(effects
							(font
								(size 1.27 1.27)
							)
						)
					)
					(number "3"
						(effects
							(font
								(size 1.27 1.27)
							)
						)
					)
					(alternate "GND" passive line)
				)
				(pin passive line
					(at 0 -7.62 0)
					(length 2.54)
					(name "4"
						(effects
							(font
								(size 1.27 1.27)
							)
						)
					)
					(number "4"
						(effects
							(font
								(size 1.27 1.27)
							)
						)
					)
					(alternate "ADBUS0" passive line)
					(alternate "I2C_SCL" passive line)
					(alternate "JTAG_TCK" passive line)
					(alternate "SPI_SCK" passive line)
					(alternate "SWD_CLK" passive line)
				)
				(pin passive line
					(at 0 -10.16 0)
					(length 2.54)
					(name "5"
						(effects
							(font
								(size 1.27 1.27)
							)
						)
					)
					(number "5"
						(effects
							(font
								(size 1.27 1.27)
							)
						)
					)
					(alternate "GND" passive line)
				)
				(pin passive line
					(at 29.21 0 180)
					(length 2.54)
					(name "10"
						(effects
							(font
								(size 1.27 1.27)
							)
						)
					)
					(number "10"
						(effects
							(font
								(size 1.27 1.27)
							)
						)
					)
					(alternate "ADBUS5" passive line)
					(alternate "I2C_NC" passive line)
					(alternate "JTAG_~{RESET}" passive line)
					(alternate "SPI_NC" passive line)
					(alternate "SWD_NC" passive line)
				)
				(pin passive line
					(at 29.21 -2.54 180)
					(length 2.54)
					(name "9"
						(effects
							(font
								(size 1.27 1.27)
							)
						)
					)
					(number "9"
						(effects
							(font
								(size 1.27 1.27)
							)
						)
					)
					(alternate "GND" passive line)
				)
				(pin passive line
					(at 29.21 -5.08 180)
					(length 2.54)
					(name "8"
						(effects
							(font
								(size 1.27 1.27)
							)
						)
					)
					(number "8"
						(effects
							(font
								(size 1.27 1.27)
							)
						)
					)
					(alternate "ADBUS1" passive line)
					(alternate "I2C_SDA" passive line)
					(alternate "JTAG_TDI" passive line)
					(alternate "SPI_MOSI" passive line)
					(alternate "SWD_IO" passive line)
				)
				(pin passive line
					(at 29.21 -7.62 180)
					(length 2.54)
					(name "7"
						(effects
							(font
								(size 1.27 1.27)
							)
						)
					)
					(number "7"
						(effects
							(font
								(size 1.27 1.27)
							)
						)
					)
					(alternate "NC" passive line)
				)
				(pin passive line
					(at 29.21 -10.16 180)
					(length 2.54)
					(name "6"
						(effects
							(font
								(size 1.27 1.27)
							)
						)
					)
					(number "6"
						(effects
							(font
								(size 1.27 1.27)
							)
						)
					)
					(alternate "ADBUS2" passive line)
					(alternate "I2C_SDA" passive line)
					(alternate "JTAG_TDO" passive line)
					(alternate "SPI_MISO" passive line)
					(alternate "SWD_IO" passive line)
				)
			)
		)
	(symbol "antmicroTransistorsFETsMOSFETsSingle:AO3401A"
			(pin_names
				(offset 0)
			)
			(exclude_from_sim no)
			(in_bom yes)
			(on_board yes)
			(property "Reference" "Q"
				(at 22.86 -6.35 0)
				(effects
					(font
						(size 1.27 1.27)
						(thickness 0.15)
					)
					(justify left bottom)
				)
			)
			(property "Value" "AO3401A"
				(at 22.86 -8.89 0)
				(effects
					(font
						(size 1.27 1.27)
						(thickness 0.15)
					)
					(justify left bottom)
					(hide yes)
				)
			)
			(property "Footprint" "antmicro-footprints:SOT-23-3"
				(at 22.86 -11.43 0)
				(effects
					(font
						(size 1.27 1.27)
						(thickness 0.15)
					)
					(justify left bottom)
					(hide yes)
				)
			)
			(property "Datasheet" "http://aosmd.com/res/data_sheets/AO3401A.pdf"
				(at 22.86 -13.97 0)
				(effects
					(font
						(size 1.27 1.27)
						(thickness 0.15)
					)
					(justify left bottom)
					(hide yes)
				)
			)
			(property "Description" "Power MOSFET, P Channel, 30 V, 4 A, 0.07 ohm, SOT-23, Surface Mount"
				(at 58.42 -25.654 0)
				(effects
					(font
						(size 1.27 1.27)
					)
					(hide yes)
				)
			)
			(property "MPN" "AO3401A"
				(at 22.86 -16.51 0)
				(effects
					(font
						(size 1.27 1.27)
						(thickness 0.15)
					)
					(justify left bottom)
				)
			)
			(property "Manufacturer" "AOSMD"
				(at 22.86 -19.05 0)
				(effects
					(font
						(size 1.27 1.27)
						(thickness 0.15)
					)
					(justify left bottom)
					(hide yes)
				)
			)
			(property "Author" "Antmicro"
				(at 22.86 -21.59 0)
				(effects
					(font
						(size 1.27 1.27)
						(thickness 0.15)
					)
					(justify left bottom)
					(hide yes)
				)
			)
			(property "License" "Apache-2.0"
				(at 22.86 -24.13 0)
				(effects
					(font
						(size 1.27 1.27)
						(thickness 0.15)
					)
					(justify left bottom)
					(hide yes)
				)
			)
			(property "ki_keywords" "SMT, TRANSISTOR, SEMICONDUCTOR"
				(at 0 0 0)
				(effects
					(font
						(size 1.27 1.27)
					)
					(hide yes)
				)
			)
			(symbol "AO3401A_1_1"
				(polyline
					(pts
						(xy 2.54 0) (xy 4.572 0) (xy 4.572 3.937)
					)
					(stroke
						(width 0.254)
						(type default)
					)
					(fill
						(type none)
					)
				)
				(polyline
					(pts
						(xy 5.08 4.445) (xy 5.08 3.429)
					)
					(stroke
						(width 0.254)
						(type default)
					)
					(fill
						(type background)
					)
				)
				(polyline
					(pts
						(xy 5.08 2.54) (xy 5.08 3.048)
					)
					(stroke
						(width 0.254)
						(type default)
					)
					(fill
						(type background)
					)
				)
				(polyline
					(pts
						(xy 5.08 2.54) (xy 5.08 2.032)
					)
					(stroke
						(width 0.254)
						(type default)
					)
					(fill
						(type background)
					)
				)
				(polyline
					(pts
						(xy 5.08 1.143) (xy 5.08 1.651)
					)
					(stroke
						(width 0.254)
						(type default)
					)
					(fill
						(type background)
					)
				)
				(polyline
					(pts
						(xy 5.08 1.143) (xy 5.08 0.635)
					)
					(stroke
						(width 0.254)
						(type default)
					)
					(fill
						(type background)
					)
				)
				(circle
					(center 6.35 2.54)
					(radius 3.302)
					(stroke
						(width 0.254)
						(type default)
					)
					(fill
						(type background)
					)
				)
				(polyline
					(pts
						(xy 7.239 2.54) (xy 6.477 3.048) (xy 6.477 2.032) (xy 7.239 2.54)
					)
					(stroke
						(width 0.254)
						(type default)
					)
					(fill
						(type outline)
					)
				)
				(polyline
					(pts
						(xy 7.493 0.635) (xy 8.636 0.635) (xy 8.636 3.937) (xy 8.636 4.445) (xy 7.493 4.445)
					)
					(stroke
						(width 0.254)
						(type default)
					)
					(fill
						(type background)
					)
				)
				(polyline
					(pts
						(xy 7.62 6.35) (xy 7.62 3.937) (xy 5.08 3.937)
					)
					(stroke
						(width 0.254)
						(type default)
					)
					(fill
						(type none)
					)
				)
				(circle
					(center 7.62 4.445)
					(radius 0.127)
					(stroke
						(width 0.254)
						(type default)
					)
					(fill
						(type background)
					)
				)
				(polyline
					(pts
						(xy 7.62 1.143) (xy 5.08 1.143)
					)
					(stroke
						(width 0.254)
						(type default)
					)
					(fill
						(type background)
					)
				)
				(circle
					(center 7.62 1.143)
					(radius 0.127)
					(stroke
						(width 0.254)
						(type default)
					)
					(fill
						(type background)
					)
				)
				(circle
					(center 7.62 0.635)
					(radius 0.127)
					(stroke
						(width 0.254)
						(type default)
					)
					(fill
						(type background)
					)
				)
				(polyline
					(pts
						(xy 7.62 -1.27) (xy 7.62 2.54) (xy 5.08 2.54)
					)
					(stroke
						(width 0.254)
						(type default)
					)
					(fill
						(type none)
					)
				)
				(polyline
					(pts
						(xy 8.636 2.286) (xy 8.128 3.048) (xy 9.144 3.048) (xy 8.636 2.286)
					)
					(stroke
						(width 0.254)
						(type default)
					)
					(fill
						(type outline)
					)
				)
				(polyline
					(pts
						(xy 9.144 2.2352) (xy 8.128 2.2352)
					)
					(stroke
						(width 0.254)
						(type default)
					)
					(fill
						(type background)
					)
				)
				(pin input line
					(at 0 0 0)
					(length 2.54)
					(name "G"
						(effects
							(font
								(size 1.27 1.27)
							)
						)
					)
					(number "1"
						(effects
							(font
								(size 1.27 1.27)
							)
						)
					)
				)
				(pin passive line
					(at 7.62 8.89 270)
					(length 2.54)
					(name "D"
						(effects
							(font
								(size 1.27 1.27)
							)
						)
					)
					(number "3"
						(effects
							(font
								(size 1.27 1.27)
							)
						)
					)
				)
				(pin passive line
					(at 7.62 -3.81 90)
					(length 2.54)
					(name "S"
						(effects
							(font
								(size 1.27 1.27)
							)
						)
					)
					(number "2"
						(effects
							(font
								(size 1.27 1.27)
							)
						)
					)
				)
			)
		)
	(symbol "antmicroTransistorsFETsMOSFETsSingle:DMG1012T-7"
			(pin_names
				(offset 0)
			)
			(exclude_from_sim no)
			(in_bom no)
			(on_board yes)
			(property "Reference" "Q"
				(at 10.16 3.81 0)
				(effects
					(font
						(size 1.27 1.27)
						(thickness 0.15)
					)
					(justify left bottom)
				)
			)
			(property "Value" "DMG1012T-7"
				(at 10.16 -3.81 0)
				(effects
					(font
						(size 1.27 1.27)
						(thickness 0.15)
					)
					(justify left bottom)
					(hide yes)
				)
			)
			(property "Footprint" "antmicro-footprints:SOT-523"
				(at 10.16 -6.35 0)
				(effects
					(font
						(size 1.27 1.27)
						(thickness 0.15)
					)
					(justify left bottom)
					(hide yes)
				)
			)
			(property "Datasheet" "https://www.diodes.com/assets/Datasheets/ds31783.pdf"
				(at 10.16 -8.89 0)
				(effects
					(font
						(size 1.27 1.27)
						(thickness 0.15)
					)
					(justify left bottom)
					(hide yes)
				)
			)
			(property "Description" "Power MOSFET, N Channel, 20 V, 630 mA, 0.3 ohm, SOT-523, Surface Mount"
				(at 47.752 -15.494 0)
				(effects
					(font
						(size 1.27 1.27)
					)
					(hide yes)
				)
			)
			(property "MPN" "DMG1012T-7"
				(at 10.16 1.27 0)
				(effects
					(font
						(size 1.27 1.27)
						(thickness 0.15)
					)
					(justify left bottom)
				)
			)
			(property "Manufacturer" "Diodes Incorporated"
				(at 10.16 -1.27 0)
				(effects
					(font
						(size 1.27 1.27)
						(thickness 0.15)
					)
					(justify left bottom)
					(hide yes)
				)
			)
			(property "Author" "Antmicro"
				(at 10.16 -11.43 0)
				(effects
					(font
						(size 1.27 1.27)
						(thickness 0.15)
					)
					(justify left bottom)
					(hide yes)
				)
			)
			(property "License" "Apache-2.0"
				(at 10.16 -13.97 0)
				(effects
					(font
						(size 1.27 1.27)
						(thickness 0.15)
					)
					(justify left bottom)
					(hide yes)
				)
			)
			(property "ki_keywords" "SMT, MOSFET, SEMICONDUCTOR"
				(at 0 0 0)
				(effects
					(font
						(size 1.27 1.27)
					)
					(hide yes)
				)
			)
			(symbol "DMG1012T-7_1_1"
				(polyline
					(pts
						(xy 1.27 0) (xy 3.302 0) (xy 3.302 3.937)
					)
					(stroke
						(width 0.254)
						(type default)
					)
					(fill
						(type none)
					)
				)
				(polyline
					(pts
						(xy 3.81 4.445) (xy 3.81 3.429)
					)
					(stroke
						(width 0.254)
						(type default)
					)
					(fill
						(type background)
					)
				)
				(polyline
					(pts
						(xy 3.81 2.54) (xy 3.81 3.048)
					)
					(stroke
						(width 0.254)
						(type default)
					)
					(fill
						(type background)
					)
				)
				(polyline
					(pts
						(xy 3.81 2.54) (xy 3.81 2.032)
					)
					(stroke
						(width 0.254)
						(type default)
					)
					(fill
						(type background)
					)
				)
				(polyline
					(pts
						(xy 3.81 2.54) (xy 4.572 3.048) (xy 4.572 2.032) (xy 3.81 2.54)
					)
					(stroke
						(width 0.254)
						(type default)
					)
					(fill
						(type outline)
					)
				)
				(polyline
					(pts
						(xy 3.81 1.143) (xy 3.81 1.651)
					)
					(stroke
						(width 0.254)
						(type default)
					)
					(fill
						(type background)
					)
				)
				(polyline
					(pts
						(xy 3.81 1.143) (xy 3.81 0.635)
					)
					(stroke
						(width 0.254)
						(type default)
					)
					(fill
						(type background)
					)
				)
				(circle
					(center 5.08 2.54)
					(radius 3.302)
					(stroke
						(width 0.254)
						(type default)
					)
					(fill
						(type background)
					)
				)
				(polyline
					(pts
						(xy 6.223 0.635) (xy 7.366 0.635) (xy 7.366 3.937) (xy 7.366 4.445) (xy 6.223 4.445)
					)
					(stroke
						(width 0.254)
						(type default)
					)
					(fill
						(type none)
					)
				)
				(polyline
					(pts
						(xy 6.35 6.35) (xy 6.35 3.937) (xy 3.81 3.937)
					)
					(stroke
						(width 0.254)
						(type default)
					)
					(fill
						(type none)
					)
				)
				(circle
					(center 6.35 4.445)
					(radius 0.127)
					(stroke
						(width 0.254)
						(type default)
					)
					(fill
						(type background)
					)
				)
				(polyline
					(pts
						(xy 6.35 1.143) (xy 3.81 1.143)
					)
					(stroke
						(width 0.254)
						(type default)
					)
					(fill
						(type background)
					)
				)
				(circle
					(center 6.35 1.143)
					(radius 0.127)
					(stroke
						(width 0.254)
						(type default)
					)
					(fill
						(type background)
					)
				)
				(circle
					(center 6.35 0.635)
					(radius 0.127)
					(stroke
						(width 0.254)
						(type default)
					)
					(fill
						(type background)
					)
				)
				(polyline
					(pts
						(xy 6.35 -1.27) (xy 6.35 2.54) (xy 3.81 2.54)
					)
					(stroke
						(width 0.254)
						(type default)
					)
					(fill
						(type none)
					)
				)
				(polyline
					(pts
						(xy 7.366 3.048) (xy 6.858 2.286) (xy 7.874 2.286) (xy 7.366 3.048)
					)
					(stroke
						(width 0.254)
						(type default)
					)
					(fill
						(type outline)
					)
				)
				(polyline
					(pts
						(xy 7.874 3.048) (xy 6.858 3.048)
					)
					(stroke
						(width 0.254)
						(type default)
					)
					(fill
						(type background)
					)
				)
				(pin input line
					(at 0 0 0)
					(length 2.54)
					(name "G"
						(effects
							(font
								(size 1.27 1.27)
							)
						)
					)
					(number "1"
						(effects
							(font
								(size 1.27 1.27)
							)
						)
					)
				)
				(pin passive line
					(at 6.35 7.62 270)
					(length 2.54)
					(name "D"
						(effects
							(font
								(size 1.27 1.27)
							)
						)
					)
					(number "3"
						(effects
							(font
								(size 1.27 1.27)
							)
						)
					)
				)
				(pin passive line
					(at 6.35 -2.54 90)
					(length 2.54)
					(name "S"
						(effects
							(font
								(size 1.27 1.27)
							)
						)
					)
					(number "2"
						(effects
							(font
								(size 1.27 1.27)
							)
						)
					)
				)
			)
		)
	(symbol "antmicropower:+1V05"
			(power)
			(pin_names
				(offset 0)
			)
			(exclude_from_sim no)
			(in_bom yes)
			(on_board yes)
			(property "Reference" "#PWR"
				(at 0 -3.81 0)
				(effects
					(font
						(size 1.27 1.27)
					)
					(hide yes)
				)
			)
			(property "Value" "+1V05"
				(at 0 3.556 0)
				(effects
					(font
						(size 1.27 1.27)
					)
				)
			)
			(property "Footprint" ""
				(at 0 0 0)
				(effects
					(font
						(size 1.27 1.27)
					)
					(hide yes)
				)
			)
			(property "Datasheet" ""
				(at 0 0 0)
				(effects
					(font
						(size 1.27 1.27)
					)
					(hide yes)
				)
			)
			(property "Description" ""
				(at 0 0 0)
				(effects
					(font
						(size 1.27 1.27)
					)
					(hide yes)
				)
			)
			(symbol "+1V05_0_1"
				(polyline
					(pts
						(xy -0.762 1.27) (xy 0 2.54)
					)
					(stroke
						(width 0)
						(type default)
					)
					(fill
						(type none)
					)
				)
				(polyline
					(pts
						(xy 0 2.54) (xy 0.762 1.27)
					)
					(stroke
						(width 0)
						(type default)
					)
					(fill
						(type none)
					)
				)
				(polyline
					(pts
						(xy 0 0) (xy 0 2.54)
					)
					(stroke
						(width 0)
						(type default)
					)
					(fill
						(type none)
					)
				)
			)
			(symbol "+1V05_1_1"
				(pin power_in line
					(at 0 0 90)
					(length 0)
					(hide yes)
					(name "+1V05"
						(effects
							(font
								(size 1.27 1.27)
							)
						)
					)
					(number "1"
						(effects
							(font
								(size 1.27 1.27)
							)
						)
					)
				)
			)
		)
	(symbol "antmicropower:+1V1"
			(power)
			(pin_names
				(offset 0)
			)
			(exclude_from_sim no)
			(in_bom yes)
			(on_board yes)
			(property "Reference" "#PWR"
				(at 0 -3.81 0)
				(effects
					(font
						(size 1.27 1.27)
					)
					(hide yes)
				)
			)
			(property "Value" "+1V1"
				(at 0 3.556 0)
				(effects
					(font
						(size 1.27 1.27)
					)
				)
			)
			(property "Footprint" ""
				(at 0 0 0)
				(effects
					(font
						(size 1.27 1.27)
					)
					(hide yes)
				)
			)
			(property "Datasheet" ""
				(at 0 0 0)
				(effects
					(font
						(size 1.27 1.27)
					)
					(hide yes)
				)
			)
			(property "Description" ""
				(at 0 0 0)
				(effects
					(font
						(size 1.27 1.27)
					)
					(hide yes)
				)
			)
			(symbol "+1V1_0_1"
				(polyline
					(pts
						(xy -0.762 1.27) (xy 0 2.54)
					)
					(stroke
						(width 0)
						(type default)
					)
					(fill
						(type none)
					)
				)
				(polyline
					(pts
						(xy 0 2.54) (xy 0.762 1.27)
					)
					(stroke
						(width 0)
						(type default)
					)
					(fill
						(type none)
					)
				)
				(polyline
					(pts
						(xy 0 0) (xy 0 2.54)
					)
					(stroke
						(width 0)
						(type default)
					)
					(fill
						(type none)
					)
				)
			)
			(symbol "+1V1_1_1"
				(pin power_in line
					(at 0 0 90)
					(length 0)
					(hide yes)
					(name "+1V1"
						(effects
							(font
								(size 1.27 1.27)
							)
						)
					)
					(number "1"
						(effects
							(font
								(size 1.27 1.27)
							)
						)
					)
				)
			)
		)
	(symbol "antmicropower:+1V2"
			(power)
			(pin_names
				(offset 0)
			)
			(exclude_from_sim no)
			(in_bom yes)
			(on_board yes)
			(property "Reference" "#PWR"
				(at 0 -3.81 0)
				(effects
					(font
						(size 1.27 1.27)
					)
					(hide yes)
				)
			)
			(property "Value" "+1V2"
				(at 0 3.556 0)
				(effects
					(font
						(size 1.27 1.27)
					)
				)
			)
			(property "Footprint" ""
				(at 0 0 0)
				(effects
					(font
						(size 1.27 1.27)
					)
					(hide yes)
				)
			)
			(property "Datasheet" ""
				(at 0 0 0)
				(effects
					(font
						(size 1.27 1.27)
					)
					(hide yes)
				)
			)
			(property "Description" ""
				(at 0 0 0)
				(effects
					(font
						(size 1.27 1.27)
					)
					(hide yes)
				)
			)
			(symbol "+1V2_0_1"
				(polyline
					(pts
						(xy -0.762 1.27) (xy 0 2.54)
					)
					(stroke
						(width 0)
						(type default)
					)
					(fill
						(type none)
					)
				)
				(polyline
					(pts
						(xy 0 2.54) (xy 0.762 1.27)
					)
					(stroke
						(width 0)
						(type default)
					)
					(fill
						(type none)
					)
				)
				(polyline
					(pts
						(xy 0 0) (xy 0 2.54)
					)
					(stroke
						(width 0)
						(type default)
					)
					(fill
						(type none)
					)
				)
			)
			(symbol "+1V2_1_1"
				(pin power_in line
					(at 0 0 90)
					(length 0)
					(hide yes)
					(name "+1V2"
						(effects
							(font
								(size 1.27 1.27)
							)
						)
					)
					(number "1"
						(effects
							(font
								(size 1.27 1.27)
							)
						)
					)
				)
			)
		)
	(symbol "antmicropower:+1V8"
			(power)
			(pin_numbers
				(hide yes)
			)
			(pin_names
				(hide yes)
			)
			(exclude_from_sim no)
			(in_bom yes)
			(on_board yes)
			(property "Reference" "#PWR"
				(at 15.24 -2.54 0)
				(effects
					(font
						(size 1.27 1.27)
						(thickness 0.15)
					)
					(justify left bottom)
					(hide yes)
				)
			)
			(property "Value" "+1V8"
				(at -3.175 2.54 0)
				(effects
					(font
						(size 1.27 1.27)
						(thickness 0.15)
					)
					(justify left bottom)
				)
			)
			(property "Footprint" ""
				(at 15.24 -7.62 0)
				(effects
					(font
						(size 1.27 1.27)
						(thickness 0.15)
					)
					(justify left bottom)
					(hide yes)
				)
			)
			(property "Datasheet" ""
				(at 15.24 -10.16 0)
				(effects
					(font
						(size 1.27 1.27)
						(thickness 0.15)
					)
					(justify left bottom)
					(hide yes)
				)
			)
			(property "Description" ""
				(at 0 0 0)
				(effects
					(font
						(size 1.27 1.27)
					)
					(hide yes)
				)
			)
			(property "Author" "Antmicro"
				(at 15.24 -5.08 0)
				(effects
					(font
						(size 1.27 1.27)
						(thickness 0.15)
					)
					(justify left bottom)
					(hide yes)
				)
			)
			(property "License" "Apache-2.0"
				(at 15.24 -7.62 0)
				(effects
					(font
						(size 1.27 1.27)
						(thickness 0.15)
					)
					(justify left bottom)
					(hide yes)
				)
			)
			(symbol "+1V8_1_1"
				(polyline
					(pts
						(xy -0.762 1.27) (xy 0 2.54)
					)
					(stroke
						(width 0)
						(type default)
					)
					(fill
						(type background)
					)
				)
				(polyline
					(pts
						(xy 0 2.54) (xy 0.762 1.27)
					)
					(stroke
						(width 0)
						(type default)
					)
					(fill
						(type background)
					)
				)
				(polyline
					(pts
						(xy 0 0) (xy 0 2.54)
					)
					(stroke
						(width 0)
						(type default)
					)
					(fill
						(type background)
					)
				)
				(pin power_in line
					(at 0 0 90)
					(length 0)
					(hide yes)
					(name "+1V8"
						(effects
							(font
								(size 1.27 1.27)
							)
						)
					)
					(number "1"
						(effects
							(font
								(size 1.27 1.27)
							)
						)
					)
				)
			)
		)
	(symbol "antmicropower:+2V5"
			(power)
			(pin_names
				(offset 0)
			)
			(exclude_from_sim no)
			(in_bom yes)
			(on_board yes)
			(property "Reference" "#PWR"
				(at 0 -3.81 0)
				(effects
					(font
						(size 1.27 1.27)
					)
					(hide yes)
				)
			)
			(property "Value" "+2V5"
				(at 0 3.556 0)
				(effects
					(font
						(size 1.27 1.27)
					)
				)
			)
			(property "Footprint" ""
				(at 0 0 0)
				(effects
					(font
						(size 1.27 1.27)
					)
					(hide yes)
				)
			)
			(property "Datasheet" ""
				(at 0 0 0)
				(effects
					(font
						(size 1.27 1.27)
					)
					(hide yes)
				)
			)
			(property "Description" ""
				(at 0 0 0)
				(effects
					(font
						(size 1.27 1.27)
					)
					(hide yes)
				)
			)
			(symbol "+2V5_0_1"
				(polyline
					(pts
						(xy -0.762 1.27) (xy 0 2.54)
					)
					(stroke
						(width 0)
						(type default)
					)
					(fill
						(type none)
					)
				)
				(polyline
					(pts
						(xy 0 2.54) (xy 0.762 1.27)
					)
					(stroke
						(width 0)
						(type default)
					)
					(fill
						(type none)
					)
				)
				(polyline
					(pts
						(xy 0 0) (xy 0 2.54)
					)
					(stroke
						(width 0)
						(type default)
					)
					(fill
						(type none)
					)
				)
			)
			(symbol "+2V5_1_1"
				(pin power_in line
					(at 0 0 90)
					(length 0)
					(hide yes)
					(name "+2V5"
						(effects
							(font
								(size 1.27 1.27)
							)
						)
					)
					(number "1"
						(effects
							(font
								(size 1.27 1.27)
							)
						)
					)
				)
			)
		)
	(symbol "antmicropower:+3V3"
			(power)
			(pin_numbers
				(hide yes)
			)
			(pin_names
				(hide yes)
			)
			(exclude_from_sim no)
			(in_bom yes)
			(on_board yes)
			(property "Reference" "#PWR"
				(at 15.24 0 0)
				(effects
					(font
						(size 1.27 1.27)
						(thickness 0.15)
					)
					(justify left bottom)
					(hide yes)
				)
			)
			(property "Value" "+3V3"
				(at -3.175 2.54 0)
				(effects
					(font
						(size 1.27 1.27)
						(thickness 0.15)
					)
					(justify left bottom)
				)
			)
			(property "Footprint" ""
				(at 15.24 -7.62 0)
				(effects
					(font
						(size 1.27 1.27)
						(thickness 0.15)
					)
					(justify left bottom)
					(hide yes)
				)
			)
			(property "Datasheet" ""
				(at 15.24 -10.16 0)
				(effects
					(font
						(size 1.27 1.27)
						(thickness 0.15)
					)
					(justify left bottom)
					(hide yes)
				)
			)
			(property "Description" ""
				(at 0 0 0)
				(effects
					(font
						(size 1.27 1.27)
					)
					(hide yes)
				)
			)
			(property "Author" "Antmicro"
				(at 15.24 -2.54 0)
				(effects
					(font
						(size 1.27 1.27)
						(thickness 0.15)
					)
					(justify left bottom)
					(hide yes)
				)
			)
			(property "License" "Apache-2.0"
				(at 15.24 -5.08 0)
				(effects
					(font
						(size 1.27 1.27)
						(thickness 0.15)
					)
					(justify left bottom)
					(hide yes)
				)
			)
			(symbol "+3V3_0_1"
				(polyline
					(pts
						(xy 0 2.54) (xy -0.762 1.27)
					)
					(stroke
						(width 0)
						(type default)
					)
					(fill
						(type none)
					)
				)
				(polyline
					(pts
						(xy 0 2.54) (xy 0.762 1.27)
					)
					(stroke
						(width 0)
						(type default)
					)
					(fill
						(type none)
					)
				)
				(polyline
					(pts
						(xy 0 0) (xy 0 2.54)
					)
					(stroke
						(width 0)
						(type default)
					)
					(fill
						(type none)
					)
				)
			)
			(symbol "+3V3_1_1"
				(pin power_in line
					(at 0 0 90)
					(length 0)
					(hide yes)
					(name "+3V3"
						(effects
							(font
								(size 1.27 1.27)
							)
						)
					)
					(number "1"
						(effects
							(font
								(size 1.27 1.27)
							)
						)
					)
				)
			)
		)
	(symbol "antmicropower:+5V"
			(power)
			(pin_numbers
				(hide yes)
			)
			(pin_names
				(hide yes)
			)
			(exclude_from_sim no)
			(in_bom yes)
			(on_board yes)
			(property "Reference" "#PWR"
				(at 15.24 -2.54 0)
				(effects
					(font
						(size 1.27 1.27)
						(thickness 0.15)
					)
					(justify left bottom)
					(hide yes)
				)
			)
			(property "Value" "+5V"
				(at 15.24 -5.08 0)
				(effects
					(font
						(size 1.27 1.27)
						(thickness 0.15)
					)
					(justify left bottom)
				)
			)
			(property "Footprint" ""
				(at 15.24 -7.62 0)
				(effects
					(font
						(size 1.27 1.27)
						(thickness 0.15)
					)
					(justify left bottom)
					(hide yes)
				)
			)
			(property "Datasheet" ""
				(at 15.24 -10.16 0)
				(effects
					(font
						(size 1.27 1.27)
						(thickness 0.15)
					)
					(justify left bottom)
					(hide yes)
				)
			)
			(property "Description" ""
				(at 0 0 0)
				(effects
					(font
						(size 1.27 1.27)
					)
					(hide yes)
				)
			)
			(property "Author" "Antmicro"
				(at 15.24 -7.62 0)
				(effects
					(font
						(size 1.27 1.27)
						(thickness 0.15)
					)
					(justify left bottom)
					(hide yes)
				)
			)
			(property "License" "Apache-2.0"
				(at 15.24 -10.16 0)
				(effects
					(font
						(size 1.27 1.27)
						(thickness 0.15)
					)
					(justify left bottom)
					(hide yes)
				)
			)
			(symbol "+5V_1_1"
				(polyline
					(pts
						(xy -0.762 1.27) (xy 0 2.54)
					)
					(stroke
						(width 0)
						(type default)
					)
					(fill
						(type background)
					)
				)
				(polyline
					(pts
						(xy 0 2.54) (xy 0.762 1.27)
					)
					(stroke
						(width 0)
						(type default)
					)
					(fill
						(type background)
					)
				)
				(polyline
					(pts
						(xy 0 0) (xy 0 2.54)
					)
					(stroke
						(width 0)
						(type default)
					)
					(fill
						(type background)
					)
				)
				(pin power_in line
					(at 0 0 90)
					(length 0)
					(name "+5V"
						(effects
							(font
								(size 1.27 1.27)
							)
						)
					)
					(number "1"
						(effects
							(font
								(size 1.27 1.27)
							)
						)
					)
				)
			)
		)
	(symbol "antmicropower:GND"
			(power)
			(pin_numbers
				(hide yes)
			)
			(pin_names
				(hide yes)
			)
			(exclude_from_sim no)
			(in_bom yes)
			(on_board yes)
			(property "Reference" "#PWR"
				(at 8.89 -2.54 0)
				(effects
					(font
						(size 1.27 1.27)
						(thickness 0.15)
					)
					(justify left bottom)
					(hide yes)
				)
			)
			(property "Value" "GND"
				(at 8.89 -5.08 0)
				(effects
					(font
						(size 1.27 1.27)
						(thickness 0.15)
					)
					(justify left bottom)
				)
			)
			(property "Footprint" ""
				(at 8.89 -7.62 0)
				(effects
					(font
						(size 1.27 1.27)
						(thickness 0.15)
					)
					(justify left bottom)
					(hide yes)
				)
			)
			(property "Datasheet" ""
				(at 8.89 -12.7 0)
				(effects
					(font
						(size 1.27 1.27)
						(thickness 0.15)
					)
					(justify left bottom)
					(hide yes)
				)
			)
			(property "Description" ""
				(at 0 0 0)
				(effects
					(font
						(size 1.27 1.27)
					)
					(hide yes)
				)
			)
			(property "Author" "Antmicro"
				(at 8.89 -7.62 0)
				(effects
					(font
						(size 1.27 1.27)
						(thickness 0.15)
					)
					(justify left bottom)
					(hide yes)
				)
			)
			(property "License" "Apache-2.0"
				(at 8.89 -10.16 0)
				(effects
					(font
						(size 1.27 1.27)
						(thickness 0.15)
					)
					(justify left bottom)
					(hide yes)
				)
			)
			(symbol "GND_1_1"
				(polyline
					(pts
						(xy 0 0) (xy 0 -1.27) (xy 1.27 -1.27) (xy 0 -2.54) (xy -1.27 -1.27) (xy 0 -1.27)
					)
					(stroke
						(width 0)
						(type default)
					)
					(fill
						(type none)
					)
				)
				(pin power_in line
					(at 0 0 270)
					(length 0)
					(name "GND"
						(effects
							(font
								(size 1.27 1.27)
							)
						)
					)
					(number "1"
						(effects
							(font
								(size 1.27 1.27)
							)
						)
					)
				)
			)
		)
	(symbol "antmicropower:PWR_FLAG"
			(power)
			(pin_numbers
				(hide yes)
			)
			(pin_names
				(offset 0)
				(hide yes)
			)
			(exclude_from_sim no)
			(in_bom yes)
			(on_board yes)
			(property "Reference" "#FLG"
				(at 0 1.905 0)
				(effects
					(font
						(size 1.27 1.27)
					)
					(hide yes)
				)
			)
			(property "Value" "PWR_FLAG"
				(at 0 3.81 0)
				(effects
					(font
						(size 1.27 1.27)
					)
				)
			)
			(property "Footprint" ""
				(at 0 0 0)
				(effects
					(font
						(size 1.27 1.27)
					)
					(hide yes)
				)
			)
			(property "Datasheet" ""
				(at 0 0 0)
				(effects
					(font
						(size 1.27 1.27)
					)
					(hide yes)
				)
			)
			(property "Description" ""
				(at 0 0 0)
				(effects
					(font
						(size 1.27 1.27)
					)
					(hide yes)
				)
			)
			(symbol "PWR_FLAG_0_0"
				(pin power_out line
					(at 0 0 90)
					(length 0)
					(name "pwr"
						(effects
							(font
								(size 1.27 1.27)
							)
						)
					)
					(number "1"
						(effects
							(font
								(size 1.27 1.27)
							)
						)
					)
				)
			)
			(symbol "PWR_FLAG_0_1"
				(polyline
					(pts
						(xy 0 0) (xy 0 1.27) (xy -1.016 1.905) (xy 0 2.54) (xy 1.016 1.905) (xy 0 1.27)
					)
					(stroke
						(width 0)
						(type default)
					)
					(fill
						(type none)
					)
				)
			)
		)
	(symbol "antmicropower:VDDAUX"
			(power)
			(pin_names
				(offset 0)
			)
			(exclude_from_sim no)
			(in_bom yes)
			(on_board yes)
			(property "Reference" "#PWR"
				(at 0 -3.81 0)
				(effects
					(font
						(size 1.27 1.27)
					)
					(hide yes)
				)
			)
			(property "Value" "VDDAUX"
				(at 0 3.81 0)
				(effects
					(font
						(size 1.27 1.27)
					)
				)
			)
			(property "Footprint" ""
				(at 0 0 0)
				(effects
					(font
						(size 1.27 1.27)
					)
					(hide yes)
				)
			)
			(property "Datasheet" ""
				(at 0 0 0)
				(effects
					(font
						(size 1.27 1.27)
					)
					(hide yes)
				)
			)
			(property "Description" ""
				(at 0 0 0)
				(effects
					(font
						(size 1.27 1.27)
					)
					(hide yes)
				)
			)
			(symbol "VDDAUX_0_1"
				(polyline
					(pts
						(xy -0.762 1.27) (xy 0 2.54)
					)
					(stroke
						(width 0)
						(type default)
					)
					(fill
						(type none)
					)
				)
				(polyline
					(pts
						(xy 0 2.54) (xy 0.762 1.27)
					)
					(stroke
						(width 0)
						(type default)
					)
					(fill
						(type none)
					)
				)
				(polyline
					(pts
						(xy 0 0) (xy 0 2.54)
					)
					(stroke
						(width 0)
						(type default)
					)
					(fill
						(type none)
					)
				)
			)
			(symbol "VDDAUX_1_1"
				(pin power_in line
					(at 0 0 90)
					(length 0)
					(hide yes)
					(name "VDDAUX"
						(effects
							(font
								(size 1.27 1.27)
							)
						)
					)
					(number "1"
						(effects
							(font
								(size 1.27 1.27)
							)
						)
					)
				)
			)
		)
	(symbol "antmicropower:VDDI"
			(power)
			(pin_names
				(offset 0)
			)
			(exclude_from_sim no)
			(in_bom yes)
			(on_board yes)
			(property "Reference" "#PWR"
				(at 0 -3.81 0)
				(effects
					(font
						(size 1.27 1.27)
					)
					(hide yes)
				)
			)
			(property "Value" "VDDI"
				(at 0 3.81 0)
				(effects
					(font
						(size 1.27 1.27)
					)
				)
			)
			(property "Footprint" ""
				(at 0 0 0)
				(effects
					(font
						(size 1.27 1.27)
					)
					(hide yes)
				)
			)
			(property "Datasheet" ""
				(at 0 0 0)
				(effects
					(font
						(size 1.27 1.27)
					)
					(hide yes)
				)
			)
			(property "Description" ""
				(at 0 0 0)
				(effects
					(font
						(size 1.27 1.27)
					)
					(hide yes)
				)
			)
			(symbol "VDDI_0_1"
				(polyline
					(pts
						(xy -0.762 1.27) (xy 0 2.54)
					)
					(stroke
						(width 0)
						(type default)
					)
					(fill
						(type none)
					)
				)
				(polyline
					(pts
						(xy 0 2.54) (xy 0.762 1.27)
					)
					(stroke
						(width 0)
						(type default)
					)
					(fill
						(type none)
					)
				)
				(polyline
					(pts
						(xy 0 0) (xy 0 2.54)
					)
					(stroke
						(width 0)
						(type default)
					)
					(fill
						(type none)
					)
				)
			)
			(symbol "VDDI_1_1"
				(pin power_in line
					(at 0 0 90)
					(length 0)
					(hide yes)
					(name "VDD"
						(effects
							(font
								(size 1.27 1.27)
							)
						)
					)
					(number "1"
						(effects
							(font
								(size 1.27 1.27)
							)
						)
					)
				)
			)
		)
)
